G04 ================== begin FILE IDENTIFICATION RECORD ==================*
G04 Layout Name:  15126-1b.brd*
G04 Film Name:    L5*
G04 File Format:  Gerber RS274X*
G04 File Origin:  Cadence Allegro 16.6-2015-S079*
G04 Origin Date:  Fri Feb 10 17:22:26 2017*
G04 *
G04 Layer:  VIA CLASS/L5*
G04 Layer:  PIN/L5*
G04 Layer:  ETCH/L5*
G04 Layer:  DRAWING FORMAT/LAYER_PCB_STORY*
G04 Layer:  DRAWING FORMAT/LAYER_L5*
G04 *
G04 Offset:    (0.00 0.00)*
G04 Mirror:    No*
G04 Mode:      Positive*
G04 Rotation:  0*
G04 FullContactRelief:  No*
G04 UndefLineWidth:     6.00*
G04 ================== end FILE IDENTIFICATION RECORD ====================*
%FSLAX35Y35*MOIN*%
%IR0*IPPOS*OFA0.00000B0.00000*MIA0B0*SFA1.00000B1.00000*%
%ADD12C,.02*%
%ADD10C,.022*%
%ADD13C,.032*%
%ADD11C,.034*%
%ADD17C,.044*%
%ADD14C,.071*%
%ADD25C,.045*%
%ADD21C,.018*%
%ADD26C,.055*%
%ADD23C,.064*%
%ADD22C,.019*%
%ADD20C,.028*%
%ADD15C,.046*%
%ADD24C,.056*%
%ADD19C,.039*%
%ADD18C,.057*%
%ADD16C,.14*%
%ADD27C,.01*%
%ADD28C,.04*%
%ADD29C,.014*%
%ADD30C,.015*%
%ADD31C,.024*%
%ADD32C,.016*%
%ADD33C,.004*%
%ADD34C,.006*%
%ADD35C,.005*%
%ADD36C,.0035*%
%ADD37C,.0045*%
%ADD38C,.00352*%
%ADD39C,.0056*%
%ADD49O,.07202X.12102*%
%ADD50C,.03004*%
%ADD47C,.04004*%
%ADD45C,.03204*%
%ADD52C,.06004*%
%ADD53C,.02604*%
%ADD44C,.02804*%
%ADD46C,.03804*%
%ADD41C,.05604*%
%ADD51C,.12104*%
%ADD42C,.11204*%
%ADD43C,.15004*%
%ADD40C,.11404*%
%ADD48C,.17804*%
G75*
%LPD*%
G75*
G36*
G01X1973300Y-60000D02*
X-19810D01*
Y-34500D01*
X1973300D01*
Y-60000D01*
G37*
G36*
G01X-13000Y169500D02*
X-18800Y175300D01*
Y335976D01*
X-13354Y341422D01*
X2846D01*
X3174Y341750D01*
X4950D01*
X8800Y337900D01*
Y271800D01*
X2000Y265000D01*
Y234800D01*
X7000Y229800D01*
Y195800D01*
X11200Y191600D01*
X45300D01*
X51100Y185800D01*
Y183008D01*
G02X50376Y182774I-400J0D01*
G03X47336Y171530I-6085J-4388D01*
G02X47782Y170882I163J-365D01*
G01X46400Y169500D01*
X-13000D01*
G37*
G36*
G01X-20621Y661811D02*
G02X-19685Y662747I936J0D01*
G01X1972600D01*
Y637600D01*
X-20412D01*
G02X-20621Y638189I726J589D01*
G01Y661811D01*
G37*
G36*
G01X13399Y197001D02*
X12100Y198300D01*
Y232727D01*
X9100Y235727D01*
Y264300D01*
X13850Y269050D01*
Y336947D01*
X16201Y339298D01*
X38759D01*
X39599Y338458D01*
Y274697D01*
G03Y274597I1401J-50D01*
G01Y265400D01*
G03Y265300I1401J-50D01*
G01Y199360D01*
X37240Y197001D01*
X13399D01*
G37*
G36*
G01X33261Y493608D02*
X31043Y495826D01*
X22910D01*
X22891Y496005D01*
G03X22728Y496595I-1891J-205D01*
G02X23030Y497158I363J168D01*
G03X19605Y502601I-539J3460D01*
G02X18875Y502828I-330J226D01*
G01Y518585D01*
X8750Y528710D01*
Y532000D01*
X7345Y533405D01*
X4055D01*
X1933Y535527D01*
G02X2086Y536189I283J283D01*
G03X3026Y539304I-647J1895D01*
G03X3064Y541850I-1526J1296D01*
G03X-64I-1564J1250D01*
G03X-87Y539379I1564J-1250D01*
G03X-455Y538730I1527J-1295D01*
G02X-1117Y538577I-379J130D01*
G01X-6500Y543960D01*
Y560100D01*
X-3200Y563400D01*
X3078D01*
X3098Y563380D01*
X8043D01*
X9778Y565115D01*
Y569301D01*
X7596Y571483D01*
X4692D01*
X4600Y571575D01*
Y578900D01*
X2300Y581200D01*
X-3200D01*
X-6500Y584500D01*
Y595000D01*
X-6000Y595500D01*
X6729D01*
G03X20869I7070J15130D01*
G01X40909D01*
G02X41309Y595114I0J-400D01*
G03X44573Y593854I1901J66D01*
G02X45145Y593855I286J-279D01*
G03X48401Y595116I1355J1335D01*
G02X48800Y595500I400J-16D01*
G01X58800D01*
X64400Y589900D01*
Y565370D01*
G02X63949Y564973I-400J0D01*
G03X60625Y559500I-449J-3473D01*
G03X60336Y556000I2875J-1999D01*
G03X63949Y551027I3164J-1500D01*
G02X64400Y550630I51J-397D01*
G01Y539243D01*
X64189Y539032D01*
X60368D01*
X58935Y537599D01*
Y534044D01*
X61110Y531869D01*
X63965D01*
X64400Y531434D01*
Y528204D01*
G03X62610Y527137I-20J-2002D01*
G02X61881Y527187I-353J187D01*
G03X61770Y525565I-1881J-686D01*
G02X62499Y525515I353J-187D01*
G03X62856Y524904I1880J689D01*
G03X62395Y523868I1524J-1299D01*
G02X61782Y523584I-397J52D01*
G03X62031Y520404I-1082J-1684D01*
G02X62664Y520263I266J-299D01*
G03X63064Y519662I1839J791D01*
G02X63073Y519394I-144J-139D01*
G03X62918Y517014I1527J-1294D01*
G01X62950Y516965D01*
Y516735D01*
X62918Y516686D01*
G03X62950Y514466I1682J-1086D01*
G01Y495194D01*
X62787Y495031D01*
G02X62104Y495318I-283J282D01*
G03X58937Y496763I-1902J24D01*
G02X58661Y496772I-133J149D01*
G03X55814Y494257I-1359J-1331D01*
G02X55501Y493608I-313J-249D01*
G01X50286D01*
G03X45314I-2486J-6008D01*
G01X33261D01*
G37*
G36*
G01X97700Y193000D02*
X95900Y194800D01*
Y202200D01*
X97014Y203314D01*
X97038Y203328D01*
G03X97643Y203933I-789J1394D01*
G01X97657Y203957D01*
X101822Y208122D01*
X101927Y208102D01*
G03X103923Y208400I581J2945D01*
G01X106271D01*
G03X109129I1429J2640D01*
G01X115090D01*
X117765Y211075D01*
Y211496D01*
X117813Y211552D01*
G03X118121Y215034I-2277J1956D01*
G03X118333Y217527I-2613J1478D01*
G02X118627Y218054I377J135D01*
G03X119202Y223745I-619J2937D01*
G03X118452Y225043I-2892J-805D01*
G03X117855Y226499I-1372J288D01*
G01X117765Y226558D01*
Y226635D01*
X115000Y229400D01*
Y237700D01*
X118820Y241520D01*
Y249740D01*
X119250Y250170D01*
X120320D01*
X120800Y250650D01*
Y251887D01*
X120813Y251922D01*
G03Y254060I-2805J1069D01*
G01X120800Y254095D01*
Y255500D01*
X115000Y261300D01*
Y272000D01*
X120100Y277100D01*
Y282838D01*
G03Y287144I-2092J2153D01*
G01Y290400D01*
X115000Y295500D01*
Y300600D01*
X119500Y305100D01*
Y314386D01*
G03X118723Y319907I-1492J2605D01*
G03X118364Y320493I-2722J-1265D01*
G03X116392Y322247I-1301J523D01*
G02X115800Y322598I-192J351D01*
G01Y336700D01*
X119356Y340256D01*
X119408Y340269D01*
G03X120200Y342427I-358J1356D01*
G01Y346940D01*
G03Y351042I-2192J2051D01*
G01Y353000D01*
X114400Y358800D01*
Y367925D01*
G03X112640Y370107I-900J1075D01*
G01X112501Y369999D01*
X100081Y382419D01*
X100068Y382441D01*
G03X98957Y383543I-2596J-1507D01*
G01X93517Y388983D01*
X93511Y389057D01*
G03X92000Y391439I-2993J-229D01*
G01Y421500D01*
X93623Y423123D01*
X113880D01*
X114791Y422212D01*
Y409709D01*
X116200Y408300D01*
X116371D01*
G02X116727Y407718I0J-400D01*
G03X119919Y403392I2671J-1370D01*
G03X121471Y402615I2062J2181D01*
G02X121690Y401942I-68J-394D01*
G03X123526Y402275I1150J-1115D01*
G02X123496Y402981I172J361D01*
G03X124646Y404190I-1515J2592D01*
G01X129189D01*
Y402888D01*
X129200Y402877D01*
Y399500D01*
X135198Y393501D01*
Y368673D01*
X135200Y368672D01*
Y365326D01*
X135198Y365325D01*
Y276860D01*
X135191Y276833D01*
G03Y275939I1538J-447D01*
G01X135198Y275912D01*
Y207399D01*
X135200Y207398D01*
Y206200D01*
X127767Y198767D01*
G02X127114Y198897I-283J283D01*
G03X121354Y197441I-2774J-1147D01*
G02X120956Y197000I-398J-41D01*
G01X116300D01*
X112350Y193050D01*
X110050D01*
X110000Y193000D01*
X97700D01*
G37*
G36*
G01X53000Y223300D02*
X51802Y224498D01*
Y245001D01*
X51800Y245002D01*
Y246798D01*
X51802Y246799D01*
Y258899D01*
X59986Y267084D01*
X72912D01*
X74529Y265467D01*
Y265408D01*
X74988Y264949D01*
Y224634D01*
X73654Y223300D01*
X53000D01*
G37*
G36*
G01X136200Y364910D02*
X137518Y366228D01*
X169186D01*
X170236Y365178D01*
Y210794D01*
X166142Y206700D01*
X162442D01*
X161742Y206000D01*
X156842D01*
X154090Y203248D01*
X139366D01*
X138996Y203618D01*
Y205018D01*
X136200Y207814D01*
Y364910D01*
G37*
G36*
G01X169383Y391017D02*
Y381165D01*
X170236Y380312D01*
Y369152D01*
X169314Y368230D01*
X137058D01*
X136200Y369088D01*
Y394200D01*
X131000Y399400D01*
Y401158D01*
X131021Y401179D01*
Y403021D01*
X132000Y404000D01*
X143570D01*
X149310Y398260D01*
X162140D01*
X169383Y391017D01*
G37*
G36*
G01X172700Y210600D02*
X171700Y211600D01*
Y362700D01*
X173200Y364200D01*
X192100D01*
X194135Y362165D01*
G02X193996Y361508I-282J-283D01*
G03X193478Y361160I503J-1309D01*
G02X192901Y361154I-291J274D01*
G03X192922Y359213I-1001J-981D01*
G02X193499Y359219I291J-274D01*
G03X195580Y359306I1001J981D01*
G02X196165Y359339I308J-255D01*
G03X197248Y358952I972J1011D01*
G01X197340Y358960D01*
X248680Y307620D01*
X256780D01*
X259300Y305100D01*
X271920D01*
X272008Y305188D01*
X272057Y305203D01*
G03X272125Y305225I-297J1035D01*
G03X274042Y306911I-1233J3335D01*
G02X274200Y307108I577J-301D01*
G01X274689D01*
X274721D01*
G03X276609Y307749I-102J3401D01*
G02X276885Y307709I117J-162D01*
G03X279294Y309098I1114J851D01*
G02X279396Y309357I185J77D01*
G03X280946Y310759I-1397J3103D01*
G02X281346Y311008I433J-250D01*
G01X281412D01*
G02X281812Y310759I-33J-499D01*
G03X283362Y309357I2947J1701D01*
G02X283464Y309098I-83J-182D01*
G03X286054I1295J-538D01*
G02X286156Y309357I185J77D01*
G03X287706Y310759I-1397J3103D01*
G02X288106Y311008I433J-250D01*
G01X288209D01*
X288241D01*
G03X291087Y312709I-101J3401D01*
G02X291494Y312958I432J-249D01*
G01X291604D01*
G03X291643Y312959I-8J1077D01*
G03X294466Y314659I-125J3401D01*
G02X295332I433J-250D01*
G03X301226I2947J1701D01*
G02X301626Y314908I433J-250D01*
G01X301729D01*
X301761D01*
G03X303649Y315549I-102J3401D01*
G02X303925Y315509I117J-162D01*
G03X306334Y316898I1114J851D01*
G02X306436Y317157I185J77D01*
G03X306910Y317417I-1395J3104D01*
G01X306960Y317450D01*
X307306D01*
X307366Y317382D01*
G03X309470I1052J927D01*
G01X309530Y317450D01*
X309878D01*
X309928Y317417D01*
G03X310401Y317157I1871J2843D01*
G02X310503Y316898I-83J-182D01*
G03X313093I1295J-538D01*
G02X313195Y317157I185J77D01*
G03X313668Y317417I-1398J3103D01*
G01X313718Y317450D01*
X314066D01*
X314126Y317382D01*
G03X316230I1052J927D01*
G01X316290Y317450D01*
X316638D01*
X316688Y317417D01*
G03X317161Y317157I1871J2843D01*
G02X317263Y316898I-83J-182D01*
G03X319853I1295J-538D01*
G02X319955Y317157I185J77D01*
G03X320428Y317417I-1398J3103D01*
G01X320478Y317450D01*
X320826D01*
X320886Y317382D01*
G03X323046Y317450I1052J927D01*
G01X323653D01*
G02X324023Y316897I0J-400D01*
G03X326613I1295J-537D01*
G02X326983Y317450I370J153D01*
G01X327590D01*
G03X329806I1108J859D01*
G01X330413D01*
G02X330783Y316897I0J-400D01*
G03X332878Y317512I1295J-537D01*
G02X332823Y318123I228J328D01*
G01X333375Y318675D01*
G02X334057Y318374I283J-283D01*
G03X335393Y319710I1401J-65D01*
G02X335092Y320392I-18J399D01*
G01X335506Y320806D01*
X335579Y320812D01*
G03X336855Y322088I-121J1397D01*
G01X336861Y322161D01*
X337858Y323158D01*
G03X339954Y325009I980J1003D01*
G01X339848Y325148D01*
X340311Y325611D01*
G02X340955Y325502I283J-282D01*
G03X342826Y327373I1263J608D01*
G02X342717Y328017I173J361D01*
G01X345289Y330589D01*
X345389Y330574D01*
G03X346984Y332169I209J1386D01*
G01X346969Y332269D01*
X347523Y332823D01*
G02X348066Y332844I283J-283D01*
G03X350043Y334821I912J1065D01*
G02X350064Y335364I304J260D01*
G01X350343Y335643D01*
G02X351010Y335471I283J-283D01*
G03X352746Y337207I1347J389D01*
G02X352574Y337874I111J384D01*
G01X355136Y340436D01*
X355256Y340392D01*
G03X357054Y342190I481J1317D01*
G01X357010Y342310D01*
X357468Y342768D01*
G02X358054Y342746I283J-283D01*
G03X360031Y344723I1063J914D01*
G02X360009Y345309I261J303D01*
G01X360400Y345700D01*
X361086D01*
X361098Y345514D01*
G03X363896I1399J95D01*
G01X363908Y345700D01*
X367846D01*
X367858Y345514D01*
G03X370656I1399J95D01*
G01X370668Y345700D01*
X374606D01*
X374618Y345514D01*
G03X377416I1399J95D01*
G01X377428Y345700D01*
X378800D01*
X388800Y335700D01*
X431279D01*
X432881Y337302D01*
Y343337D01*
X431784Y344434D01*
X422487D01*
X420910Y346011D01*
Y351420D01*
X420510Y351820D01*
Y354282D01*
X421134D01*
X421352Y354500D01*
X422311D01*
X422345Y354343D01*
G03X425083I1369J304D01*
G01X425117Y354500D01*
X429071D01*
X429105Y354343D01*
G03X431564Y353766I1369J304D01*
G02X432121Y353830I311J-252D01*
G01X432209D01*
G02X432574Y353267I0J-400D01*
G03X434944Y353578I1280J-571D01*
G02X434958Y353845I155J126D01*
G01X435306Y354193D01*
G02X435953Y354074I282J-283D01*
G03X438441Y353935I1280J573D01*
G02X439068Y354015I345J-203D01*
G01X439148Y353934D01*
X439393D01*
G02X439546Y353605I0J-200D01*
G03X441817Y351978I1067J-910D01*
G02X442444Y352056I344J-205D01*
G01X450300Y344200D01*
Y336900D01*
X450175Y336850D01*
G03X449670Y336501I525J-1300D01*
G02X449027Y336579I-293J272D01*
G03X448830Y334949I-1227J-679D01*
G02X449473Y334871I293J-272D01*
G03X450175Y334250I1227J679D01*
G01X450300Y334200D01*
Y325753D01*
G03X449995Y325450I966J-1278D01*
G02X449481Y325344I-318J243D01*
G03X447633Y325149I-787J-1395D01*
G02X447113Y325140I-265J299D01*
G03X447155Y322704I-1019J-1236D01*
G02X447675Y322713I265J-299D01*
G03X449659Y322670I1019J1236D01*
G02X450300Y322351I241J-319D01*
G01Y320124D01*
X444022Y313846D01*
Y312922D01*
X443700Y312600D01*
Y311637D01*
G02X443266Y311238I-400J0D01*
G03X441960Y310585I-118J-1397D01*
G02X441282I-339J213D01*
G03Y309097I-1188J-744D01*
G02X441960I339J-213D01*
G03X443266Y308444I1188J744D01*
G02X443700Y308045I34J-399D01*
G01Y297895D01*
G02X443259Y297497I-400J0D01*
G03X441894Y296965I-165J-1593D01*
G02X441294I-300J265D01*
G03X439160Y294602I-1200J-1061D01*
G02X439186Y293972I-233J-325D01*
G03X441261Y292127I908J-1068D01*
G02X441927I333J-222D01*
G03X443254Y291511I1167J777D01*
G02X443700Y291114I46J-397D01*
G01Y280895D01*
G02X443259Y280497I-400J0D01*
G03X441894Y279965I-165J-1593D01*
G02X441294I-300J265D01*
G03Y277843I-1200J-1061D01*
G02X441894I300J-265D01*
G03X443259Y277311I1200J1061D01*
G02X443700Y276913I41J-398D01*
G01Y268515D01*
G03X443017Y267127I708J-1210D01*
G01X443030Y267030D01*
X442553Y266553D01*
G02X441877Y266761I-283J283D01*
G03X439407Y265622I-1377J-261D01*
G02X439243Y265001I-312J-250D01*
G03X438632Y262872I521J-1302D01*
G01X438733Y262733D01*
X426606Y250606D01*
X426484Y250653D01*
G03X424668Y248837I-510J-1306D01*
G01X424715Y248715D01*
X424264Y248264D01*
G02X423673Y248291I-283J282D01*
G03X421699Y246317I-1079J-895D01*
G02X421726Y245726I-255J-308D01*
G01X421294Y245294D01*
G02X420612Y245548I-283J283D01*
G03X419113Y244049I-1398J-101D01*
G02X419367Y243367I-29J-399D01*
G01X418919Y242919D01*
X418866Y242905D01*
G03X417977Y242206I348J-1358D01*
G01X417920Y242100D01*
X417136D01*
G02X416802Y242721I0J400D01*
G03X414466I-1168J775D01*
G02X414132Y242100I-334J-221D01*
G01X413800D01*
X412700Y243200D01*
Y250400D01*
X419129Y256828D01*
X422915D01*
X422974Y256888D01*
X426149D01*
X428575Y259314D01*
Y263000D01*
X428760Y263185D01*
Y263417D01*
G02X429063Y263589I200J0D01*
G03X430696Y263731I718J1204D01*
G02X431294Y263644I261J-303D01*
G03X431491Y265621I1349J864D01*
G02X430888Y265654I-287J278D01*
G03X429063Y265997I-1107J-861D01*
G02X428760Y266169I-103J172D01*
G01Y266173D01*
X428575Y266358D01*
Y266517D01*
X426492Y268600D01*
X362914D01*
X362861Y268718D01*
G03X360123I-1369J-618D01*
G01X360070Y268600D01*
X360000D01*
X359302Y267902D01*
X359285D01*
X356431Y265048D01*
X356308Y265098D01*
G03X354348Y263138I-571J-1389D01*
G01X354398Y263015D01*
X354020Y262636D01*
G02X353431Y262662I-283J283D01*
G03X351611Y260573I-1073J-902D01*
G01X351630Y260561D01*
X351787Y260404D01*
X351584Y260200D01*
X350331D01*
X350281Y260326D01*
G03X347675I-1303J-517D01*
G01X347625Y260200D01*
X346977D01*
G02X346671Y260857I0J400D01*
G03X344241Y262112I-1073J903D01*
G02X343571Y261929I-387J100D01*
G01X343277Y262223D01*
G02X343262Y262773I283J283D01*
G03X341282Y264753I-1044J936D01*
G02X340732Y264768I-267J298D01*
G01X340198Y265302D01*
X340217Y265406D01*
G03X338584Y267039I-1379J254D01*
G01X338480Y267020D01*
X335916Y269584D01*
G02X336035Y270231I283J282D01*
G03X334180Y272086I-577J1278D01*
G02X333533Y271967I-365J164D01*
G01X333185Y272315D01*
G02X333171Y272582I142J141D01*
G03X331200Y274553I-1093J878D01*
G02X330933Y274567I-126J156D01*
G01X330102Y275398D01*
X330098Y275475D01*
G03X328764Y276809I-1400J-66D01*
G01X328687Y276813D01*
X328269Y277231D01*
G02X328584Y277913I283J283D01*
G03X327538Y278523I114J1397D01*
G01X327631Y278386D01*
X327373Y278127D01*
X327000Y278500D01*
X326134D01*
G03X324502I-816J-1140D01*
G01X323693D01*
G02X323303Y278991I0J400D01*
G03X320573I-1365J319D01*
G02X320183Y278500I-390J-91D01*
G01X319374D01*
G03X317742I-816J-1140D01*
G01X316933D01*
G02X316543Y278991I0J400D01*
G03X313813I-1365J319D01*
G02X313423Y278500I-390J-91D01*
G01X312614D01*
G03X310982I-816J-1140D01*
G01X305855D01*
G03X304223I-816J-1140D01*
G01X299095D01*
G03X297463I-816J-1140D01*
G01X292335D01*
G03X290703I-816J-1140D01*
G01X285575D01*
G03X283943I-816J-1140D01*
G01X278815D01*
G03X277183I-816J-1140D01*
G01X276413D01*
X275818Y278843D01*
X275673Y278751D01*
X275586Y278776D01*
G03X273652I-967J-3367D01*
G01X273565Y278751D01*
X273420Y278843D01*
X272245Y278165D01*
X272252Y277993D01*
X272187Y277930D01*
G03X271585Y277160I2432J-2521D01*
G02X271269Y276962I-346J200D01*
G01X270303D01*
G03X270011Y276925I1J-1177D01*
G01X269931Y276904D01*
X269795Y276983D01*
X268646Y276265D01*
X268650Y276215D01*
G02X268451Y276000I-199J-15D01*
G01X266251D01*
X265570Y276682D01*
X254911D01*
X254230Y276000D01*
X242700D01*
X177300Y210600D01*
X172700D01*
G37*
G36*
G01X276096Y216745D02*
X276058Y217499D01*
X276807Y217941D01*
X277449Y217540D01*
X277537Y217390D01*
X276185Y216593D01*
X276096Y216745D01*
G37*
G36*
G01X273334Y197719D02*
X273044Y198504D01*
X273681Y199140D01*
X274466Y198850D01*
X274589Y198726D01*
X273458Y197595D01*
X273334Y197719D01*
G37*
G36*
G01X270576Y194961D02*
X270286Y195746D01*
X270923Y196382D01*
X271708Y196092D01*
X271831Y195968D01*
X270700Y194837D01*
X270576Y194961D01*
G37*
G36*
G01X263124Y189104D02*
X262834Y189889D01*
X263470Y190525D01*
X264255Y190235D01*
X264379Y190112D01*
X263247Y188980D01*
X263124Y189104D01*
G37*
G36*
G01X276038Y201116D02*
X276006Y201871D01*
X276759Y202306D01*
X277397Y201901D01*
X277485Y201749D01*
X276125Y200964D01*
X276038Y201116D01*
G37*
G36*
G01X279408Y202218D02*
X279376Y202973D01*
X280129Y203408D01*
X280767Y203003D01*
X280855Y202852D01*
X279495Y202067D01*
X279408Y202218D01*
G37*
G36*
G01X265882Y191862D02*
X265592Y192647D01*
X266228Y193283D01*
X267013Y192993D01*
X267137Y192870D01*
X266005Y191738D01*
X265882Y191862D01*
G37*
G36*
G01X265032Y189458D02*
X265322Y188673D01*
X264686Y188037D01*
X263901Y188327D01*
X263777Y188450D01*
X264909Y189582D01*
X265032Y189458D01*
G37*
G36*
G01X272484Y195315D02*
X272774Y194530D01*
X272138Y193894D01*
X271353Y194184D01*
X271229Y194308D01*
X272360Y195439D01*
X272484Y195315D01*
G37*
G36*
G01X275242Y198073D02*
X275532Y197288D01*
X274896Y196652D01*
X274111Y196942D01*
X273987Y197066D01*
X275118Y198197D01*
X275242Y198073D01*
G37*
G36*
G01X282960Y200201D02*
X282992Y199446D01*
X282239Y199011D01*
X281601Y199416D01*
X281513Y199567D01*
X282873Y200353D01*
X282960Y200201D01*
G37*
G36*
G01X285018Y205370D02*
X285701Y205693D01*
X286394Y205169D01*
X286269Y204424D01*
X286165Y204284D01*
X284911Y205231D01*
X285018Y205370D01*
G37*
G36*
G01X267790Y192216D02*
X268080Y191431D01*
X267444Y190795D01*
X266659Y191085D01*
X266535Y191208D01*
X267667Y192340D01*
X267790Y192216D01*
G37*
G36*
G01X287386Y186867D02*
X287096Y187652D01*
X287733Y188288D01*
X288518Y187998D01*
X288641Y187874D01*
X287510Y186743D01*
X287386Y186867D01*
G37*
G36*
G01X290144Y189625D02*
X289854Y190409D01*
X290491Y191046D01*
X291275Y190756D01*
X291399Y190632D01*
X290268Y189501D01*
X290144Y189625D01*
G37*
G36*
G01X292902Y192382D02*
X292612Y193167D01*
X293248Y193804D01*
X294033Y193514D01*
X294157Y193390D01*
X293026Y192259D01*
X292902Y192382D01*
G37*
G36*
G01X289295Y187221D02*
X289585Y186436D01*
X288949Y185799D01*
X288164Y186089D01*
X288040Y186213D01*
X289171Y187344D01*
X289295Y187221D01*
G37*
G36*
G01X292053Y189978D02*
X292343Y189194D01*
X291706Y188557D01*
X290922Y188847D01*
X290798Y188971D01*
X291929Y190102D01*
X292053Y189978D01*
G37*
G36*
G01X258463Y192683D02*
X258173Y193468D01*
X258809Y194104D01*
X259594Y193814D01*
X259718Y193691D01*
X258586Y192559D01*
X258463Y192683D01*
G37*
G36*
G01X264978Y197285D02*
X265328Y198045D01*
X266228D01*
X266578Y197285D01*
Y197110D01*
X264978D01*
Y197285D01*
G37*
G36*
G01X261221Y195441D02*
X260931Y196226D01*
X261567Y196862D01*
X262352Y196572D01*
X262476Y196449D01*
X261344Y195317D01*
X261221Y195441D01*
G37*
G36*
G01X269061Y198620D02*
X268771Y199405D01*
X269407Y200041D01*
X270192Y199751D01*
X270316Y199628D01*
X269184Y198496D01*
X269061Y198620D01*
G37*
G36*
G01X272667Y203070D02*
X272635Y203825D01*
X273388Y204260D01*
X274026Y203855D01*
X274114Y203703D01*
X272754Y202918D01*
X272667Y203070D01*
G37*
G36*
G01X276032Y205012D02*
X276000Y205767D01*
X276753Y206202D01*
X277391Y205797D01*
X277479Y205645D01*
X276119Y204861D01*
X276032Y205012D01*
G37*
G36*
G01X270968Y198975D02*
X271258Y198190D01*
X270622Y197554D01*
X269837Y197844D01*
X269713Y197967D01*
X270845Y199099D01*
X270968Y198975D01*
G37*
G36*
G01X266578Y196186D02*
X266228Y195426D01*
X265328D01*
X264978Y196186D01*
Y196361D01*
X266578D01*
Y196186D01*
G37*
G36*
G01X263129Y195795D02*
X263419Y195010D01*
X262783Y194374D01*
X261998Y194664D01*
X261874Y194787D01*
X263006Y195919D01*
X263129Y195795D01*
G37*
G36*
G01X276571Y203449D02*
X276603Y202694D01*
X275850Y202259D01*
X275212Y202664D01*
X275124Y202815D01*
X276484Y203601D01*
X276571Y203449D01*
G37*
G36*
G01X282263Y206353D02*
X281593Y206703D01*
Y207573D01*
X282263Y207923D01*
X282438D01*
Y206353D01*
X282263D01*
G37*
G36*
G01X260371Y193037D02*
X260661Y192252D01*
X260025Y191616D01*
X259240Y191906D01*
X259116Y192029D01*
X260248Y193161D01*
X260371Y193037D01*
G37*
G36*
G01X281757Y188437D02*
X281467Y189222D01*
X282103Y189858D01*
X282888Y189568D01*
X283012Y189445D01*
X281880Y188313D01*
X281757Y188437D01*
G37*
G36*
G01X283975Y189816D02*
X284325Y190576D01*
X285225D01*
X285575Y189816D01*
Y189641D01*
X283975D01*
Y189816D01*
G37*
G36*
G01X290119Y193889D02*
X289829Y194673D01*
X290466Y195310D01*
X291250Y195020D01*
X291374Y194896D01*
X290243Y193765D01*
X290119Y193889D01*
G37*
G36*
G01X292397Y200549D02*
X291727Y200899D01*
Y201769D01*
X292397Y202119D01*
X292572D01*
Y200549D01*
X292397D01*
G37*
G36*
G01X287361Y191131D02*
X287071Y191915D01*
X287708Y192552D01*
X288492Y192262D01*
X288616Y192138D01*
X287485Y191007D01*
X287361Y191131D01*
G37*
G36*
G01X285575Y188716D02*
X285225Y187956D01*
X284325D01*
X283975Y188716D01*
Y188891D01*
X285575D01*
Y188716D01*
G37*
G36*
G01X289270Y191484D02*
X289560Y190699D01*
X288924Y190063D01*
X288139Y190353D01*
X288015Y190476D01*
X289147Y191608D01*
X289270Y191484D01*
G37*
G36*
G01X292028Y194242D02*
X292318Y193457D01*
X291682Y192821D01*
X290897Y193111D01*
X290773Y193234D01*
X291905Y194366D01*
X292028Y194242D01*
G37*
G36*
G01X275887Y194212D02*
X276177Y193427D01*
X275541Y192791D01*
X274756Y193081D01*
X274632Y193204D01*
X275764Y194336D01*
X275887Y194212D01*
G37*
G36*
G01X279500Y195276D02*
X279150Y194516D01*
X278250D01*
X277900Y195276D01*
Y195451D01*
X279500D01*
Y195276D01*
G37*
G36*
G01X273129Y191454D02*
X273419Y190669D01*
X272783Y190033D01*
X271998Y190323D01*
X271874Y190446D01*
X273006Y191578D01*
X273129Y191454D01*
G37*
G36*
G01X286035Y196917D02*
X286325Y196133D01*
X285688Y195496D01*
X284904Y195786D01*
X284780Y195910D01*
X285911Y197041D01*
X286035Y196917D01*
G37*
G36*
G01X283400Y195276D02*
X283050Y194516D01*
X282150D01*
X281800Y195276D01*
Y195451D01*
X283400D01*
Y195276D01*
G37*
G36*
G01X277606Y189269D02*
X277896Y188484D01*
X277260Y187848D01*
X276475Y188138D01*
X276351Y188261D01*
X277483Y189393D01*
X277606Y189269D01*
G37*
G36*
G01X288186Y194668D02*
X288476Y193883D01*
X287840Y193247D01*
X287055Y193537D01*
X286931Y193660D01*
X288063Y194792D01*
X288186Y194668D01*
G37*
G36*
G01X283429Y192085D02*
X283079Y191325D01*
X282179D01*
X281829Y192085D01*
Y192260D01*
X283429D01*
Y192085D01*
G37*
G36*
G01X290641Y202119D02*
X291311Y201769D01*
Y200899D01*
X290641Y200549D01*
X290466D01*
Y202119D01*
X290641D01*
G37*
G36*
G01Y205970D02*
X291311Y205620D01*
Y204750D01*
X290641Y204400D01*
X290466D01*
Y205970D01*
X290641D01*
G37*
G36*
G01Y209869D02*
X291311Y209519D01*
Y208649D01*
X290641Y208299D01*
X290466D01*
Y209869D01*
X290641D01*
G37*
G36*
G01X273978Y193859D02*
X273688Y194643D01*
X274325Y195280D01*
X275109Y194990D01*
X275233Y194866D01*
X274102Y193735D01*
X273978Y193859D01*
G37*
G36*
G01X277900Y196376D02*
X278250Y197136D01*
X279150D01*
X279500Y196376D01*
Y196201D01*
X277900D01*
Y196376D01*
G37*
G36*
G01X281800D02*
X282150Y197136D01*
X283050D01*
X283400Y196376D01*
Y196201D01*
X281800D01*
Y196376D01*
G37*
G36*
G01X271220Y191101D02*
X270930Y191885D01*
X271567Y192522D01*
X272351Y192232D01*
X272475Y192108D01*
X271344Y190977D01*
X271220Y191101D01*
G37*
G36*
G01X275697Y188916D02*
X275407Y189700D01*
X276044Y190337D01*
X276828Y190047D01*
X276952Y189923D01*
X275821Y188792D01*
X275697Y188916D01*
G37*
G36*
G01X281829Y193185D02*
X282179Y193945D01*
X283079D01*
X283429Y193185D01*
Y193010D01*
X281829D01*
Y193185D01*
G37*
G36*
G01X286277Y194315D02*
X285987Y195099D01*
X286624Y195736D01*
X287408Y195446D01*
X287532Y195322D01*
X286401Y194191D01*
X286277Y194315D01*
G37*
G36*
G01X289017Y202475D02*
X288347Y202825D01*
Y203695D01*
X289017Y204045D01*
X289192D01*
Y202475D01*
X289017D01*
G37*
G36*
G01Y206399D02*
X288347Y206749D01*
Y207619D01*
X289017Y207969D01*
X289192D01*
Y206399D01*
X289017D01*
G37*
G36*
G01X278601Y272100D02*
X279239Y272505D01*
X279992Y272070D01*
X279960Y271315D01*
X279873Y271163D01*
X278513Y271949D01*
X278601Y272100D01*
G37*
G36*
G01X265749Y269181D02*
X265587Y269920D01*
X266253Y270479D01*
X266952Y270191D01*
X267064Y270057D01*
X265862Y269047D01*
X265749Y269181D01*
G37*
G36*
G01X269278Y271315D02*
X269246Y272070D01*
X269999Y272505D01*
X270637Y272100D01*
X270725Y271949D01*
X269365Y271163D01*
X269278Y271315D01*
G37*
G36*
G01X272652Y273261D02*
X272620Y274016D01*
X273373Y274451D01*
X274011Y274046D01*
X274099Y273895D01*
X272739Y273109D01*
X272652Y273261D01*
G37*
G36*
G01X275227Y274046D02*
X275865Y274451D01*
X276618Y274016D01*
X276586Y273261D01*
X276499Y273109D01*
X275139Y273895D01*
X275227Y274046D01*
G37*
G36*
G01X278877Y231724D02*
X278207Y232074D01*
Y232944D01*
X278877Y233294D01*
X279052D01*
Y231724D01*
X278877D01*
G37*
G36*
G01Y227800D02*
X278207Y228150D01*
Y229020D01*
X278877Y229370D01*
X279052D01*
Y227800D01*
X278877D01*
G37*
G36*
G01Y223949D02*
X278207Y224299D01*
Y225169D01*
X278877Y225519D01*
X279052D01*
Y223949D01*
X278877D01*
G37*
G36*
G01Y220049D02*
X278207Y220399D01*
Y221269D01*
X278877Y221619D01*
X279052D01*
Y220049D01*
X278877D01*
G37*
G36*
G01Y235624D02*
X278207Y235974D01*
Y236844D01*
X278877Y237194D01*
X279052D01*
Y235624D01*
X278877D01*
G37*
G36*
G01X280501Y235220D02*
X281171Y234870D01*
Y234000D01*
X280501Y233650D01*
X280326D01*
Y235220D01*
X280501D01*
G37*
G36*
G01Y219620D02*
X281171Y219270D01*
Y218400D01*
X280501Y218050D01*
X280326D01*
Y219620D01*
X280501D01*
G37*
G36*
G01Y223520D02*
X281171Y223170D01*
Y222300D01*
X280501Y221950D01*
X280326D01*
Y223520D01*
X280501D01*
G37*
G36*
G01Y227445D02*
X281171Y227095D01*
Y226225D01*
X280501Y225875D01*
X280326D01*
Y227445D01*
X280501D01*
G37*
G36*
G01Y231369D02*
X281171Y231019D01*
Y230149D01*
X280501Y229799D01*
X280326D01*
Y231369D01*
X280501D01*
G37*
G36*
G01X272652Y253761D02*
X272620Y254516D01*
X273373Y254951D01*
X274011Y254546D01*
X274099Y254395D01*
X272739Y253609D01*
X272652Y253761D01*
G37*
G36*
G01X269278Y251815D02*
X269246Y252570D01*
X269999Y253005D01*
X270637Y252600D01*
X270725Y252449D01*
X269365Y251663D01*
X269278Y251815D01*
G37*
G36*
G01D02*
X269246Y252570D01*
X269999Y253005D01*
X270637Y252600D01*
X270725Y252449D01*
X269365Y251663D01*
X269278Y251815D01*
G37*
G36*
G01X265913Y249875D02*
X265881Y250630D01*
X266635Y251064D01*
X267272Y250659D01*
X267361Y250508D01*
X266000Y249723D01*
X265913Y249875D01*
G37*
G36*
G01X281564Y254061D02*
X282229Y254420D01*
X282950Y253934D01*
X282866Y253183D01*
X282768Y253038D01*
X281466Y253916D01*
X281564Y254061D01*
G37*
G36*
G01X261593Y241497D02*
X260833Y241847D01*
Y242747D01*
X261593Y243097D01*
X261768D01*
Y241497D01*
X261593D01*
G37*
G36*
G01Y245397D02*
X260833Y245747D01*
Y246647D01*
X261593Y246997D01*
X261768D01*
Y245397D01*
X261593D01*
G37*
G36*
G01X278601Y252600D02*
X279239Y253005D01*
X279992Y252570D01*
X279960Y251815D01*
X279873Y251663D01*
X278513Y252449D01*
X278601Y252600D01*
G37*
G36*
G01X273206Y252208D02*
X273238Y251453D01*
X272485Y251018D01*
X271847Y251423D01*
X271759Y251575D01*
X273119Y252360D01*
X273206Y252208D01*
G37*
G36*
G01X269820Y250254D02*
X269852Y249499D01*
X269099Y249064D01*
X268461Y249469D01*
X268373Y249621D01*
X269733Y250406D01*
X269820Y250254D01*
G37*
G36*
G01X281987Y250646D02*
X282625Y251051D01*
X283378Y250616D01*
X283346Y249861D01*
X283259Y249709D01*
X281899Y250495D01*
X281987Y250646D01*
G37*
G36*
G01X266446Y248308D02*
X266478Y247553D01*
X265725Y247118D01*
X265087Y247523D01*
X264999Y247675D01*
X266359Y248460D01*
X266446Y248308D01*
G37*
G36*
G01X262693Y244997D02*
X263453Y244647D01*
Y243747D01*
X262693Y243397D01*
X262518D01*
Y244997D01*
X262693D01*
G37*
G36*
G01X275497Y233674D02*
X274827Y234024D01*
Y234894D01*
X275497Y235244D01*
X275672D01*
Y233674D01*
X275497D01*
G37*
G36*
G01Y225874D02*
X274827Y226224D01*
Y227094D01*
X275497Y227444D01*
X275672D01*
Y225874D01*
X275497D01*
G37*
G36*
G01Y221974D02*
X274827Y222324D01*
Y223194D01*
X275497Y223544D01*
X275672D01*
Y221974D01*
X275497D01*
G37*
G36*
G01Y229774D02*
X274827Y230124D01*
Y230994D01*
X275497Y231344D01*
X275672D01*
Y229774D01*
X275497D01*
G37*
G36*
G01Y237574D02*
X274827Y237924D01*
Y238794D01*
X275497Y239144D01*
X275672D01*
Y237574D01*
X275497D01*
G37*
G36*
G01X277121Y233294D02*
X277791Y232944D01*
Y232074D01*
X277121Y231724D01*
X276946D01*
Y233294D01*
X277121D01*
G37*
G36*
G01Y229394D02*
X277791Y229044D01*
Y228174D01*
X277121Y227824D01*
X276946D01*
Y229394D01*
X277121D01*
G37*
G36*
G01Y225494D02*
X277791Y225144D01*
Y224274D01*
X277121Y223924D01*
X276946D01*
Y225494D01*
X277121D01*
G37*
G36*
G01Y221619D02*
X277791Y221269D01*
Y220399D01*
X277121Y220049D01*
X276946D01*
Y221619D01*
X277121D01*
G37*
G36*
G01Y237194D02*
X277791Y236844D01*
Y235974D01*
X277121Y235624D01*
X276946D01*
Y237194D01*
X277121D01*
G37*
G36*
G01X273206Y271708D02*
X273238Y270953D01*
X272485Y270518D01*
X271847Y270923D01*
X271759Y271075D01*
X273119Y271860D01*
X273206Y271708D01*
G37*
G36*
G01X277391Y270923D02*
X276753Y270518D01*
X276000Y270953D01*
X276032Y271708D01*
X276119Y271860D01*
X277479Y271075D01*
X277391Y270923D01*
G37*
G36*
G01X266339Y267784D02*
X266371Y267029D01*
X265618Y266594D01*
X264980Y266999D01*
X264892Y267151D01*
X266252Y267936D01*
X266339Y267784D01*
G37*
G36*
G01X269820Y269754D02*
X269852Y268999D01*
X269099Y268564D01*
X268461Y268969D01*
X268373Y269120D01*
X269733Y269905D01*
X269820Y269754D01*
G37*
G36*
G01X269278Y255715D02*
X269246Y256470D01*
X269999Y256905D01*
X270637Y256500D01*
X270725Y256349D01*
X269365Y255563D01*
X269278Y255715D01*
G37*
G36*
G01X272652Y257661D02*
X272620Y258416D01*
X273373Y258851D01*
X274011Y258446D01*
X274099Y258295D01*
X272739Y257509D01*
X272652Y257661D01*
G37*
G36*
G01X259366Y250238D02*
X259076Y251022D01*
X259713Y251659D01*
X260497Y251369D01*
X260621Y251245D01*
X259490Y250114D01*
X259366Y250238D01*
G37*
G36*
G01X258173Y246506D02*
X257413Y246856D01*
Y247756D01*
X258173Y248106D01*
X258348D01*
Y246506D01*
X258173D01*
G37*
G36*
G01X269820Y254154D02*
X269852Y253399D01*
X269099Y252964D01*
X268461Y253369D01*
X268373Y253521D01*
X269733Y254306D01*
X269820Y254154D01*
G37*
G36*
G01X273206Y256108D02*
X273238Y255353D01*
X272485Y254918D01*
X271847Y255323D01*
X271759Y255475D01*
X273119Y256260D01*
X273206Y256108D01*
G37*
G36*
G01X266339Y252184D02*
X266371Y251429D01*
X265618Y250994D01*
X264980Y251399D01*
X264892Y251551D01*
X266252Y252336D01*
X266339Y252184D01*
G37*
G36*
G01X261275Y250591D02*
X261565Y249806D01*
X260929Y249170D01*
X260144Y249460D01*
X260020Y249583D01*
X261152Y250715D01*
X261275Y250591D01*
G37*
G36*
G01X259273Y247906D02*
X260033Y247556D01*
Y246656D01*
X259273Y246306D01*
X259098D01*
Y247906D01*
X259273D01*
G37*
G36*
G01X281981Y274049D02*
X282619Y274454D01*
X283372Y274019D01*
X283340Y273264D01*
X283253Y273112D01*
X281893Y273898D01*
X281981Y274049D01*
G37*
G36*
G01X269122Y275298D02*
X269065Y276053D01*
X269802Y276514D01*
X270454Y276131D01*
X270546Y275983D01*
X269216Y275150D01*
X269122Y275298D01*
G37*
G36*
G01X272688Y277183D02*
X272656Y277939D01*
X273410Y278374D01*
X274048Y277968D01*
X274135Y277817D01*
X272776Y277032D01*
X272688Y277183D01*
G37*
G36*
G01X275190Y277968D02*
X275828Y278374D01*
X276582Y277939D01*
X276550Y277183D01*
X276462Y277032D01*
X275103Y277817D01*
X275190Y277968D01*
G37*
G36*
G01X278601Y276000D02*
X279239Y276405D01*
X279992Y275970D01*
X279960Y275215D01*
X279873Y275063D01*
X278513Y275849D01*
X278601Y276000D01*
G37*
G36*
G01X280777Y272869D02*
X280139Y272464D01*
X279386Y272899D01*
X279418Y273654D01*
X279505Y273805D01*
X280865Y273020D01*
X280777Y272869D01*
G37*
G36*
G01X282376Y268819D02*
X281679Y269109D01*
X281603Y269976D01*
X282240Y270383D01*
X282414Y270398D01*
X282551Y268834D01*
X282376Y268819D01*
G37*
G36*
G01X269607Y273729D02*
X269665Y272974D01*
X268927Y272513D01*
X268275Y272896D01*
X268183Y273044D01*
X269514Y273877D01*
X269607Y273729D01*
G37*
G36*
G01X273206Y275608D02*
X273238Y274853D01*
X272485Y274418D01*
X271847Y274823D01*
X271759Y274975D01*
X273119Y275760D01*
X273206Y275608D01*
G37*
G36*
G01X277391Y274823D02*
X276753Y274418D01*
X276000Y274853D01*
X276032Y275608D01*
X276119Y275760D01*
X277479Y274975D01*
X277391Y274823D01*
G37*
G36*
G01X269278Y259615D02*
X269246Y260370D01*
X269999Y260805D01*
X270637Y260400D01*
X270725Y260249D01*
X269365Y259463D01*
X269278Y259615D01*
G37*
G36*
G01X272652Y261561D02*
X272620Y262316D01*
X273373Y262751D01*
X274011Y262346D01*
X274099Y262195D01*
X272739Y261409D01*
X272652Y261561D01*
G37*
G36*
G01X258970Y254122D02*
X258680Y254907D01*
X259317Y255543D01*
X260102Y255253D01*
X260225Y255129D01*
X259094Y253998D01*
X258970Y254122D01*
G37*
G36*
G01X256213Y251364D02*
X255923Y252149D01*
X256559Y252785D01*
X257344Y252495D01*
X257468Y252372D01*
X256336Y251240D01*
X256213Y251364D01*
G37*
G36*
G01X266339Y256084D02*
X266371Y255329D01*
X265618Y254894D01*
X264980Y255299D01*
X264892Y255451D01*
X266252Y256236D01*
X266339Y256084D01*
G37*
G36*
G01X269820Y258054D02*
X269852Y257299D01*
X269099Y256864D01*
X268461Y257269D01*
X268373Y257420D01*
X269733Y258205D01*
X269820Y258054D01*
G37*
G36*
G01X273206Y260008D02*
X273238Y259253D01*
X272485Y258818D01*
X271847Y259223D01*
X271759Y259375D01*
X273119Y260160D01*
X273206Y260008D01*
G37*
G36*
G01X278601Y260400D02*
X279239Y260805D01*
X279992Y260370D01*
X279960Y259615D01*
X279873Y259463D01*
X278513Y260249D01*
X278601Y260400D01*
G37*
G36*
G01X259520Y253119D02*
X259810Y252334D01*
X259174Y251698D01*
X258389Y251988D01*
X258265Y252111D01*
X259397Y253243D01*
X259520Y253119D01*
G37*
G36*
G01X276080Y250941D02*
X276021Y251694D01*
X276759Y252155D01*
X277410Y251773D01*
X277504Y251625D01*
X276172Y250792D01*
X276080Y250941D01*
G37*
G36*
G01X269278Y247915D02*
X269246Y248670D01*
X269999Y249105D01*
X270637Y248700D01*
X270725Y248549D01*
X269365Y247763D01*
X269278Y247915D01*
G37*
G36*
G01X272652Y249861D02*
X272620Y250616D01*
X273373Y251051D01*
X274011Y250646D01*
X274099Y250495D01*
X272739Y249709D01*
X272652Y249861D01*
G37*
G36*
G01X265357Y239549D02*
X264687Y239899D01*
Y240769D01*
X265357Y241119D01*
X265532D01*
Y239549D01*
X265357D01*
G37*
G36*
G01Y243407D02*
X264687Y243757D01*
X264688Y244626D01*
X265357Y244976D01*
X265533Y244977D01*
X265532Y243406D01*
X265357Y243407D01*
G37*
G36*
G01X265913Y245975D02*
X265881Y246730D01*
X266635Y247164D01*
X267272Y246759D01*
X267361Y246608D01*
X266000Y245823D01*
X265913Y245975D01*
G37*
G36*
G01X277368Y248311D02*
X276680Y247998D01*
X275995Y248534D01*
X276131Y249277D01*
X276239Y249415D01*
X277477Y248449D01*
X277368Y248311D01*
G37*
G36*
G01X273206Y248308D02*
X273238Y247553D01*
X272485Y247118D01*
X271847Y247523D01*
X271759Y247675D01*
X273119Y248460D01*
X273206Y248308D01*
G37*
G36*
G01X269820Y246354D02*
X269852Y245599D01*
X269099Y245164D01*
X268461Y245569D01*
X268373Y245721D01*
X269733Y246506D01*
X269820Y246354D01*
G37*
G36*
G01X266981Y239120D02*
X267651Y238770D01*
Y237900D01*
X266981Y237550D01*
X266806D01*
Y239120D01*
X266981D01*
G37*
G36*
G01Y243020D02*
X267651Y242670D01*
Y241800D01*
X266981Y241450D01*
X266806D01*
Y243020D01*
X266981D01*
G37*
G36*
G01X283235Y246983D02*
X283227Y246228D01*
X282453Y245833D01*
X281837Y246270D01*
X281757Y246427D01*
X283156Y247140D01*
X283235Y246983D01*
G37*
G36*
G01X266339Y259984D02*
X266371Y259229D01*
X265618Y258794D01*
X264980Y259199D01*
X264892Y259351D01*
X266252Y260136D01*
X266339Y259984D01*
G37*
G36*
G01X269790Y261937D02*
X269822Y261182D01*
X269069Y260747D01*
X268431Y261152D01*
X268343Y261303D01*
X269703Y262089D01*
X269790Y261937D01*
G37*
G36*
G01X273206Y263908D02*
X273238Y263153D01*
X272485Y262718D01*
X271847Y263123D01*
X271759Y263275D01*
X273119Y264060D01*
X273206Y263908D01*
G37*
G36*
G01X277391Y263123D02*
X276753Y262718D01*
X276000Y263153D01*
X276032Y263908D01*
X276119Y264060D01*
X277479Y263275D01*
X277391Y263123D01*
G37*
G36*
G01X280806Y261152D02*
X280168Y260747D01*
X279415Y261182D01*
X279447Y261937D01*
X279534Y262089D01*
X280894Y261303D01*
X280806Y261152D01*
G37*
G36*
G01X268293Y232577D02*
X268583Y231792D01*
X267946Y231156D01*
X267161Y231446D01*
X267038Y231570D01*
X268169Y232701D01*
X268293Y232577D01*
G37*
G36*
G01X265535Y229819D02*
X265825Y229035D01*
X265188Y228398D01*
X264404Y228688D01*
X264280Y228812D01*
X265411Y229943D01*
X265535Y229819D01*
G37*
G36*
G01X270361Y241095D02*
X271031Y240745D01*
Y239875D01*
X270361Y239525D01*
X270186D01*
Y241095D01*
X270361D01*
G37*
G36*
G01X273159Y244388D02*
X273191Y243633D01*
X272438Y243198D01*
X271800Y243603D01*
X271712Y243755D01*
X273072Y244540D01*
X273159Y244388D01*
G37*
G36*
G01X270361Y237195D02*
X271031Y236845D01*
Y235975D01*
X270361Y235625D01*
X270186D01*
Y237195D01*
X270361D01*
G37*
G36*
G01X273219Y235290D02*
X273979Y234940D01*
Y234040D01*
X273219Y233690D01*
X273044D01*
Y235290D01*
X273219D01*
G37*
G36*
G01X276577Y242452D02*
X276609Y241697D01*
X275856Y241262D01*
X275218Y241667D01*
X275130Y241818D01*
X276490Y242603D01*
X276577Y242452D01*
G37*
G36*
G01X273740Y239144D02*
X274410Y238794D01*
Y237924D01*
X273740Y237574D01*
X273565D01*
Y239144D01*
X273740D01*
G37*
G36*
G01X280784Y241665D02*
X280146Y241260D01*
X279393Y241695D01*
X279425Y242450D01*
X279512Y242602D01*
X280872Y241816D01*
X280784Y241665D01*
G37*
G36*
G01X284157Y239720D02*
X283519Y239315D01*
X282766Y239750D01*
X282798Y240505D01*
X282885Y240656D01*
X284245Y239871D01*
X284157Y239720D01*
G37*
G36*
G01X262717Y263160D02*
X262367Y262400D01*
X261467D01*
X261117Y263160D01*
Y263335D01*
X262717D01*
Y263160D01*
G37*
G36*
G01X269790Y265837D02*
X269822Y265082D01*
X269069Y264647D01*
X268431Y265052D01*
X268343Y265203D01*
X269703Y265989D01*
X269790Y265837D01*
G37*
G36*
G01X266339Y263884D02*
X266371Y263129D01*
X265618Y262694D01*
X264980Y263099D01*
X264892Y263251D01*
X266252Y264036D01*
X266339Y263884D01*
G37*
G36*
G01X273206Y267808D02*
X273238Y267053D01*
X272485Y266618D01*
X271847Y267023D01*
X271759Y267175D01*
X273119Y267960D01*
X273206Y267808D01*
G37*
G36*
G01X272652Y265461D02*
X272620Y266216D01*
X273373Y266651D01*
X274011Y266246D01*
X274099Y266095D01*
X272739Y265309D01*
X272652Y265461D01*
G37*
G36*
G01X275227Y266246D02*
X275865Y266651D01*
X276618Y266216D01*
X276586Y265461D01*
X276499Y265309D01*
X275139Y266095D01*
X275227Y266246D01*
G37*
G36*
G01X269285Y263519D02*
X269253Y264274D01*
X270006Y264709D01*
X270644Y264304D01*
X270732Y264153D01*
X269372Y263367D01*
X269285Y263519D01*
G37*
G36*
G01X278594Y264304D02*
X279232Y264709D01*
X279985Y264274D01*
X279953Y263519D01*
X279866Y263367D01*
X278506Y264153D01*
X278594Y264304D01*
G37*
G36*
G01X281974Y262353D02*
X282612Y262758D01*
X283365Y262323D01*
X283333Y261568D01*
X283246Y261416D01*
X281886Y262202D01*
X281974Y262353D01*
G37*
G36*
G01X266383Y232224D02*
X266093Y233009D01*
X266730Y233645D01*
X267515Y233355D01*
X267638Y233231D01*
X266507Y232100D01*
X266383Y232224D01*
G37*
G36*
G01X263626Y229466D02*
X263336Y230251D01*
X263972Y230887D01*
X264757Y230597D01*
X264881Y230474D01*
X263749Y229342D01*
X263626Y229466D01*
G37*
G36*
G01X269271Y244012D02*
X269239Y244767D01*
X269993Y245201D01*
X270630Y244796D01*
X270719Y244645D01*
X269358Y243860D01*
X269271Y244012D01*
G37*
G36*
G01X272652Y245961D02*
X272620Y246716D01*
X273373Y247151D01*
X274011Y246746D01*
X274099Y246595D01*
X272739Y245809D01*
X272652Y245961D01*
G37*
G36*
G01X268738Y241432D02*
X268068Y241782D01*
X268069Y242651D01*
X268738Y243001D01*
X268914Y243002D01*
X268913Y241431D01*
X268738Y241432D01*
G37*
G36*
G01X268737Y237574D02*
X268067Y237924D01*
Y238794D01*
X268737Y239144D01*
X268912D01*
Y237574D01*
X268737D01*
G37*
G36*
G01X272119Y233690D02*
X271359Y234040D01*
Y234940D01*
X272119Y235290D01*
X272294D01*
Y233690D01*
X272119D01*
G37*
G36*
G01X278571Y244817D02*
X279209Y245222D01*
X279962Y244787D01*
X279930Y244032D01*
X279843Y243880D01*
X278483Y244665D01*
X278571Y244817D01*
G37*
G36*
G01X272652Y242061D02*
X272620Y242816D01*
X273373Y243251D01*
X274011Y242846D01*
X274099Y242695D01*
X272738Y241910D01*
X272652Y242061D01*
G37*
G36*
G01X272118Y239481D02*
X271448Y239831D01*
Y240701D01*
X272118Y241051D01*
X272293Y241052D01*
X272292Y239481D01*
X272118D01*
G37*
G36*
G01X276067Y244032D02*
X276035Y244787D01*
X276788Y245222D01*
X277426Y244817D01*
X277514Y244666D01*
X276154Y243880D01*
X276067Y244032D01*
G37*
G36*
G01X281987Y242846D02*
X282625Y243251D01*
X283378Y242816D01*
X283346Y242061D01*
X283259Y241909D01*
X281899Y242695D01*
X281987Y242846D01*
G37*
G36*
G01X261117Y264260D02*
X261467Y265020D01*
X262367D01*
X262717Y264260D01*
Y264085D01*
X261117D01*
Y264260D01*
G37*
G36*
G01X272658Y269364D02*
X272626Y270119D01*
X273379Y270554D01*
X274017Y270149D01*
X274105Y269997D01*
X272745Y269212D01*
X272658Y269364D01*
G37*
G36*
G01X275221Y270149D02*
X275859Y270554D01*
X276612Y270119D01*
X276580Y269364D01*
X276493Y269212D01*
X275133Y269997D01*
X275221Y270149D01*
G37*
G36*
G01X269281Y267417D02*
X269249Y268172D01*
X270002Y268607D01*
X270640Y268202D01*
X270728Y268051D01*
X269368Y267265D01*
X269281Y267417D01*
G37*
G36*
G01X265904Y265470D02*
X265872Y266225D01*
X266625Y266660D01*
X267263Y266255D01*
X267351Y266104D01*
X265991Y265318D01*
X265904Y265470D01*
G37*
G36*
G01X276550Y324336D02*
X276582Y323580D01*
X275828Y323145D01*
X275190Y323551D01*
X275103Y323702D01*
X276462Y324487D01*
X276550Y324336D01*
G37*
G36*
G01X274048Y323551D02*
X273410Y323145D01*
X272656Y323580D01*
X272688Y324336D01*
X272776Y324487D01*
X274135Y323702D01*
X274048Y323551D01*
G37*
G36*
G01X279966Y326308D02*
X279998Y325553D01*
X279245Y325118D01*
X278607Y325523D01*
X278519Y325675D01*
X279879Y326460D01*
X279966Y326308D01*
G37*
G36*
G01X270631Y325523D02*
X269993Y325118D01*
X269240Y325553D01*
X269272Y326308D01*
X269359Y326460D01*
X270719Y325675D01*
X270631Y325523D01*
G37*
G36*
G01X265091Y325524D02*
X264741Y324764D01*
X263841D01*
X263491Y325524D01*
Y325699D01*
X265091D01*
Y325524D01*
G37*
G36*
G01X283340Y328254D02*
X283372Y327499D01*
X282619Y327064D01*
X281981Y327469D01*
X281893Y327620D01*
X283253Y328405D01*
X283340Y328254D01*
G37*
G36*
G01X286726Y330208D02*
X286758Y329453D01*
X286005Y329018D01*
X285367Y329423D01*
X285279Y329575D01*
X286639Y330360D01*
X286726Y330208D01*
G37*
G36*
G01X279966Y341908D02*
X279998Y341153D01*
X279245Y340718D01*
X278607Y341123D01*
X278519Y341275D01*
X279879Y342060D01*
X279966Y341908D01*
G37*
G36*
G01X277391Y341123D02*
X276753Y340718D01*
X276000Y341153D01*
X276032Y341908D01*
X276119Y342060D01*
X277479Y341275D01*
X277391Y341123D01*
G37*
G36*
G01X265718Y327698D02*
X265556Y328437D01*
X266222Y328996D01*
X266921Y328708D01*
X267033Y328574D01*
X265831Y327564D01*
X265718Y327698D01*
G37*
G36*
G01X261376Y328718D02*
X262161Y329008D01*
X262797Y328372D01*
X262507Y327587D01*
X262384Y327463D01*
X261252Y328595D01*
X261376Y328718D01*
G37*
G36*
G01X276032Y325912D02*
X276000Y326667D01*
X276753Y327102D01*
X277391Y326697D01*
X277479Y326545D01*
X276119Y325761D01*
X276032Y325912D01*
G37*
G36*
G01X271847Y326697D02*
X272485Y327102D01*
X273238Y326667D01*
X273206Y325912D01*
X273119Y325761D01*
X271759Y326545D01*
X271847Y326697D01*
G37*
G36*
G01X268467Y328647D02*
X269105Y329052D01*
X269858Y328617D01*
X269826Y327862D01*
X269739Y327711D01*
X268379Y328495D01*
X268467Y328647D01*
G37*
G36*
G01X279966Y338008D02*
X279998Y337253D01*
X279245Y336818D01*
X278607Y337223D01*
X278519Y337375D01*
X279879Y338160D01*
X279966Y338008D01*
G37*
G36*
G01X277391Y337223D02*
X276753Y336818D01*
X276000Y337253D01*
X276032Y338008D01*
X276119Y338160D01*
X277479Y337375D01*
X277391Y337223D01*
G37*
G36*
G01X274017Y339169D02*
X273379Y338764D01*
X272626Y339199D01*
X272658Y339954D01*
X272745Y340105D01*
X274105Y339320D01*
X274017Y339169D01*
G37*
G36*
G01X270631Y341123D02*
X269993Y340718D01*
X269240Y341153D01*
X269272Y341908D01*
X269359Y342060D01*
X270719Y341275D01*
X270631Y341123D01*
G37*
G36*
G01X279966Y322408D02*
X279998Y321653D01*
X279245Y321218D01*
X278607Y321623D01*
X278519Y321775D01*
X279879Y322560D01*
X279966Y322408D01*
G37*
G36*
G01X270631Y321623D02*
X269993Y321218D01*
X269240Y321653D01*
X269272Y322408D01*
X269359Y322560D01*
X270719Y321775D01*
X270631Y321623D01*
G37*
G36*
G01X263563Y322506D02*
X263213Y321746D01*
X262313D01*
X261963Y322506D01*
Y322681D01*
X263563D01*
Y322506D01*
G37*
G36*
G01X276580Y320454D02*
X276612Y319699D01*
X275859Y319264D01*
X275221Y319669D01*
X275133Y319820D01*
X276493Y320605D01*
X276580Y320454D01*
G37*
G36*
G01X274017Y319669D02*
X273379Y319264D01*
X272626Y319699D01*
X272658Y320454D01*
X272745Y320605D01*
X274105Y319820D01*
X274017Y319669D01*
G37*
G36*
G01X283331Y324349D02*
X283363Y323594D01*
X282610Y323159D01*
X281972Y323564D01*
X281884Y323715D01*
X283244Y324501D01*
X283331Y324349D01*
G37*
G36*
G01X286726Y326308D02*
X286758Y325553D01*
X286005Y325118D01*
X285367Y325523D01*
X285279Y325675D01*
X286639Y326460D01*
X286726Y326308D01*
G37*
G36*
G01X276038Y322015D02*
X276006Y322770D01*
X276759Y323205D01*
X277397Y322800D01*
X277485Y322649D01*
X276125Y321863D01*
X276038Y322015D01*
G37*
G36*
G01X271841Y322800D02*
X272479Y323205D01*
X273232Y322770D01*
X273200Y322015D01*
X273113Y321863D01*
X271753Y322649D01*
X271841Y322800D01*
G37*
G36*
G01X261963Y323604D02*
X262313Y324364D01*
X263213D01*
X263563Y323604D01*
Y323429D01*
X261963D01*
Y323604D01*
G37*
G36*
G01X279427Y323970D02*
X279395Y324725D01*
X280148Y325160D01*
X280786Y324755D01*
X280874Y324603D01*
X279514Y323818D01*
X279427Y323970D01*
G37*
G36*
G01X268461Y324749D02*
X269099Y325154D01*
X269852Y324719D01*
X269820Y323964D01*
X269733Y323812D01*
X268373Y324597D01*
X268461Y324749D01*
G37*
G36*
G01X270631Y337223D02*
X269993Y336818D01*
X269240Y337253D01*
X269272Y338008D01*
X269359Y338160D01*
X270719Y337375D01*
X270631Y337223D01*
G37*
G36*
G01X267257Y339169D02*
X266619Y338764D01*
X265866Y339199D01*
X265898Y339954D01*
X265985Y340105D01*
X267345Y339320D01*
X267257Y339169D01*
G37*
G36*
G01X262598Y341566D02*
X262248Y340806D01*
X261348D01*
X260998Y341566D01*
Y341741D01*
X262598D01*
Y341566D01*
G37*
G36*
G01X279412Y335661D02*
X279380Y336416D01*
X280133Y336851D01*
X280771Y336446D01*
X280859Y336295D01*
X279499Y335509D01*
X279412Y335661D01*
G37*
G36*
G01X274017Y335269D02*
X273379Y334864D01*
X272626Y335299D01*
X272658Y336054D01*
X272745Y336205D01*
X274105Y335420D01*
X274017Y335269D01*
G37*
G36*
G01X282953Y336697D02*
X282985Y335942D01*
X282232Y335507D01*
X281594Y335912D01*
X281506Y336063D01*
X282866Y336849D01*
X282953Y336697D01*
G37*
G36*
G01X258698Y341566D02*
X258348Y340806D01*
X257448D01*
X257098Y341566D01*
Y341741D01*
X258698D01*
Y341566D01*
G37*
G36*
G01X271841Y338400D02*
X272479Y338805D01*
X273232Y338370D01*
X273200Y337615D01*
X273113Y337463D01*
X271753Y338249D01*
X271841Y338400D01*
G37*
G36*
G01X268467Y340346D02*
X269105Y340751D01*
X269858Y340316D01*
X269826Y339561D01*
X269739Y339409D01*
X268379Y340195D01*
X268467Y340346D01*
G37*
G36*
G01X263220Y337260D02*
X262870Y336500D01*
X261970D01*
X261620Y337260D01*
Y337435D01*
X263220D01*
Y337260D01*
G37*
G36*
G01X267257Y335269D02*
X266619Y334864D01*
X265866Y335299D01*
X265898Y336054D01*
X265985Y336205D01*
X267345Y335420D01*
X267257Y335269D01*
G37*
G36*
G01X274017Y331369D02*
X273379Y330964D01*
X272626Y331399D01*
X272658Y332154D01*
X272745Y332305D01*
X274105Y331520D01*
X274017Y331369D01*
G37*
G36*
G01X270631Y333323D02*
X269993Y332918D01*
X269240Y333353D01*
X269272Y334108D01*
X269359Y334260D01*
X270719Y333475D01*
X270631Y333323D01*
G37*
G36*
G01X259228Y336909D02*
X258878Y336149D01*
X257978D01*
X257628Y336909D01*
Y337084D01*
X259228D01*
Y336909D01*
G37*
G36*
G01X265070Y334527D02*
X265743Y334872D01*
X266453Y334369D01*
X266352Y333619D01*
X266251Y333477D01*
X264969Y334384D01*
X265070Y334527D01*
G37*
G36*
G01X279412Y331761D02*
X279380Y332516D01*
X280133Y332951D01*
X280771Y332546D01*
X280859Y332395D01*
X279499Y331609D01*
X279412Y331761D01*
G37*
G36*
G01X276038Y329815D02*
X276006Y330570D01*
X276759Y331005D01*
X277397Y330600D01*
X277485Y330449D01*
X276125Y329663D01*
X276038Y329815D01*
G37*
G36*
G01X271841Y330600D02*
X272479Y331005D01*
X273232Y330570D01*
X273200Y329815D01*
X273113Y329663D01*
X271753Y330449D01*
X271841Y330600D01*
G37*
G36*
G01X268467Y332546D02*
X269105Y332951D01*
X269858Y332516D01*
X269826Y331761D01*
X269739Y331609D01*
X268379Y332395D01*
X268467Y332546D01*
G37*
G36*
G01X282798Y333715D02*
X282766Y334470D01*
X283519Y334905D01*
X284157Y334500D01*
X284245Y334349D01*
X282885Y333563D01*
X282798Y333715D01*
G37*
G36*
G01X265081Y338400D02*
X265719Y338805D01*
X266472Y338370D01*
X266440Y337615D01*
X266353Y337463D01*
X264993Y338249D01*
X265081Y338400D01*
G37*
G36*
G01X261620Y338360D02*
X261970Y339120D01*
X262870D01*
X263220Y338360D01*
Y338185D01*
X261620D01*
Y338360D01*
G37*
G36*
G01X271841Y334500D02*
X272479Y334905D01*
X273232Y334470D01*
X273200Y333715D01*
X273113Y333563D01*
X271753Y334349D01*
X271841Y334500D01*
G37*
G36*
G01X268467Y336446D02*
X269105Y336851D01*
X269858Y336416D01*
X269826Y335661D01*
X269739Y335509D01*
X268379Y336295D01*
X268467Y336446D01*
G37*
G36*
G01X257628Y338009D02*
X257978Y338769D01*
X258878D01*
X259228Y338009D01*
Y337834D01*
X257628D01*
Y338009D01*
G37*
G36*
G01X276580Y328254D02*
X276612Y327499D01*
X275859Y327064D01*
X275221Y327469D01*
X275133Y327620D01*
X276493Y328405D01*
X276580Y328254D01*
G37*
G36*
G01X274017Y327469D02*
X273379Y327064D01*
X272626Y327499D01*
X272658Y328254D01*
X272745Y328405D01*
X274105Y327620D01*
X274017Y327469D01*
G37*
G36*
G01X279966Y330208D02*
X279998Y329453D01*
X279245Y329018D01*
X278607Y329423D01*
X278519Y329575D01*
X279879Y330360D01*
X279966Y330208D01*
G37*
G36*
G01X270631Y329423D02*
X269993Y329018D01*
X269240Y329453D01*
X269272Y330208D01*
X269359Y330360D01*
X270719Y329575D01*
X270631Y329423D01*
G37*
G36*
G01X266942Y331310D02*
X266243Y331022D01*
X265577Y331581D01*
X265739Y332320D01*
X265852Y332454D01*
X267054Y331444D01*
X266942Y331310D01*
G37*
G36*
G01X283340Y332154D02*
X283372Y331399D01*
X282619Y330964D01*
X281981Y331369D01*
X281893Y331520D01*
X283253Y332305D01*
X283340Y332154D01*
G37*
G36*
G01X286655Y334072D02*
X286687Y333317D01*
X285934Y332882D01*
X285296Y333288D01*
X285208Y333438D01*
X286568Y334224D01*
X286655Y334072D01*
G37*
G36*
G01X283379Y359201D02*
X282958Y358573D01*
X282094Y358667D01*
X281818Y359371D01*
X281837Y359545D01*
X283398Y359374D01*
X283379Y359201D01*
G37*
G36*
G01X278877Y364349D02*
X278207Y364699D01*
Y365569D01*
X278877Y365919D01*
X279052D01*
Y364349D01*
X278877D01*
G37*
G36*
G01Y368200D02*
X278207Y368550D01*
Y369420D01*
X278877Y369770D01*
X279052D01*
Y368200D01*
X278877D01*
G37*
G36*
G01X277406Y372314D02*
X276768Y371909D01*
X276015Y372344D01*
X276047Y373099D01*
X276134Y373251D01*
X277494Y372465D01*
X277406Y372314D01*
G37*
G36*
G01X273342Y374309D02*
X272992Y373549D01*
X272092D01*
X271742Y374309D01*
Y374484D01*
X273342D01*
Y374309D01*
G37*
G36*
G01X267652Y376989D02*
X266868Y376699D01*
X266231Y377336D01*
X266521Y378120D01*
X266645Y378244D01*
X267776Y377113D01*
X267652Y376989D01*
G37*
G36*
G01X279799Y360363D02*
X279044Y360373D01*
X278651Y361149D01*
X279091Y361764D01*
X279247Y361843D01*
X279956Y360442D01*
X279799Y360363D01*
G37*
G36*
G01X267298Y378897D02*
X268082Y379187D01*
X268719Y378550D01*
X268429Y377766D01*
X268305Y377642D01*
X267174Y378773D01*
X267298Y378897D01*
G37*
G36*
G01X275227Y375446D02*
X275865Y375851D01*
X276618Y375416D01*
X276586Y374661D01*
X276499Y374509D01*
X275139Y375295D01*
X275227Y375446D01*
G37*
G36*
G01X278571Y373517D02*
X279208Y373923D01*
X279961Y373488D01*
X279930Y372733D01*
X279842Y372581D01*
X278482Y373366D01*
X278571Y373517D01*
G37*
G36*
G01X271742Y375409D02*
X272092Y376169D01*
X272992D01*
X273342Y375409D01*
Y375234D01*
X271742D01*
Y375409D01*
G37*
G36*
G01X280462Y363751D02*
X281217Y363714D01*
X281582Y362924D01*
X281121Y362326D01*
X280962Y362252D01*
X280303Y363677D01*
X280462Y363751D01*
G37*
G36*
G01X280501Y367845D02*
X281171Y367495D01*
Y366625D01*
X280501Y366275D01*
X280326D01*
Y367845D01*
X280501D01*
G37*
G36*
G01X280500Y371743D02*
X281170Y371394D01*
Y370524D01*
X280501Y370174D01*
X280325D01*
Y371744D01*
X280500Y371743D01*
G37*
G36*
G01X274017Y343069D02*
X273379Y342664D01*
X272626Y343099D01*
X272658Y343854D01*
X272745Y344005D01*
X274105Y343220D01*
X274017Y343069D01*
G37*
G36*
G01X270631Y345023D02*
X269993Y344618D01*
X269240Y345053D01*
X269272Y345808D01*
X269359Y345960D01*
X270719Y345175D01*
X270631Y345023D01*
G37*
G36*
G01X267257Y346969D02*
X266619Y346564D01*
X265866Y346999D01*
X265898Y347754D01*
X265985Y347905D01*
X267345Y347120D01*
X267257Y346969D01*
G37*
G36*
G01X260905Y352237D02*
X260120Y351947D01*
X259484Y352583D01*
X259774Y353368D01*
X259897Y353492D01*
X261029Y352360D01*
X260905Y352237D01*
G37*
G36*
G01X283340Y343854D02*
X283372Y343099D01*
X282619Y342664D01*
X281981Y343069D01*
X281893Y343220D01*
X283253Y344005D01*
X283340Y343854D01*
G37*
G36*
G01X286726Y345808D02*
X286758Y345053D01*
X286005Y344618D01*
X285367Y345023D01*
X285279Y345175D01*
X286639Y345960D01*
X286726Y345808D01*
G37*
G36*
G01X271841Y346200D02*
X272479Y346605D01*
X273232Y346170D01*
X273200Y345415D01*
X273113Y345263D01*
X271753Y346049D01*
X271841Y346200D01*
G37*
G36*
G01X268467Y348146D02*
X269105Y348551D01*
X269858Y348116D01*
X269826Y347361D01*
X269739Y347209D01*
X268379Y347995D01*
X268467Y348146D01*
G37*
G36*
G01X265073Y350019D02*
X265711Y350424D01*
X266464Y349989D01*
X266432Y349234D01*
X266345Y349082D01*
X264985Y349868D01*
X265073Y350019D01*
G37*
G36*
G01X260550Y354144D02*
X261335Y354434D01*
X261971Y353798D01*
X261681Y353013D01*
X261558Y352889D01*
X260426Y354021D01*
X260550Y354144D01*
G37*
G36*
G01X279412Y343461D02*
X279380Y344216D01*
X280133Y344651D01*
X280771Y344246D01*
X280859Y344095D01*
X279499Y343309D01*
X279412Y343461D01*
G37*
G36*
G01X275227Y344246D02*
X275865Y344651D01*
X276618Y344216D01*
X276586Y343461D01*
X276499Y343309D01*
X275139Y344095D01*
X275227Y344246D01*
G37*
G36*
G01X276248Y358455D02*
X275578Y358805D01*
Y359675D01*
X276248Y360025D01*
X276423D01*
Y358455D01*
X276248D01*
G37*
G36*
G01X260003Y378039D02*
X259218Y377749D01*
X258582Y378386D01*
X258872Y379170D01*
X258995Y379294D01*
X260127Y378163D01*
X260003Y378039D01*
G37*
G36*
G01X275497Y362350D02*
X274827Y362700D01*
Y363570D01*
X275497Y363920D01*
X275672D01*
Y362350D01*
X275497D01*
G37*
G36*
G01X272219Y367823D02*
X271434Y367533D01*
X270798Y368170D01*
X271088Y368954D01*
X271211Y369078D01*
X272343Y367947D01*
X272219Y367823D01*
G37*
G36*
G01X265519Y372523D02*
X264734Y372233D01*
X264098Y372870D01*
X264388Y373654D01*
X264511Y373778D01*
X265643Y372647D01*
X265519Y372523D01*
G37*
G36*
G01X262761Y375281D02*
X261976Y374991D01*
X261340Y375628D01*
X261630Y376412D01*
X261753Y376536D01*
X262885Y375405D01*
X262761Y375281D01*
G37*
G36*
G01X269461Y370581D02*
X268676Y370291D01*
X268040Y370928D01*
X268330Y371712D01*
X268453Y371836D01*
X269585Y370705D01*
X269461Y370581D01*
G37*
G36*
G01X259648Y379947D02*
X260433Y380237D01*
X261070Y379601D01*
X260780Y378816D01*
X260656Y378692D01*
X259525Y379823D01*
X259648Y379947D01*
G37*
G36*
G01X277120Y365893D02*
X277790Y365544D01*
Y364674D01*
X277121Y364324D01*
X276946Y364323D01*
Y365894D01*
X277120Y365893D01*
G37*
G36*
G01X275191Y367667D02*
X275828Y368073D01*
X276581Y367638D01*
X276550Y366883D01*
X276463Y366731D01*
X275103Y367517D01*
X275191Y367667D01*
G37*
G36*
G01X265164Y374431D02*
X265949Y374721D01*
X266586Y374085D01*
X266296Y373300D01*
X266172Y373176D01*
X265041Y374307D01*
X265164Y374431D01*
G37*
G36*
G01X262406Y377189D02*
X263191Y377479D01*
X263828Y376843D01*
X263538Y376058D01*
X263414Y375934D01*
X262283Y377065D01*
X262406Y377189D01*
G37*
G36*
G01X269106Y372489D02*
X269891Y372779D01*
X270528Y372143D01*
X270238Y371358D01*
X270114Y371234D01*
X268983Y372365D01*
X269106Y372489D01*
G37*
G36*
G01X271564Y370031D02*
X272349Y370321D01*
X272986Y369685D01*
X272696Y368900D01*
X272572Y368776D01*
X271441Y369907D01*
X271564Y370031D01*
G37*
G36*
G01X282257Y389675D02*
X281587Y390025D01*
Y390895D01*
X282257Y391245D01*
X282432D01*
Y389675D01*
X282257D01*
G37*
G36*
G01X280771Y393772D02*
X280133Y393367D01*
X279380Y393802D01*
X279412Y394557D01*
X279499Y394709D01*
X280859Y393923D01*
X280771Y393772D01*
G37*
G36*
G01X277406Y395714D02*
X276768Y395309D01*
X276015Y395744D01*
X276047Y396499D01*
X276134Y396651D01*
X277494Y395865D01*
X277406Y395714D01*
G37*
G36*
G01X274017Y397669D02*
X273379Y397264D01*
X272626Y397699D01*
X272658Y398454D01*
X272745Y398605D01*
X274105Y397820D01*
X274017Y397669D01*
G37*
G36*
G01X271052Y400479D02*
X270268Y400189D01*
X269631Y400826D01*
X269921Y401610D01*
X270045Y401734D01*
X271176Y400603D01*
X271052Y400479D01*
G37*
G36*
G01X283079Y393169D02*
X283749Y392820D01*
Y391950D01*
X283079Y391600D01*
X282905Y391599D01*
X282904Y393170D01*
X283079Y393169D01*
G37*
G36*
G01X278592Y396905D02*
X279230Y397310D01*
X279983Y396875D01*
X279951Y396120D01*
X279864Y395968D01*
X278504Y396753D01*
X278592Y396905D01*
G37*
G36*
G01X275227Y398846D02*
X275865Y399251D01*
X276618Y398816D01*
X276586Y398061D01*
X276499Y397909D01*
X275139Y398695D01*
X275227Y398846D01*
G37*
G36*
G01X271798Y401287D02*
X272582Y401577D01*
X273219Y400940D01*
X272929Y400156D01*
X272805Y400032D01*
X271674Y401163D01*
X271798Y401287D01*
G37*
G36*
G01X292397Y391591D02*
X291728Y391941D01*
Y392810D01*
X292398Y393160D01*
X292573Y393161D01*
X292572Y391590D01*
X292397Y391591D01*
G37*
G36*
G01X277397Y391819D02*
X276759Y391414D01*
X276006Y391849D01*
X276038Y392604D01*
X276125Y392755D01*
X277485Y391970D01*
X277397Y391819D01*
G37*
G36*
G01X274011Y393772D02*
X273373Y393367D01*
X272620Y393802D01*
X272652Y394557D01*
X272739Y394709D01*
X274099Y393923D01*
X274011Y393772D01*
G37*
G36*
G01X269729Y395759D02*
X269379Y394999D01*
X268479D01*
X268129Y395759D01*
Y395934D01*
X269729D01*
Y395759D01*
G37*
G36*
G01X265096Y396884D02*
X264311Y396594D01*
X263675Y397231D01*
X263964Y398016D01*
X264088Y398139D01*
X265220Y397008D01*
X265096Y396884D01*
G37*
G36*
G01X275221Y394950D02*
X275859Y395355D01*
X276612Y394920D01*
X276580Y394165D01*
X276493Y394013D01*
X275133Y394799D01*
X275221Y394950D01*
G37*
G36*
G01X271832Y396905D02*
X272470Y397310D01*
X273223Y396875D01*
X273191Y396120D01*
X273104Y395968D01*
X271744Y396753D01*
X271832Y396905D01*
G37*
G36*
G01X268129Y396860D02*
X268479Y397620D01*
X269379D01*
X269729Y396860D01*
Y396685D01*
X268129D01*
Y396860D01*
G37*
G36*
G01X264743Y398794D02*
X265528Y399084D01*
X266164Y398448D01*
X265874Y397663D01*
X265751Y397539D01*
X264619Y398670D01*
X264743Y398794D01*
G37*
G36*
G01X289768Y389655D02*
X289098Y390005D01*
Y390875D01*
X289768Y391225D01*
X289943D01*
Y389655D01*
X289768D01*
G37*
G36*
G01X288941Y402369D02*
X288591Y401609D01*
X287691D01*
X287341Y402369D01*
Y402544D01*
X288941D01*
Y402369D01*
G37*
G36*
G01X291809Y400018D02*
X291025Y399728D01*
X290388Y400365D01*
X290678Y401149D01*
X290802Y401273D01*
X291933Y400142D01*
X291809Y400018D01*
G37*
G36*
G01X290641Y393170D02*
X291311Y392820D01*
Y391950D01*
X290641Y391600D01*
X290466D01*
Y393170D01*
X290641D01*
G37*
G36*
G01X291455Y401926D02*
X292240Y402216D01*
X292876Y401580D01*
X292586Y400795D01*
X292463Y400671D01*
X291331Y401803D01*
X291455Y401926D01*
G37*
G36*
G01X267257Y343069D02*
X266619Y342664D01*
X265866Y343099D01*
X265898Y343854D01*
X265985Y344005D01*
X267345Y343220D01*
X267257Y343069D01*
G37*
G36*
G01X260294Y346821D02*
X259944Y346151D01*
X259074D01*
X258724Y346821D01*
Y346996D01*
X260294D01*
Y346821D01*
G37*
G36*
G01X256394D02*
X256044Y346151D01*
X255174D01*
X254824Y346821D01*
Y346996D01*
X256394D01*
Y346821D01*
G37*
G36*
G01X271841Y342300D02*
X272479Y342705D01*
X273232Y342270D01*
X273200Y341515D01*
X273113Y341363D01*
X271753Y342149D01*
X271841Y342300D01*
G37*
G36*
G01X268467Y344246D02*
X269105Y344651D01*
X269858Y344216D01*
X269826Y343461D01*
X269739Y343309D01*
X268379Y344095D01*
X268467Y344246D01*
G37*
G36*
G01X265081Y346200D02*
X265719Y346605D01*
X266472Y346170D01*
X266440Y345415D01*
X266353Y345263D01*
X264993Y346049D01*
X265081Y346200D01*
G37*
G36*
G01X259194Y347967D02*
X259544Y348636D01*
X260413D01*
X260763Y347966D01*
Y347791D01*
X259193Y347792D01*
X259194Y347967D01*
G37*
G36*
G01X255294D02*
X255644Y348636D01*
X256513D01*
X256863Y347966D01*
Y347791D01*
X255293Y347792D01*
X255294Y347967D01*
G37*
G36*
G01X265081Y342300D02*
X265719Y342705D01*
X266472Y342270D01*
X266440Y341515D01*
X266353Y341363D01*
X264993Y342149D01*
X265081Y342300D01*
G37*
G36*
G01X260998Y342664D02*
X261348Y343424D01*
X262248D01*
X262598Y342664D01*
Y342489D01*
X260998D01*
Y342664D01*
G37*
G36*
G01X257098D02*
X257448Y343424D01*
X258348D01*
X258698Y342664D01*
Y342489D01*
X257098D01*
Y342664D01*
G37*
G36*
G01X264487Y358041D02*
X264138Y357282D01*
X263237D01*
X262887Y358041D01*
Y358217D01*
X264487D01*
Y358041D01*
G37*
G36*
G01X279966Y345808D02*
X279998Y345053D01*
X279245Y344618D01*
X278607Y345023D01*
X278519Y345175D01*
X279879Y345960D01*
X279966Y345808D01*
G37*
G36*
G01X277391Y345023D02*
X276753Y344618D01*
X276000Y345053D01*
X276032Y345808D01*
X276119Y345960D01*
X277479Y345175D01*
X277391Y345023D01*
G37*
G36*
G01X274017Y346969D02*
X273379Y346564D01*
X272626Y346999D01*
X272658Y347754D01*
X272745Y347905D01*
X274105Y347120D01*
X274017Y346969D01*
G37*
G36*
G01X270631Y348923D02*
X269993Y348518D01*
X269240Y348953D01*
X269272Y349708D01*
X269359Y349860D01*
X270719Y349075D01*
X270631Y348923D01*
G37*
G36*
G01X267024Y350883D02*
X266361Y350520D01*
X265636Y351002D01*
X265717Y351755D01*
X265815Y351900D01*
X267120Y351028D01*
X267024Y350883D01*
G37*
G36*
G01X286340Y350351D02*
X286372Y349596D01*
X285619Y349161D01*
X284981Y349566D01*
X284893Y349717D01*
X286253Y350503D01*
X286340Y350351D01*
G37*
G36*
G01X282857Y348523D02*
X283262Y347885D01*
X282828Y347132D01*
X282073Y347164D01*
X281921Y347251D01*
X282706Y348610D01*
X282857Y348523D01*
G37*
G36*
G01X271841Y350100D02*
X272479Y350505D01*
X273232Y350070D01*
X273200Y349315D01*
X273113Y349163D01*
X271753Y349949D01*
X271841Y350100D01*
G37*
G36*
G01X268467Y352046D02*
X269105Y352451D01*
X269858Y352016D01*
X269826Y351261D01*
X269739Y351109D01*
X268379Y351895D01*
X268467Y352046D01*
G37*
G36*
G01X275227Y348146D02*
X275865Y348551D01*
X276618Y348116D01*
X276586Y347361D01*
X276499Y347209D01*
X275139Y347995D01*
X275227Y348146D01*
G37*
G36*
G01X267047Y357002D02*
X267807Y356652D01*
Y355751D01*
X267047Y355402D01*
X266872D01*
Y357002D01*
X267047D01*
G37*
G36*
G01X263387Y359140D02*
X263737Y359900D01*
X264638D01*
X264987Y359140D01*
Y358965D01*
X263387D01*
Y359140D01*
G37*
G36*
G01X260751Y361144D02*
X261535Y361434D01*
X262172Y360797D01*
X261882Y360013D01*
X261758Y359889D01*
X260627Y361020D01*
X260751Y361144D01*
G37*
G36*
G01X270359Y359741D02*
X271119Y359391D01*
Y358491D01*
X270359Y358141D01*
X270184D01*
Y359741D01*
X270359D01*
G37*
G36*
G01X275227Y352046D02*
X275865Y352451D01*
X276618Y352016D01*
X276586Y351261D01*
X276499Y351109D01*
X275139Y351895D01*
X275227Y352046D01*
G37*
G36*
G01X271841Y354000D02*
X272479Y354405D01*
X273232Y353970D01*
X273200Y353215D01*
X273113Y353063D01*
X271753Y353849D01*
X271841Y354000D01*
G37*
G36*
G01X282798Y353215D02*
X282766Y353970D01*
X283519Y354405D01*
X284157Y354000D01*
X284245Y353849D01*
X282885Y353063D01*
X282798Y353215D01*
G37*
G36*
G01X265258Y364016D02*
X265608Y364776D01*
X266508D01*
X266858Y364016D01*
Y363841D01*
X265258D01*
Y364016D01*
G37*
G36*
G01X268723Y363948D02*
X269508Y364238D01*
X270145Y363601D01*
X269855Y362816D01*
X269731Y362692D01*
X268599Y363824D01*
X268723Y363948D01*
G37*
G36*
G01X287261Y391245D02*
X287931Y390895D01*
Y390025D01*
X287261Y389675D01*
X287086D01*
Y391245D01*
X287261D01*
G37*
G36*
G01X277621Y402353D02*
X278406Y402643D01*
X279042Y402007D01*
X278752Y401222D01*
X278629Y401098D01*
X277497Y402230D01*
X277621Y402353D01*
G37*
G36*
G01X281987Y398846D02*
X282625Y399251D01*
X283378Y398816D01*
X283346Y398061D01*
X283259Y397909D01*
X281899Y398695D01*
X281987Y398846D01*
G37*
G36*
G01X287260Y395143D02*
X287930Y394794D01*
Y393924D01*
X287261Y393574D01*
X287086Y393573D01*
Y395144D01*
X287260Y395143D01*
G37*
G36*
G01X285331Y396917D02*
X285968Y397323D01*
X286721Y396888D01*
X286690Y396133D01*
X286603Y395981D01*
X285243Y396767D01*
X285331Y396917D01*
G37*
G36*
G01X274017Y354769D02*
X273379Y354364D01*
X272626Y354799D01*
X272658Y355554D01*
X272745Y355705D01*
X274105Y354920D01*
X274017Y354769D01*
G37*
G36*
G01X277391Y352823D02*
X276753Y352418D01*
X276000Y352853D01*
X276032Y353608D01*
X276119Y353760D01*
X277479Y352975D01*
X277391Y352823D01*
G37*
G36*
G01X265188Y366501D02*
X264404Y366211D01*
X263767Y366848D01*
X264057Y367632D01*
X264181Y367756D01*
X265312Y366625D01*
X265188Y366501D01*
G37*
G36*
G01X268870Y365575D02*
X268521Y364816D01*
X267620D01*
X267271Y365575D01*
Y365751D01*
X268870D01*
Y365575D01*
G37*
G36*
G01X271507Y363935D02*
X270722Y363645D01*
X270086Y364281D01*
X270376Y365066D01*
X270499Y365190D01*
X271631Y364058D01*
X271507Y363935D01*
G37*
G36*
G01X272119Y359467D02*
X271359Y359817D01*
Y360717D01*
X272119Y361067D01*
X272294D01*
Y359467D01*
X272119D01*
G37*
G36*
G01X262430Y369259D02*
X261646Y368969D01*
X261009Y369606D01*
X261299Y370390D01*
X261423Y370514D01*
X262554Y369383D01*
X262430Y369259D01*
G37*
G36*
G01X281352Y402527D02*
X280567Y402237D01*
X279931Y402873D01*
X280221Y403658D01*
X280344Y403782D01*
X281476Y402650D01*
X281352Y402527D01*
G37*
G36*
G01X287600Y397611D02*
X286929Y397263D01*
X286216Y397762D01*
X286314Y398512D01*
X286414Y398655D01*
X287700Y397755D01*
X287600Y397611D01*
G37*
G36*
G01X284201Y399638D02*
X283563Y399233D01*
X282810Y399668D01*
X282842Y400423D01*
X282929Y400575D01*
X284289Y399790D01*
X284201Y399638D01*
G37*
G36*
G01X269259Y358141D02*
X268499Y358491D01*
Y359391D01*
X269259Y359741D01*
X269434D01*
Y358141D01*
X269259D01*
G37*
G36*
G01X279966Y349708D02*
X279998Y348953D01*
X279245Y348518D01*
X278607Y348923D01*
X278519Y349075D01*
X279879Y349860D01*
X279966Y349708D01*
G37*
G36*
G01X277391Y348923D02*
X276753Y348518D01*
X276000Y348953D01*
X276032Y349708D01*
X276119Y349860D01*
X277479Y349075D01*
X277391Y348923D01*
G37*
G36*
G01X274017Y350869D02*
X273379Y350464D01*
X272626Y350899D01*
X272658Y351654D01*
X272745Y351805D01*
X274105Y351020D01*
X274017Y350869D01*
G37*
G36*
G01X270631Y352823D02*
X269993Y352418D01*
X269240Y352853D01*
X269272Y353608D01*
X269359Y353760D01*
X270719Y352975D01*
X270631Y352823D01*
G37*
G36*
G01X283340Y351654D02*
X283372Y350899D01*
X282619Y350464D01*
X281981Y350869D01*
X281893Y351020D01*
X283253Y351805D01*
X283340Y351654D01*
G37*
G36*
G01X286669Y353597D02*
X286701Y352842D01*
X285948Y352407D01*
X285310Y352813D01*
X285222Y352963D01*
X286582Y353749D01*
X286669Y353597D01*
G37*
G36*
G01X266858Y362916D02*
X266508Y362156D01*
X265608D01*
X265258Y362916D01*
Y363091D01*
X266858D01*
Y362916D01*
G37*
G36*
G01X287522Y385960D02*
X286851Y385612D01*
X286138Y386111D01*
X286236Y386860D01*
X286336Y387003D01*
X287622Y386104D01*
X287522Y385960D01*
G37*
G36*
G01X285637Y387700D02*
X284967Y388050D01*
Y388920D01*
X285637Y389270D01*
X285812D01*
Y387700D01*
X285637D01*
G37*
G36*
G01X277974Y400444D02*
X277190Y400154D01*
X276553Y400791D01*
X276843Y401575D01*
X276967Y401699D01*
X278098Y400568D01*
X277974Y400444D01*
G37*
G36*
G01X280777Y397669D02*
X280139Y397264D01*
X279386Y397699D01*
X279418Y398454D01*
X279505Y398605D01*
X280865Y397820D01*
X280777Y397669D01*
G37*
G36*
G01X285637Y391600D02*
X284967Y391950D01*
Y392820D01*
X285637Y393170D01*
X285812D01*
Y391600D01*
X285637D01*
G37*
G36*
G01X284166Y395714D02*
X283528Y395309D01*
X282775Y395744D01*
X282807Y396499D01*
X282894Y396651D01*
X284254Y395865D01*
X284166Y395714D01*
G37*
G36*
G01X273219Y360067D02*
X273979Y359717D01*
Y358817D01*
X273219Y358467D01*
X273044D01*
Y360067D01*
X273219D01*
G37*
G36*
G01X278543Y354029D02*
X279181Y354434D01*
X279934Y353999D01*
X279902Y353244D01*
X279815Y353092D01*
X278455Y353878D01*
X278543Y354029D01*
G37*
G36*
G01X275227Y355946D02*
X275865Y356351D01*
X276618Y355916D01*
X276586Y355161D01*
X276499Y355009D01*
X275139Y355795D01*
X275227Y355946D01*
G37*
G36*
G01X264835Y368410D02*
X265620Y368700D01*
X266256Y368064D01*
X265966Y367279D01*
X265843Y367155D01*
X264711Y368287D01*
X264835Y368410D01*
G37*
G36*
G01X267271Y366676D02*
X267621Y367436D01*
X268520D01*
X268870Y366676D01*
X268871Y366501D01*
X267270D01*
X267271Y366676D01*
G37*
G36*
G01X262077Y371168D02*
X262862Y371458D01*
X263498Y370822D01*
X263208Y370037D01*
X263085Y369913D01*
X261953Y371045D01*
X262077Y371168D01*
G37*
G36*
G01X271154Y365844D02*
X271938Y366134D01*
X272575Y365497D01*
X272285Y364713D01*
X272161Y364589D01*
X271030Y365720D01*
X271154Y365844D01*
G37*
G36*
G01X285339Y400807D02*
X285977Y401212D01*
X286730Y400777D01*
X286698Y400022D01*
X286611Y399871D01*
X285251Y400655D01*
X285339Y400807D01*
G37*
G36*
G01X289262Y397866D02*
X290017Y397898D01*
X290452Y397145D01*
X290047Y396506D01*
X289895Y396419D01*
X289110Y397779D01*
X289262Y397866D01*
G37*
G36*
G01X269040Y404045D02*
X269824Y404335D01*
X270461Y403698D01*
X270171Y402914D01*
X270047Y402790D01*
X268916Y403921D01*
X269040Y404045D01*
G37*
G36*
G01X284816Y404023D02*
X284032Y403733D01*
X283395Y404370D01*
X283685Y405154D01*
X283809Y405278D01*
X284940Y404147D01*
X284816Y404023D01*
G37*
G36*
G01X284462Y405931D02*
X285247Y406221D01*
X285883Y405585D01*
X285593Y404800D01*
X285470Y404676D01*
X284338Y405808D01*
X284462Y405931D01*
G37*
G36*
G01X287841Y403466D02*
X288191Y404226D01*
X289091D01*
X289441Y403466D01*
Y403291D01*
X287841D01*
Y403466D01*
G37*
G36*
G01X276952Y405827D02*
X276167Y405537D01*
X275531Y406173D01*
X275821Y406958D01*
X275944Y407082D01*
X277076Y405950D01*
X276952Y405827D01*
G37*
G36*
G01X276599Y407736D02*
X277383Y408026D01*
X278020Y407389D01*
X277730Y406605D01*
X277606Y406481D01*
X276475Y407612D01*
X276599Y407736D01*
G37*
G36*
G01X280999Y404436D02*
X281783Y404726D01*
X282420Y404089D01*
X282130Y403305D01*
X282006Y403181D01*
X280875Y404312D01*
X280999Y404436D01*
G37*
G36*
G01X295777Y198550D02*
X295107Y198900D01*
Y199770D01*
X295777Y200120D01*
X295952D01*
Y198550D01*
X295777D01*
G37*
G36*
G01Y202475D02*
X295107Y202825D01*
Y203695D01*
X295777Y204045D01*
X295952D01*
Y202475D01*
X295777D01*
G37*
G36*
G01X297401Y202119D02*
X298071Y201769D01*
Y200899D01*
X297401Y200549D01*
X297226D01*
Y202119D01*
X297401D01*
G37*
G36*
G01Y206019D02*
X298071Y205669D01*
Y204799D01*
X297401Y204449D01*
X297226D01*
Y206019D01*
X297401D01*
G37*
G36*
G01X295528Y207807D02*
X296198Y208155D01*
X296911Y207656D01*
X296813Y206907D01*
X296713Y206764D01*
X295427Y207663D01*
X295528Y207807D01*
G37*
G36*
G01X294811Y192736D02*
X295101Y191951D01*
X294464Y191315D01*
X293679Y191605D01*
X293556Y191729D01*
X294687Y192860D01*
X294811Y192736D01*
G37*
G36*
G01X294021Y200120D02*
X294691Y199770D01*
Y198900D01*
X294021Y198550D01*
X293846D01*
Y200120D01*
X294021D01*
G37*
G36*
G01Y204045D02*
X294691Y203695D01*
Y202825D01*
X294021Y202475D01*
X293846D01*
Y204045D01*
X294021D01*
G37*
G36*
G01X293106Y208239D02*
X293827Y208011D01*
X293978Y207154D01*
X293379Y206693D01*
X293206Y206663D01*
X292934Y208209D01*
X293106Y208239D01*
G37*
G36*
G01X314993Y199357D02*
X315753Y199007D01*
Y198107D01*
X314993Y197757D01*
X314818D01*
Y199357D01*
X314993D01*
G37*
G36*
G01Y203257D02*
X315753Y202907D01*
Y202007D01*
X314993Y201657D01*
X314818D01*
Y203257D01*
X314993D01*
G37*
G36*
G01X314300Y215720D02*
X314970Y215370D01*
Y214500D01*
X314300Y214150D01*
X314125D01*
Y215720D01*
X314300D01*
G37*
G36*
G01Y211820D02*
X314970Y211470D01*
Y210600D01*
X314300Y210250D01*
X314125D01*
Y211820D01*
X314300D01*
G37*
G36*
G01X319383Y201972D02*
X320143Y201622D01*
Y200722D01*
X319383Y200372D01*
X319208D01*
Y201972D01*
X319383D01*
G37*
G36*
G01X317803Y217221D02*
X318563Y216871D01*
Y215971D01*
X317803Y215621D01*
X317628D01*
Y217221D01*
X317803D01*
G37*
G36*
G01Y209821D02*
X318563Y209471D01*
Y208571D01*
X317803Y208221D01*
X317628D01*
Y209821D01*
X317803D01*
G37*
G36*
G01Y213721D02*
X318563Y213371D01*
Y212471D01*
X317803Y212121D01*
X317628D01*
Y213721D01*
X317803D01*
G37*
G36*
G01X319383Y205872D02*
X320143Y205522D01*
Y204622D01*
X319383Y204272D01*
X319208D01*
Y205872D01*
X319383D01*
G37*
G36*
G01X313893Y197757D02*
X313133Y198107D01*
Y199007D01*
X313893Y199357D01*
X314068D01*
Y197757D01*
X313893D01*
G37*
G36*
G01Y201657D02*
X313133Y202007D01*
Y202907D01*
X313893Y203257D01*
X314068D01*
Y201657D01*
X313893D01*
G37*
G36*
G01X312676Y216149D02*
X312006Y216499D01*
Y217369D01*
X312676Y217719D01*
X312851D01*
Y216149D01*
X312676D01*
G37*
G36*
G01Y212249D02*
X312006Y212599D01*
Y213469D01*
X312676Y213819D01*
X312851D01*
Y212249D01*
X312676D01*
G37*
G36*
G01X318283Y199872D02*
X317523Y200222D01*
Y201122D01*
X318283Y201472D01*
X318458D01*
Y199872D01*
X318283D01*
G37*
G36*
G01Y203772D02*
X317523Y204122D01*
Y205022D01*
X318283Y205372D01*
X318458D01*
Y203772D01*
X318283D01*
G37*
G36*
G01X316703Y214121D02*
X315943Y214471D01*
Y215371D01*
X316703Y215721D01*
X316878D01*
Y214121D01*
X316703D01*
G37*
G36*
G01Y210221D02*
X315943Y210571D01*
Y211471D01*
X316703Y211821D01*
X316878D01*
Y210221D01*
X316703D01*
G37*
G36*
G01X309655Y203847D02*
X308895Y204197D01*
Y205097D01*
X309655Y205447D01*
X309830D01*
Y203847D01*
X309655D01*
G37*
G36*
G01X309296Y214150D02*
X308626Y214500D01*
Y215370D01*
X309296Y215720D01*
X309471D01*
Y214150D01*
X309296D01*
G37*
G36*
G01Y210250D02*
X308626Y210600D01*
Y211470D01*
X309296Y211820D01*
X309471D01*
Y210250D01*
X309296D01*
G37*
G36*
G01X309655Y207747D02*
X308895Y208097D01*
Y208997D01*
X309655Y209347D01*
X309830D01*
Y207747D01*
X309655D01*
G37*
G36*
G01X310926Y201787D02*
X311686Y201437D01*
Y200537D01*
X310926Y200187D01*
X310751D01*
Y201787D01*
X310926D01*
G37*
G36*
G01X310755Y205447D02*
X311515Y205097D01*
Y204197D01*
X310755Y203847D01*
X310580D01*
Y205447D01*
X310755D01*
G37*
G36*
G01X310920Y217719D02*
X311590Y217369D01*
Y216499D01*
X310920Y216149D01*
X310745D01*
Y217719D01*
X310920D01*
G37*
G36*
G01Y213819D02*
X311590Y213469D01*
Y212599D01*
X310920Y212249D01*
X310745D01*
Y213819D01*
X310920D01*
G37*
G36*
G01X310755Y209347D02*
X311515Y208997D01*
Y208097D01*
X310755Y207747D01*
X310580D01*
Y209347D01*
X310755D01*
G37*
G36*
G01X328248Y198794D02*
X327463Y198504D01*
X326827Y199140D01*
X327117Y199925D01*
X327240Y200049D01*
X328372Y198917D01*
X328248Y198794D01*
G37*
G36*
G01X326419Y203123D02*
X325659Y203473D01*
Y204373D01*
X326419Y204723D01*
X326594D01*
Y203123D01*
X326419D01*
G37*
G36*
G01X322743Y216016D02*
X321983Y216366D01*
Y217266D01*
X322743Y217616D01*
X322918D01*
Y216016D01*
X322743D01*
G37*
G36*
G01Y212116D02*
X321983Y212466D01*
Y213366D01*
X322743Y213716D01*
X322918D01*
Y212116D01*
X322743D01*
G37*
G36*
G01X325478Y207316D02*
X324693Y207026D01*
X324057Y207662D01*
X324347Y208447D01*
X324470Y208571D01*
X325602Y207439D01*
X325478Y207316D01*
G37*
G36*
G01X327519Y204723D02*
X328279Y204373D01*
Y203473D01*
X327519Y203123D01*
X327344D01*
Y204723D01*
X327519D01*
G37*
G36*
G01X327894Y200703D02*
X328679Y200993D01*
X329316Y200356D01*
X329026Y199571D01*
X328902Y199448D01*
X327771Y200579D01*
X327894Y200703D01*
G37*
G36*
G01X323844Y217616D02*
X324604Y217266D01*
Y216366D01*
X323844Y216016D01*
X323669D01*
Y217616D01*
X323844D01*
G37*
G36*
G01Y214116D02*
X324604Y213766D01*
Y212866D01*
X323844Y212516D01*
X323669D01*
Y214116D01*
X323844D01*
G37*
G36*
G01X325124Y209225D02*
X325909Y209515D01*
X326546Y208878D01*
X326256Y208093D01*
X326132Y207970D01*
X325001Y209101D01*
X325124Y209225D01*
G37*
G36*
G01X304151Y198550D02*
X303391Y198900D01*
Y199800D01*
X304151Y200150D01*
X304326D01*
Y198550D01*
X304151D01*
G37*
G36*
G01X304780Y201914D02*
X304490Y202699D01*
X305126Y203336D01*
X305911Y203046D01*
X306035Y202922D01*
X304904Y201791D01*
X304780Y201914D01*
G37*
G36*
G01X305916Y216160D02*
X305246Y216510D01*
Y217380D01*
X305916Y217730D01*
X306091D01*
Y216160D01*
X305916D01*
G37*
G36*
G01X306439Y208414D02*
X305679Y208764D01*
Y209664D01*
X306439Y210014D01*
X306614D01*
Y208414D01*
X306439D01*
G37*
G36*
G01Y204514D02*
X305679Y204864D01*
Y205764D01*
X306439Y206114D01*
X306614D01*
Y204514D01*
X306439D01*
G37*
G36*
G01X305916Y212260D02*
X305246Y212610D01*
Y213480D01*
X305916Y213830D01*
X306091D01*
Y212260D01*
X305916D01*
G37*
G36*
G01X305252Y200150D02*
X306012Y199800D01*
Y198900D01*
X305252Y198550D01*
X305077D01*
Y200150D01*
X305252D01*
G37*
G36*
G01X306710Y202287D02*
X307000Y201503D01*
X306363Y200866D01*
X305579Y201156D01*
X305455Y201280D01*
X306586Y202411D01*
X306710Y202287D01*
G37*
G36*
G01X307541Y215709D02*
X308211Y215359D01*
Y214489D01*
X307541Y214139D01*
X307366D01*
Y215709D01*
X307541D01*
G37*
G36*
G01X307540Y206114D02*
X308300Y205764D01*
Y204864D01*
X307540Y204514D01*
X307365D01*
Y206114D01*
X307540D01*
G37*
G36*
G01Y210014D02*
X308300Y209664D01*
Y208764D01*
X307540Y208414D01*
X307365D01*
Y210014D01*
X307540D01*
G37*
G36*
G01X319723Y214503D02*
X318963Y214853D01*
Y215753D01*
X319723Y216103D01*
X319898D01*
Y214503D01*
X319723D01*
G37*
G36*
G01Y210603D02*
X318963Y210953D01*
Y211853D01*
X319723Y212203D01*
X319898D01*
Y210603D01*
X319723D01*
G37*
G36*
G01X321547Y207008D02*
X320762Y206718D01*
X320125Y207354D01*
X320415Y208139D01*
X320539Y208263D01*
X321670Y207132D01*
X321547Y207008D01*
G37*
G36*
G01X323248Y198548D02*
X322463Y198258D01*
X321826Y198894D01*
X322116Y199679D01*
X322240Y199803D01*
X323371Y198672D01*
X323248Y198548D01*
G37*
G36*
G01X322184Y204379D02*
X321424Y204729D01*
X321423Y205629D01*
X322184Y205979D01*
X322359D01*
Y204380D01*
X322184Y204379D01*
G37*
G36*
G01X320823Y216103D02*
X321583Y215753D01*
Y214853D01*
X320823Y214503D01*
X320648D01*
Y216103D01*
X320823D01*
G37*
G36*
G01Y212203D02*
X321583Y211853D01*
Y210953D01*
X320823Y210603D01*
X320648D01*
Y212203D01*
X320823D01*
G37*
G36*
G01X321193Y208917D02*
X321978Y209207D01*
X322614Y208571D01*
X322324Y207786D01*
X322201Y207662D01*
X321069Y208793D01*
X321193Y208917D01*
G37*
G36*
G01X323284Y205979D02*
X324044Y205629D01*
Y204730D01*
X323284Y204380D01*
X323109Y204379D01*
Y205979D01*
X323284D01*
G37*
G36*
G01X314300Y235220D02*
X314970Y234870D01*
Y234000D01*
X314300Y233650D01*
X314125D01*
Y235220D01*
X314300D01*
G37*
G36*
G01Y239120D02*
X314970Y238770D01*
Y237900D01*
X314300Y237550D01*
X314125D01*
Y239120D01*
X314300D01*
G37*
G36*
G01Y243020D02*
X314970Y242670D01*
Y241800D01*
X314300Y241450D01*
X314125D01*
Y243020D01*
X314300D01*
G37*
G36*
G01Y246920D02*
X314970Y246570D01*
Y245700D01*
X314300Y245350D01*
X314125D01*
Y246920D01*
X314300D01*
G37*
G36*
G01Y250820D02*
X314970Y250470D01*
Y249600D01*
X314300Y249250D01*
X314125D01*
Y250820D01*
X314300D01*
G37*
G36*
G01Y254720D02*
X314970Y254370D01*
Y253500D01*
X314300Y253150D01*
X314125D01*
Y254720D01*
X314300D01*
G37*
G36*
G01Y258620D02*
X314970Y258270D01*
Y257400D01*
X314300Y257050D01*
X314125D01*
Y258620D01*
X314300D01*
G37*
G36*
G01Y223520D02*
X314970Y223170D01*
Y222300D01*
X314300Y221950D01*
X314125D01*
Y223520D01*
X314300D01*
G37*
G36*
G01Y227445D02*
X314970Y227095D01*
Y226225D01*
X314300Y225875D01*
X314125D01*
Y227445D01*
X314300D01*
G37*
G36*
G01Y219620D02*
X314970Y219270D01*
Y218400D01*
X314300Y218050D01*
X314125D01*
Y219620D01*
X314300D01*
G37*
G36*
G01Y231369D02*
X314970Y231019D01*
Y230149D01*
X314300Y229799D01*
X314125D01*
Y231369D01*
X314300D01*
G37*
G36*
G01X317679Y260619D02*
X318349Y260269D01*
Y259399D01*
X317679Y259049D01*
X317504D01*
Y260619D01*
X317679D01*
G37*
G36*
G01X317680Y256719D02*
X318350Y256369D01*
Y255499D01*
X317680Y255149D01*
X317505D01*
Y256719D01*
X317680D01*
G37*
G36*
G01Y252819D02*
X318350Y252469D01*
Y251599D01*
X317680Y251249D01*
X317505D01*
Y252819D01*
X317680D01*
G37*
G36*
G01Y248919D02*
X318350Y248569D01*
Y247699D01*
X317680Y247349D01*
X317505D01*
Y248919D01*
X317680D01*
G37*
G36*
G01Y245019D02*
X318350Y244669D01*
Y243799D01*
X317680Y243449D01*
X317505D01*
Y245019D01*
X317680D01*
G37*
G36*
G01Y241119D02*
X318350Y240769D01*
Y239899D01*
X317680Y239549D01*
X317505D01*
Y241119D01*
X317680D01*
G37*
G36*
G01Y237219D02*
X318350Y236869D01*
Y235999D01*
X317680Y235649D01*
X317505D01*
Y237219D01*
X317680D01*
G37*
G36*
G01Y264494D02*
X318350Y264144D01*
Y263274D01*
X317680Y262924D01*
X317505D01*
Y264494D01*
X317680D01*
G37*
G36*
G01Y229370D02*
X318350Y229020D01*
Y228150D01*
X317680Y227800D01*
X317505D01*
Y229370D01*
X317680D01*
G37*
G36*
G01Y225519D02*
X318350Y225169D01*
Y224299D01*
X317680Y223949D01*
X317505D01*
Y225519D01*
X317680D01*
G37*
G36*
G01Y221619D02*
X318350Y221269D01*
Y220399D01*
X317680Y220049D01*
X317505D01*
Y221619D01*
X317680D01*
G37*
G36*
G01Y233294D02*
X318350Y232944D01*
Y232074D01*
X317680Y231724D01*
X317505D01*
Y233294D01*
X317680D01*
G37*
G36*
G01X312676Y255149D02*
X312006Y255499D01*
Y256369D01*
X312676Y256719D01*
X312851D01*
Y255149D01*
X312676D01*
G37*
G36*
G01Y251249D02*
X312006Y251599D01*
Y252469D01*
X312676Y252819D01*
X312851D01*
Y251249D01*
X312676D01*
G37*
G36*
G01Y247349D02*
X312006Y247699D01*
Y248569D01*
X312676Y248919D01*
X312851D01*
Y247349D01*
X312676D01*
G37*
G36*
G01Y243449D02*
X312006Y243799D01*
Y244669D01*
X312676Y245019D01*
X312851D01*
Y243449D01*
X312676D01*
G37*
G36*
G01Y239549D02*
X312006Y239899D01*
Y240769D01*
X312676Y241119D01*
X312851D01*
Y239549D01*
X312676D01*
G37*
G36*
G01Y235649D02*
X312006Y235999D01*
Y236869D01*
X312676Y237219D01*
X312851D01*
Y235649D01*
X312676D01*
G37*
G36*
G01Y259049D02*
X312006Y259399D01*
Y260269D01*
X312676Y260619D01*
X312851D01*
Y259049D01*
X312676D01*
G37*
G36*
G01Y227800D02*
X312006Y228150D01*
Y229020D01*
X312676Y229370D01*
X312851D01*
Y227800D01*
X312676D01*
G37*
G36*
G01Y223949D02*
X312006Y224299D01*
Y225169D01*
X312676Y225519D01*
X312851D01*
Y223949D01*
X312676D01*
G37*
G36*
G01Y220049D02*
X312006Y220399D01*
Y221269D01*
X312676Y221619D01*
X312851D01*
Y220049D01*
X312676D01*
G37*
G36*
G01Y231724D02*
X312006Y232074D01*
Y232944D01*
X312676Y233294D01*
X312851D01*
Y231724D01*
X312676D01*
G37*
G36*
G01X316056Y233650D02*
X315386Y234000D01*
Y234870D01*
X316056Y235220D01*
X316231D01*
Y233650D01*
X316056D01*
G37*
G36*
G01Y237550D02*
X315386Y237900D01*
Y238770D01*
X316056Y239120D01*
X316231D01*
Y237550D01*
X316056D01*
G37*
G36*
G01Y241450D02*
X315386Y241800D01*
Y242670D01*
X316056Y243020D01*
X316231D01*
Y241450D01*
X316056D01*
G37*
G36*
G01Y245350D02*
X315386Y245700D01*
Y246570D01*
X316056Y246920D01*
X316231D01*
Y245350D01*
X316056D01*
G37*
G36*
G01Y249250D02*
X315386Y249600D01*
Y250470D01*
X316056Y250820D01*
X316231D01*
Y249250D01*
X316056D01*
G37*
G36*
G01Y253150D02*
X315386Y253500D01*
Y254370D01*
X316056Y254720D01*
X316231D01*
Y253150D01*
X316056D01*
G37*
G36*
G01Y257050D02*
X315386Y257400D01*
Y258270D01*
X316056Y258620D01*
X316231D01*
Y257050D01*
X316056D01*
G37*
G36*
G01Y260974D02*
X315386Y261324D01*
Y262194D01*
X316056Y262544D01*
X316231D01*
Y260974D01*
X316056D01*
G37*
G36*
G01Y264850D02*
X315386Y265200D01*
Y266070D01*
X316056Y266420D01*
X316231D01*
Y264850D01*
X316056D01*
G37*
G36*
G01Y218050D02*
X315386Y218400D01*
Y219270D01*
X316056Y219620D01*
X316231D01*
Y218050D01*
X316056D01*
G37*
G36*
G01Y221950D02*
X315386Y222300D01*
Y223170D01*
X316056Y223520D01*
X316231D01*
Y221950D01*
X316056D01*
G37*
G36*
G01Y225875D02*
X315386Y226225D01*
Y227095D01*
X316056Y227445D01*
X316231D01*
Y225875D01*
X316056D01*
G37*
G36*
G01Y229799D02*
X315386Y230149D01*
Y231019D01*
X316056Y231369D01*
X316231D01*
Y229799D01*
X316056D01*
G37*
G36*
G01X309296Y233650D02*
X308626Y234000D01*
Y234870D01*
X309296Y235220D01*
X309471D01*
Y233650D01*
X309296D01*
G37*
G36*
G01Y249250D02*
X308626Y249600D01*
Y250470D01*
X309296Y250820D01*
X309471D01*
Y249250D01*
X309296D01*
G37*
G36*
G01Y245350D02*
X308626Y245700D01*
Y246570D01*
X309296Y246920D01*
X309471D01*
Y245350D01*
X309296D01*
G37*
G36*
G01Y241450D02*
X308626Y241800D01*
Y242670D01*
X309296Y243020D01*
X309471D01*
Y241450D01*
X309296D01*
G37*
G36*
G01Y237550D02*
X308626Y237900D01*
Y238770D01*
X309296Y239120D01*
X309471D01*
Y237550D01*
X309296D01*
G37*
G36*
G01Y257050D02*
X308626Y257400D01*
Y258270D01*
X309296Y258620D01*
X309471D01*
Y257050D01*
X309296D01*
G37*
G36*
G01Y253150D02*
X308626Y253500D01*
Y254370D01*
X309296Y254720D01*
X309471D01*
Y253150D01*
X309296D01*
G37*
G36*
G01Y260974D02*
X308626Y261324D01*
Y262194D01*
X309296Y262544D01*
X309471D01*
Y260974D01*
X309296D01*
G37*
G36*
G01Y225875D02*
X308626Y226225D01*
Y227095D01*
X309296Y227445D01*
X309471D01*
Y225875D01*
X309296D01*
G37*
G36*
G01Y221950D02*
X308626Y222300D01*
Y223170D01*
X309296Y223520D01*
X309471D01*
Y221950D01*
X309296D01*
G37*
G36*
G01Y218050D02*
X308626Y218400D01*
Y219270D01*
X309296Y219620D01*
X309471D01*
Y218050D01*
X309296D01*
G37*
G36*
G01Y229799D02*
X308626Y230149D01*
Y231019D01*
X309296Y231369D01*
X309471D01*
Y229799D01*
X309296D01*
G37*
G36*
G01X310919Y260619D02*
X311589Y260269D01*
Y259399D01*
X310919Y259049D01*
X310744D01*
Y260619D01*
X310919D01*
G37*
G36*
G01X310920Y256719D02*
X311590Y256369D01*
Y255499D01*
X310920Y255149D01*
X310745D01*
Y256719D01*
X310920D01*
G37*
G36*
G01Y252819D02*
X311590Y252469D01*
Y251599D01*
X310920Y251249D01*
X310745D01*
Y252819D01*
X310920D01*
G37*
G36*
G01Y248919D02*
X311590Y248569D01*
Y247699D01*
X310920Y247349D01*
X310745D01*
Y248919D01*
X310920D01*
G37*
G36*
G01Y245019D02*
X311590Y244669D01*
Y243799D01*
X310920Y243449D01*
X310745D01*
Y245019D01*
X310920D01*
G37*
G36*
G01Y241119D02*
X311590Y240769D01*
Y239899D01*
X310920Y239549D01*
X310745D01*
Y241119D01*
X310920D01*
G37*
G36*
G01Y237219D02*
X311590Y236869D01*
Y235999D01*
X310920Y235649D01*
X310745D01*
Y237219D01*
X310920D01*
G37*
G36*
G01Y229370D02*
X311590Y229020D01*
Y228150D01*
X310920Y227800D01*
X310745D01*
Y229370D01*
X310920D01*
G37*
G36*
G01Y225519D02*
X311590Y225169D01*
Y224299D01*
X310920Y223949D01*
X310745D01*
Y225519D01*
X310920D01*
G37*
G36*
G01Y221619D02*
X311590Y221269D01*
Y220399D01*
X310920Y220049D01*
X310745D01*
Y221619D01*
X310920D01*
G37*
G36*
G01Y233294D02*
X311590Y232944D01*
Y232074D01*
X310920Y231724D01*
X310745D01*
Y233294D01*
X310920D01*
G37*
G36*
G01X322816Y233650D02*
X322146Y234000D01*
Y234870D01*
X322816Y235220D01*
X322991D01*
Y233650D01*
X322816D01*
G37*
G36*
G01Y237550D02*
X322146Y237900D01*
Y238770D01*
X322816Y239120D01*
X322991D01*
Y237550D01*
X322816D01*
G37*
G36*
G01Y241450D02*
X322146Y241800D01*
Y242670D01*
X322816Y243020D01*
X322991D01*
Y241450D01*
X322816D01*
G37*
G36*
G01Y245350D02*
X322146Y245700D01*
Y246570D01*
X322816Y246920D01*
X322991D01*
Y245350D01*
X322816D01*
G37*
G36*
G01Y249250D02*
X322146Y249600D01*
Y250470D01*
X322816Y250820D01*
X322991D01*
Y249250D01*
X322816D01*
G37*
G36*
G01Y253150D02*
X322146Y253500D01*
Y254370D01*
X322816Y254720D01*
X322991D01*
Y253150D01*
X322816D01*
G37*
G36*
G01Y257050D02*
X322146Y257400D01*
Y258270D01*
X322816Y258620D01*
X322991D01*
Y257050D01*
X322816D01*
G37*
G36*
G01Y260950D02*
X322146Y261300D01*
Y262170D01*
X322816Y262520D01*
X322991D01*
Y260950D01*
X322816D01*
G37*
G36*
G01Y221950D02*
X322146Y222300D01*
Y223170D01*
X322816Y223520D01*
X322991D01*
Y221950D01*
X322816D01*
G37*
G36*
G01Y225875D02*
X322146Y226225D01*
Y227095D01*
X322816Y227445D01*
X322991D01*
Y225875D01*
X322816D01*
G37*
G36*
G01Y229799D02*
X322146Y230149D01*
Y231019D01*
X322816Y231369D01*
X322991D01*
Y229799D01*
X322816D01*
G37*
G36*
G01X324440Y256719D02*
X325110Y256369D01*
Y255499D01*
X324440Y255149D01*
X324265D01*
Y256719D01*
X324440D01*
G37*
G36*
G01Y252819D02*
X325110Y252469D01*
Y251599D01*
X324440Y251249D01*
X324265D01*
Y252819D01*
X324440D01*
G37*
G36*
G01Y248919D02*
X325110Y248569D01*
Y247699D01*
X324440Y247349D01*
X324265D01*
Y248919D01*
X324440D01*
G37*
G36*
G01Y245019D02*
X325110Y244669D01*
Y243799D01*
X324440Y243449D01*
X324265D01*
Y245019D01*
X324440D01*
G37*
G36*
G01Y241119D02*
X325110Y240769D01*
Y239899D01*
X324440Y239549D01*
X324265D01*
Y241119D01*
X324440D01*
G37*
G36*
G01Y237219D02*
X325110Y236869D01*
Y235999D01*
X324440Y235649D01*
X324265D01*
Y237219D01*
X324440D01*
G37*
G36*
G01Y260619D02*
X325110Y260269D01*
Y259399D01*
X324440Y259049D01*
X324265D01*
Y260619D01*
X324440D01*
G37*
G36*
G01Y264519D02*
X325110Y264169D01*
Y263299D01*
X324440Y262949D01*
X324265D01*
Y264519D01*
X324440D01*
G37*
G36*
G01Y229370D02*
X325110Y229020D01*
Y228150D01*
X324440Y227800D01*
X324265D01*
Y229370D01*
X324440D01*
G37*
G36*
G01Y225519D02*
X325110Y225169D01*
Y224299D01*
X324440Y223949D01*
X324265D01*
Y225519D01*
X324440D01*
G37*
G36*
G01Y233294D02*
X325110Y232944D01*
Y232074D01*
X324440Y231724D01*
X324265D01*
Y233294D01*
X324440D01*
G37*
G36*
G01X305916Y247360D02*
X305246Y247710D01*
Y248580D01*
X305916Y248930D01*
X306091D01*
Y247360D01*
X305916D01*
G37*
G36*
G01Y243460D02*
X305246Y243810D01*
Y244680D01*
X305916Y245030D01*
X306091D01*
Y243460D01*
X305916D01*
G37*
G36*
G01Y239560D02*
X305246Y239910D01*
Y240780D01*
X305916Y241130D01*
X306091D01*
Y239560D01*
X305916D01*
G37*
G36*
G01Y235660D02*
X305246Y236010D01*
Y236880D01*
X305916Y237230D01*
X306091D01*
Y235660D01*
X305916D01*
G37*
G36*
G01X305917Y259059D02*
X305247Y259409D01*
Y260279D01*
X305917Y260629D01*
X306092D01*
Y259059D01*
X305917D01*
G37*
G36*
G01X305916Y255160D02*
X305246Y255510D01*
Y256380D01*
X305916Y256730D01*
X306091D01*
Y255160D01*
X305916D01*
G37*
G36*
G01Y251260D02*
X305246Y251610D01*
Y252480D01*
X305916Y252830D01*
X306091D01*
Y251260D01*
X305916D01*
G37*
G36*
G01Y227800D02*
X305246Y228150D01*
Y229020D01*
X305916Y229370D01*
X306091D01*
Y227800D01*
X305916D01*
G37*
G36*
G01Y223960D02*
X305246Y224310D01*
Y225180D01*
X305916Y225530D01*
X306091D01*
Y223960D01*
X305916D01*
G37*
G36*
G01Y220060D02*
X305246Y220410D01*
Y221280D01*
X305916Y221630D01*
X306091D01*
Y220060D01*
X305916D01*
G37*
G36*
G01Y231749D02*
X305246Y232099D01*
Y232969D01*
X305916Y233319D01*
X306091D01*
Y231749D01*
X305916D01*
G37*
G36*
G01X307541Y235209D02*
X308211Y234859D01*
Y233989D01*
X307541Y233639D01*
X307366D01*
Y235209D01*
X307541D01*
G37*
G36*
G01Y258609D02*
X308211Y258259D01*
Y257389D01*
X307541Y257039D01*
X307366D01*
Y258609D01*
X307541D01*
G37*
G36*
G01Y254709D02*
X308211Y254359D01*
Y253489D01*
X307541Y253139D01*
X307366D01*
Y254709D01*
X307541D01*
G37*
G36*
G01Y250809D02*
X308211Y250459D01*
Y249589D01*
X307541Y249239D01*
X307366D01*
Y250809D01*
X307541D01*
G37*
G36*
G01Y246909D02*
X308211Y246559D01*
Y245689D01*
X307541Y245339D01*
X307366D01*
Y246909D01*
X307541D01*
G37*
G36*
G01Y243009D02*
X308211Y242659D01*
Y241789D01*
X307541Y241439D01*
X307366D01*
Y243009D01*
X307541D01*
G37*
G36*
G01Y239109D02*
X308211Y238759D01*
Y237889D01*
X307541Y237539D01*
X307366D01*
Y239109D01*
X307541D01*
G37*
G36*
G01Y262544D02*
X308211Y262194D01*
Y261324D01*
X307541Y260974D01*
X307366D01*
Y262544D01*
X307541D01*
G37*
G36*
G01Y219609D02*
X308211Y219259D01*
Y218389D01*
X307541Y218039D01*
X307366D01*
Y219609D01*
X307541D01*
G37*
G36*
G01Y227420D02*
X308211Y227070D01*
Y226200D01*
X307541Y225850D01*
X307366D01*
Y227420D01*
X307541D01*
G37*
G36*
G01Y223509D02*
X308211Y223159D01*
Y222289D01*
X307541Y221939D01*
X307366D01*
Y223509D01*
X307541D01*
G37*
G36*
G01Y231369D02*
X308211Y231019D01*
Y230149D01*
X307541Y229799D01*
X307366D01*
Y231369D01*
X307541D01*
G37*
G36*
G01X319436Y235649D02*
X318766Y235999D01*
Y236869D01*
X319436Y237219D01*
X319611D01*
Y235649D01*
X319436D01*
G37*
G36*
G01Y239549D02*
X318766Y239899D01*
Y240769D01*
X319436Y241119D01*
X319611D01*
Y239549D01*
X319436D01*
G37*
G36*
G01Y243449D02*
X318766Y243799D01*
Y244669D01*
X319436Y245019D01*
X319611D01*
Y243449D01*
X319436D01*
G37*
G36*
G01Y247349D02*
X318766Y247699D01*
Y248569D01*
X319436Y248919D01*
X319611D01*
Y247349D01*
X319436D01*
G37*
G36*
G01Y251249D02*
X318766Y251599D01*
Y252469D01*
X319436Y252819D01*
X319611D01*
Y251249D01*
X319436D01*
G37*
G36*
G01Y255149D02*
X318766Y255499D01*
Y256369D01*
X319436Y256719D01*
X319611D01*
Y255149D01*
X319436D01*
G37*
G36*
G01X319437Y259049D02*
X318767Y259399D01*
Y260269D01*
X319437Y260619D01*
X319612D01*
Y259049D01*
X319437D01*
G37*
G36*
G01X319448Y262987D02*
X318773Y263327D01*
X318760Y264197D01*
X319425Y264557D01*
X319601Y264559D01*
X319623Y262989D01*
X319448Y262987D01*
G37*
G36*
G01X319436Y223949D02*
X318766Y224299D01*
Y225169D01*
X319436Y225519D01*
X319611D01*
Y223949D01*
X319436D01*
G37*
G36*
G01Y227800D02*
X318766Y228150D01*
Y229020D01*
X319436Y229370D01*
X319611D01*
Y227800D01*
X319436D01*
G37*
G36*
G01Y220049D02*
X318766Y220399D01*
Y221269D01*
X319436Y221619D01*
X319611D01*
Y220049D01*
X319436D01*
G37*
G36*
G01Y231724D02*
X318766Y232074D01*
Y232944D01*
X319436Y233294D01*
X319611D01*
Y231724D01*
X319436D01*
G37*
G36*
G01X321060Y235220D02*
X321730Y234870D01*
Y234000D01*
X321060Y233650D01*
X320885D01*
Y235220D01*
X321060D01*
G37*
G36*
G01Y239120D02*
X321730Y238770D01*
Y237900D01*
X321060Y237550D01*
X320885D01*
Y239120D01*
X321060D01*
G37*
G36*
G01Y243020D02*
X321730Y242670D01*
Y241800D01*
X321060Y241450D01*
X320885D01*
Y243020D01*
X321060D01*
G37*
G36*
G01Y246920D02*
X321730Y246570D01*
Y245700D01*
X321060Y245350D01*
X320885D01*
Y246920D01*
X321060D01*
G37*
G36*
G01Y250820D02*
X321730Y250470D01*
Y249600D01*
X321060Y249250D01*
X320885D01*
Y250820D01*
X321060D01*
G37*
G36*
G01Y254720D02*
X321730Y254370D01*
Y253500D01*
X321060Y253150D01*
X320885D01*
Y254720D01*
X321060D01*
G37*
G36*
G01Y258620D02*
X321730Y258270D01*
Y257400D01*
X321060Y257050D01*
X320885D01*
Y258620D01*
X321060D01*
G37*
G36*
G01Y262544D02*
X321730Y262194D01*
Y261324D01*
X321060Y260974D01*
X320885D01*
Y262544D01*
X321060D01*
G37*
G36*
G01Y223520D02*
X321730Y223170D01*
Y222300D01*
X321060Y221950D01*
X320885D01*
Y223520D01*
X321060D01*
G37*
G36*
G01Y227445D02*
X321730Y227095D01*
Y226225D01*
X321060Y225875D01*
X320885D01*
Y227445D01*
X321060D01*
G37*
G36*
G01Y231369D02*
X321730Y231019D01*
Y230149D01*
X321060Y229799D01*
X320885D01*
Y231369D01*
X321060D01*
G37*
G36*
G01X411500Y250700D02*
Y233800D01*
X408400Y230700D01*
X401080D01*
X401046Y230857D01*
G03X398306I-1370J-298D01*
G01X398272Y230700D01*
X394320D01*
X394286Y230857D01*
G03X391546I-1370J-298D01*
G01X391512Y230700D01*
X387561D01*
X387527Y230857D01*
G03X384787I-1370J-298D01*
G01X384753Y230700D01*
X380801D01*
X380767Y230857D01*
G03X378027I-1370J-298D01*
G01X377993Y230700D01*
X374041D01*
X374007Y230857D01*
G03X371267I-1370J-298D01*
G01X371233Y230700D01*
X367281D01*
X367247Y230857D01*
G03X364507I-1370J-298D01*
G01X364473Y230700D01*
X360521D01*
X360487Y230857D01*
G03X357747I-1370J-298D01*
G01X357713Y230700D01*
X353761D01*
X353727Y230857D01*
G03X350987I-1370J-298D01*
G01X350953Y230700D01*
X347002D01*
X346968Y230857D01*
G03X344228I-1370J-298D01*
G01X344194Y230700D01*
X341500D01*
X340000Y232200D01*
Y233676D01*
G03Y235244I-1162J784D01*
G01Y237576D01*
G03Y239144I-1162J784D01*
G01Y241476D01*
G03Y243044I-1162J784D01*
G01Y245376D01*
G03Y246944I-1162J784D01*
G01Y249276D01*
G03Y250844I-1162J784D01*
G01Y253176D01*
G03X340219Y254199I-1162J784D01*
G01X340202Y254302D01*
X340742Y254842D01*
G02X341289Y254859I283J-283D01*
G03X343268Y256838I929J1050D01*
G02X343285Y257385I300J264D01*
G01X343575Y257675D01*
G02X344244Y257496I283J-283D01*
G03X346994Y257736I1354J364D01*
G02X347393Y258100I399J-36D01*
G01X350562D01*
G02X350961Y257736I0J-400D01*
G03X352805Y259188I1396J124D01*
G02X352650Y259850I128J379D01*
G01X355206Y262406D01*
X355321Y262370D01*
G03X357076Y264125I416J1339D01*
G01X357040Y264240D01*
X359700Y266900D01*
X360767D01*
G03X362217I725J1200D01*
G01X362956D01*
G02X363354Y266456I0J-400D01*
G03X366140I1393J-156D01*
G02X366538Y266900I398J44D01*
G01X426617D01*
X427759Y265758D01*
Y263600D01*
X426959Y262800D01*
X423700D01*
X423200Y262300D01*
Y258530D01*
X422500Y257830D01*
X418630D01*
X411500Y250700D01*
G37*
G36*
G01X317680Y334719D02*
X318350Y334369D01*
Y333499D01*
X317680Y333149D01*
X317505D01*
Y334719D01*
X317680D01*
G37*
G36*
G01Y338619D02*
X318350Y338269D01*
Y337399D01*
X317680Y337049D01*
X317505D01*
Y338619D01*
X317680D01*
G37*
G36*
G01Y342519D02*
X318350Y342169D01*
Y341299D01*
X317680Y340949D01*
X317505D01*
Y342519D01*
X317680D01*
G37*
G36*
G01Y330819D02*
X318350Y330469D01*
Y329599D01*
X317680Y329249D01*
X317505D01*
Y330819D01*
X317680D01*
G37*
G36*
G01X319436Y340949D02*
X318766Y341299D01*
Y342169D01*
X319436Y342519D01*
X319611D01*
Y340949D01*
X319436D01*
G37*
G36*
G01X316056Y327250D02*
X315386Y327600D01*
Y328470D01*
X316056Y328820D01*
X316231D01*
Y327250D01*
X316056D01*
G37*
G36*
G01Y331150D02*
X315386Y331500D01*
Y332370D01*
X316056Y332720D01*
X316231D01*
Y331150D01*
X316056D01*
G37*
G36*
G01Y335050D02*
X315386Y335400D01*
Y336270D01*
X316056Y336620D01*
X316231D01*
Y335050D01*
X316056D01*
G37*
G36*
G01Y338950D02*
X315386Y339300D01*
Y340170D01*
X316056Y340520D01*
X316231D01*
Y338950D01*
X316056D01*
G37*
G36*
G01X321060Y340520D02*
X321730Y340170D01*
Y339300D01*
X321060Y338950D01*
X320885D01*
Y340520D01*
X321060D01*
G37*
G36*
G01X312676Y329249D02*
X312006Y329599D01*
Y330469D01*
X312676Y330819D01*
X312851D01*
Y329249D01*
X312676D01*
G37*
G36*
G01X313549Y332725D02*
X314219Y332375D01*
Y331505D01*
X313549Y331155D01*
X313374D01*
Y332725D01*
X313549D01*
G37*
G36*
G01X312676Y333149D02*
X312006Y333499D01*
Y334369D01*
X312676Y334719D01*
X312851D01*
Y333149D01*
X312676D01*
G37*
G36*
G01Y337049D02*
X312006Y337399D01*
Y338269D01*
X312676Y338619D01*
X312851D01*
Y337049D01*
X312676D01*
G37*
G36*
G01Y340949D02*
X312006Y341299D01*
Y342169D01*
X312676Y342519D01*
X312851D01*
Y340949D01*
X312676D01*
G37*
G36*
G01X313870Y337342D02*
X314626Y337311D01*
X314998Y336525D01*
X314541Y335922D01*
X314383Y335847D01*
X313712Y337267D01*
X313870Y337342D01*
G37*
G36*
G01X314300Y340520D02*
X314970Y340170D01*
Y339300D01*
X314300Y338950D01*
X314125D01*
Y340520D01*
X314300D01*
G37*
G36*
G01X326196Y340949D02*
X325526Y341299D01*
Y342169D01*
X326196Y342519D01*
X326371D01*
Y340949D01*
X326196D01*
G37*
G36*
G01Y337049D02*
X325526Y337399D01*
Y338269D01*
X326196Y338619D01*
X326371D01*
Y337049D01*
X326196D01*
G37*
G36*
G01X327820Y336620D02*
X328490Y336270D01*
Y335400D01*
X327820Y335050D01*
X327645D01*
Y336620D01*
X327820D01*
G37*
G36*
G01Y340520D02*
X328490Y340170D01*
Y339300D01*
X327820Y338950D01*
X327645D01*
Y340520D01*
X327820D01*
G37*
G36*
G01X309296Y331150D02*
X308626Y331500D01*
Y332370D01*
X309296Y332720D01*
X309471D01*
Y331150D01*
X309296D01*
G37*
G36*
G01Y335050D02*
X308626Y335400D01*
Y336270D01*
X309296Y336620D01*
X309471D01*
Y335050D01*
X309296D01*
G37*
G36*
G01Y338950D02*
X308626Y339300D01*
Y340170D01*
X309296Y340520D01*
X309471D01*
Y338950D01*
X309296D01*
G37*
G36*
G01X310920Y338619D02*
X311590Y338269D01*
Y337399D01*
X310920Y337049D01*
X310745D01*
Y338619D01*
X310920D01*
G37*
G36*
G01Y342519D02*
X311590Y342169D01*
Y341299D01*
X310920Y340949D01*
X310745D01*
Y342519D01*
X310920D01*
G37*
G36*
G01X310436Y335531D02*
X311190Y335476D01*
X311536Y334678D01*
X311061Y334090D01*
X310900Y334021D01*
X310276Y335461D01*
X310436Y335531D01*
G37*
G36*
G01X320187Y329244D02*
X319517Y329594D01*
Y330464D01*
X320187Y330814D01*
X320362D01*
Y329244D01*
X320187D01*
G37*
G36*
G01X321060Y332720D02*
X321730Y332370D01*
Y331500D01*
X321060Y331150D01*
X320885D01*
Y332720D01*
X321060D01*
G37*
G36*
G01X322816Y338950D02*
X322146Y339300D01*
Y340170D01*
X322816Y340520D01*
X322991D01*
Y338950D01*
X322816D01*
G37*
G36*
G01X320794Y335249D02*
X320762Y336004D01*
X321516Y336439D01*
X322154Y336034D01*
X322242Y335883D01*
X320882Y335098D01*
X320794Y335249D01*
G37*
G36*
G01X323784Y335792D02*
X324101Y335106D01*
X323570Y334417D01*
X322826Y334549D01*
X322686Y334655D01*
X323645Y335899D01*
X323784Y335792D01*
G37*
G36*
G01X324440Y338619D02*
X325110Y338269D01*
Y337399D01*
X324440Y337049D01*
X324265D01*
Y338619D01*
X324440D01*
G37*
G36*
G01Y342519D02*
X325110Y342169D01*
Y341299D01*
X324440Y340949D01*
X324265D01*
Y342519D01*
X324440D01*
G37*
G36*
G01X296609Y401016D02*
X295850Y401365D01*
Y402266D01*
X296609Y402615D01*
X296785D01*
Y401016D01*
X296609D01*
G37*
G36*
G01X295777Y397450D02*
X295107Y397800D01*
Y398670D01*
X295777Y399020D01*
X295952D01*
Y397450D01*
X295777D01*
G37*
G36*
G01X292939Y394167D02*
X292907Y394922D01*
X293660Y395356D01*
X294298Y394951D01*
X294386Y394800D01*
X293025Y394015D01*
X292939Y394167D01*
G37*
G36*
G01X296666Y394432D02*
X296999Y393753D01*
X296484Y393052D01*
X295737Y393166D01*
X295595Y393270D01*
X296525Y394535D01*
X296666Y394432D01*
G37*
G36*
G01X297708Y402615D02*
X298468Y402265D01*
Y401366D01*
X297708Y401016D01*
X297533Y401015D01*
Y402616D01*
X297708Y402615D01*
G37*
G36*
G01X297401Y397094D02*
X298071Y396744D01*
Y395874D01*
X297401Y395524D01*
X297226D01*
Y397094D01*
X297401D01*
G37*
G36*
G01X294021Y399020D02*
X294691Y398670D01*
Y397800D01*
X294021Y397450D01*
X293846D01*
Y399020D01*
X294021D01*
G37*
G36*
G01X317680Y377619D02*
X318350Y377269D01*
Y376399D01*
X317680Y376049D01*
X317505D01*
Y377619D01*
X317680D01*
G37*
G36*
G01Y381519D02*
X318350Y381169D01*
Y380299D01*
X317680Y379949D01*
X317505D01*
Y381519D01*
X317680D01*
G37*
G36*
G01Y385419D02*
X318350Y385069D01*
Y384199D01*
X317680Y383849D01*
X317505D01*
Y385419D01*
X317680D01*
G37*
G36*
G01Y389319D02*
X318350Y388969D01*
Y388099D01*
X317680Y387749D01*
X317505D01*
Y389319D01*
X317680D01*
G37*
G36*
G01X316255Y400123D02*
X317015Y399773D01*
Y398873D01*
X316255Y398523D01*
X316080D01*
Y400123D01*
X316255D01*
G37*
G36*
G01X317679Y393179D02*
X318349Y392829D01*
Y391959D01*
X317679Y391609D01*
X317504D01*
Y393179D01*
X317679D01*
G37*
G36*
G01X317680Y358119D02*
X318350Y357769D01*
Y356899D01*
X317680Y356549D01*
X317505D01*
Y358119D01*
X317680D01*
G37*
G36*
G01Y350319D02*
X318350Y349969D01*
Y349099D01*
X317680Y348749D01*
X317505D01*
Y350319D01*
X317680D01*
G37*
G36*
G01Y354219D02*
X318350Y353869D01*
Y352999D01*
X317680Y352649D01*
X317505D01*
Y354219D01*
X317680D01*
G37*
G36*
G01Y346419D02*
X318350Y346069D01*
Y345199D01*
X317680Y344849D01*
X317505D01*
Y346419D01*
X317680D01*
G37*
G36*
G01Y362019D02*
X318350Y361669D01*
Y360799D01*
X317680Y360449D01*
X317505D01*
Y362019D01*
X317680D01*
G37*
G36*
G01Y365919D02*
X318350Y365569D01*
Y364699D01*
X317680Y364349D01*
X317505D01*
Y365919D01*
X317680D01*
G37*
G36*
G01Y369770D02*
X318350Y369420D01*
Y368550D01*
X317680Y368200D01*
X317505D01*
Y369770D01*
X317680D01*
G37*
G36*
G01Y373694D02*
X318350Y373344D01*
Y372474D01*
X317680Y372124D01*
X317505D01*
Y373694D01*
X317680D01*
G37*
G36*
G01X319973Y384021D02*
X319213Y384371D01*
Y385271D01*
X319973Y385621D01*
X320148D01*
Y384021D01*
X319973D01*
G37*
G36*
G01X319436Y376049D02*
X318766Y376399D01*
Y377269D01*
X319436Y377619D01*
X319611D01*
Y376049D01*
X319436D01*
G37*
G36*
G01Y379949D02*
X318766Y380299D01*
Y381169D01*
X319436Y381519D01*
X319611D01*
Y379949D01*
X319436D01*
G37*
G36*
G01X319973Y387921D02*
X319213Y388271D01*
Y389171D01*
X319973Y389521D01*
X320148D01*
Y387921D01*
X319973D01*
G37*
G36*
G01Y391821D02*
X319213Y392171D01*
Y393071D01*
X319973Y393421D01*
X320148D01*
Y391821D01*
X319973D01*
G37*
G36*
G01X318308Y399021D02*
X317548Y399371D01*
Y400271D01*
X318308Y400621D01*
X318483D01*
Y399021D01*
X318308D01*
G37*
G36*
G01X319436Y356549D02*
X318766Y356899D01*
Y357769D01*
X319436Y358119D01*
X319611D01*
Y356549D01*
X319436D01*
G37*
G36*
G01Y348749D02*
X318766Y349099D01*
Y349969D01*
X319436Y350319D01*
X319611D01*
Y348749D01*
X319436D01*
G37*
G36*
G01Y352649D02*
X318766Y352999D01*
Y353869D01*
X319436Y354219D01*
X319611D01*
Y352649D01*
X319436D01*
G37*
G36*
G01Y344849D02*
X318766Y345199D01*
Y346069D01*
X319436Y346419D01*
X319611D01*
Y344849D01*
X319436D01*
G37*
G36*
G01Y368200D02*
X318766Y368550D01*
Y369420D01*
X319436Y369770D01*
X319611D01*
Y368200D01*
X319436D01*
G37*
G36*
G01Y372124D02*
X318766Y372474D01*
Y373344D01*
X319436Y373694D01*
X319611D01*
Y372124D01*
X319436D01*
G37*
G36*
G01Y360449D02*
X318766Y360799D01*
Y361669D01*
X319436Y362019D01*
X319611D01*
Y360449D01*
X319436D01*
G37*
G36*
G01Y364349D02*
X318766Y364699D01*
Y365569D01*
X319436Y365919D01*
X319611D01*
Y364349D01*
X319436D01*
G37*
G36*
G01X316056Y377950D02*
X315386Y378300D01*
Y379170D01*
X316056Y379520D01*
X316231D01*
Y377950D01*
X316056D01*
G37*
G36*
G01Y381850D02*
X315386Y382200D01*
Y383070D01*
X316056Y383420D01*
X316231D01*
Y381850D01*
X316056D01*
G37*
G36*
G01Y385750D02*
X315386Y386100D01*
Y386970D01*
X316056Y387320D01*
X316231D01*
Y385750D01*
X316056D01*
G37*
G36*
G01Y389675D02*
X315386Y390025D01*
Y390895D01*
X316056Y391245D01*
X316231D01*
Y389675D01*
X316056D01*
G37*
G36*
G01X315155Y398523D02*
X314395Y398873D01*
Y399773D01*
X315155Y400123D01*
X315330D01*
Y398523D01*
X315155D01*
G37*
G36*
G01X316056Y358450D02*
X315386Y358800D01*
Y359670D01*
X316056Y360020D01*
X316231D01*
Y358450D01*
X316056D01*
G37*
G36*
G01Y350650D02*
X315386Y351000D01*
Y351870D01*
X316056Y352220D01*
X316231D01*
Y350650D01*
X316056D01*
G37*
G36*
G01Y354550D02*
X315386Y354900D01*
Y355770D01*
X316056Y356120D01*
X316231D01*
Y354550D01*
X316056D01*
G37*
G36*
G01Y342850D02*
X315386Y343200D01*
Y344070D01*
X316056Y344420D01*
X316231D01*
Y342850D01*
X316056D01*
G37*
G36*
G01Y346750D02*
X315386Y347100D01*
Y347970D01*
X316056Y348320D01*
X316231D01*
Y346750D01*
X316056D01*
G37*
G36*
G01Y362350D02*
X315386Y362700D01*
Y363570D01*
X316056Y363920D01*
X316231D01*
Y362350D01*
X316056D01*
G37*
G36*
G01Y366275D02*
X315386Y366625D01*
Y367495D01*
X316056Y367845D01*
X316231D01*
Y366275D01*
X316056D01*
G37*
G36*
G01Y370199D02*
X315386Y370549D01*
Y371419D01*
X316056Y371769D01*
X316231D01*
Y370199D01*
X316056D01*
G37*
G36*
G01Y374050D02*
X315386Y374400D01*
Y375270D01*
X316056Y375620D01*
X316231D01*
Y374050D01*
X316056D01*
G37*
G36*
G01X321060Y379520D02*
X321730Y379170D01*
Y378300D01*
X321060Y377950D01*
X320885D01*
Y379520D01*
X321060D01*
G37*
G36*
G01X321073Y385621D02*
X321833Y385271D01*
Y384371D01*
X321073Y384021D01*
X320898D01*
Y385621D01*
X321073D01*
G37*
G36*
G01Y389521D02*
X321833Y389171D01*
Y388271D01*
X321073Y387921D01*
X320898D01*
Y389521D01*
X321073D01*
G37*
G36*
G01X319408Y400621D02*
X320168Y400271D01*
Y399371D01*
X319408Y399021D01*
X319233D01*
Y400621D01*
X319408D01*
G37*
G36*
G01X321073Y393421D02*
X321833Y393071D01*
Y392171D01*
X321073Y391821D01*
X320898D01*
Y393421D01*
X321073D01*
G37*
G36*
G01X321060Y360020D02*
X321730Y359670D01*
Y358800D01*
X321060Y358450D01*
X320885D01*
Y360020D01*
X321060D01*
G37*
G36*
G01Y352220D02*
X321730Y351870D01*
Y351000D01*
X321060Y350650D01*
X320885D01*
Y352220D01*
X321060D01*
G37*
G36*
G01Y356120D02*
X321730Y355770D01*
Y354900D01*
X321060Y354550D01*
X320885D01*
Y356120D01*
X321060D01*
G37*
G36*
G01Y344420D02*
X321730Y344070D01*
Y343200D01*
X321060Y342850D01*
X320885D01*
Y344420D01*
X321060D01*
G37*
G36*
G01Y348320D02*
X321730Y347970D01*
Y347100D01*
X321060Y346750D01*
X320885D01*
Y348320D01*
X321060D01*
G37*
G36*
G01Y363920D02*
X321730Y363570D01*
Y362700D01*
X321060Y362350D01*
X320885D01*
Y363920D01*
X321060D01*
G37*
G36*
G01Y367845D02*
X321730Y367495D01*
Y366625D01*
X321060Y366275D01*
X320885D01*
Y367845D01*
X321060D01*
G37*
G36*
G01Y371769D02*
X321730Y371419D01*
Y370549D01*
X321060Y370199D01*
X320885D01*
Y371769D01*
X321060D01*
G37*
G36*
G01Y375620D02*
X321730Y375270D01*
Y374400D01*
X321060Y374050D01*
X320885D01*
Y375620D01*
X321060D01*
G37*
G36*
G01X312676Y376049D02*
X312006Y376399D01*
Y377269D01*
X312676Y377619D01*
X312851D01*
Y376049D01*
X312676D01*
G37*
G36*
G01Y383849D02*
X312006Y384199D01*
Y385069D01*
X312676Y385419D01*
X312851D01*
Y383849D01*
X312676D01*
G37*
G36*
G01Y379949D02*
X312006Y380299D01*
Y381169D01*
X312676Y381519D01*
X312851D01*
Y379949D01*
X312676D01*
G37*
G36*
G01X312185Y393945D02*
X311401Y393655D01*
X310764Y394292D01*
X311054Y395076D01*
X311178Y395200D01*
X312309Y394069D01*
X312185Y393945D01*
G37*
G36*
G01X312241Y390781D02*
X311481Y391131D01*
Y392031D01*
X312241Y392381D01*
X312416D01*
Y390781D01*
X312241D01*
G37*
G36*
G01X312676Y356549D02*
X312006Y356899D01*
Y357769D01*
X312676Y358119D01*
X312851D01*
Y356549D01*
X312676D01*
G37*
G36*
G01Y348749D02*
X312006Y349099D01*
Y349969D01*
X312676Y350319D01*
X312851D01*
Y348749D01*
X312676D01*
G37*
G36*
G01Y352649D02*
X312006Y352999D01*
Y353869D01*
X312676Y354219D01*
X312851D01*
Y352649D01*
X312676D01*
G37*
G36*
G01Y344849D02*
X312006Y345199D01*
Y346069D01*
X312676Y346419D01*
X312851D01*
Y344849D01*
X312676D01*
G37*
G36*
G01Y360449D02*
X312006Y360799D01*
Y361669D01*
X312676Y362019D01*
X312851D01*
Y360449D01*
X312676D01*
G37*
G36*
G01Y364349D02*
X312006Y364699D01*
Y365569D01*
X312676Y365919D01*
X312851D01*
Y364349D01*
X312676D01*
G37*
G36*
G01Y368200D02*
X312006Y368550D01*
Y369420D01*
X312676Y369770D01*
X312851D01*
Y368200D01*
X312676D01*
G37*
G36*
G01Y372124D02*
X312006Y372474D01*
Y373344D01*
X312676Y373694D01*
X312851D01*
Y372124D01*
X312676D01*
G37*
G36*
G01X314300Y379520D02*
X314970Y379170D01*
Y378300D01*
X314300Y377950D01*
X314125D01*
Y379520D01*
X314300D01*
G37*
G36*
G01Y383420D02*
X314970Y383070D01*
Y382200D01*
X314300Y381850D01*
X314125D01*
Y383420D01*
X314300D01*
G37*
G36*
G01Y387320D02*
X314970Y386970D01*
Y386100D01*
X314300Y385750D01*
X314125D01*
Y387320D01*
X314300D01*
G37*
G36*
G01X313339Y391381D02*
X314099Y391031D01*
Y390131D01*
X313339Y389781D01*
X313164D01*
Y391381D01*
X313339D01*
G37*
G36*
G01X311831Y395853D02*
X312615Y396143D01*
X313252Y395506D01*
X312962Y394721D01*
X312838Y394598D01*
X311707Y395729D01*
X311831Y395853D01*
G37*
G36*
G01X311639Y399081D02*
X312399Y398731D01*
Y397831D01*
X311639Y397481D01*
X311464D01*
Y399081D01*
X311639D01*
G37*
G36*
G01X314300Y360020D02*
X314970Y359670D01*
Y358800D01*
X314300Y358450D01*
X314125D01*
Y360020D01*
X314300D01*
G37*
G36*
G01Y352220D02*
X314970Y351870D01*
Y351000D01*
X314300Y350650D01*
X314125D01*
Y352220D01*
X314300D01*
G37*
G36*
G01Y356120D02*
X314970Y355770D01*
Y354900D01*
X314300Y354550D01*
X314125D01*
Y356120D01*
X314300D01*
G37*
G36*
G01Y344420D02*
X314970Y344070D01*
Y343200D01*
X314300Y342850D01*
X314125D01*
Y344420D01*
X314300D01*
G37*
G36*
G01Y348320D02*
X314970Y347970D01*
Y347100D01*
X314300Y346750D01*
X314125D01*
Y348320D01*
X314300D01*
G37*
G36*
G01Y363920D02*
X314970Y363570D01*
Y362700D01*
X314300Y362350D01*
X314125D01*
Y363920D01*
X314300D01*
G37*
G36*
G01Y367845D02*
X314970Y367495D01*
Y366625D01*
X314300Y366275D01*
X314125D01*
Y367845D01*
X314300D01*
G37*
G36*
G01Y371769D02*
X314970Y371419D01*
Y370549D01*
X314300Y370199D01*
X314125D01*
Y371769D01*
X314300D01*
G37*
G36*
G01Y375620D02*
X314970Y375270D01*
Y374400D01*
X314300Y374050D01*
X314125D01*
Y375620D01*
X314300D01*
G37*
G36*
G01X326196Y376049D02*
X325526Y376399D01*
Y377269D01*
X326196Y377619D01*
X326371D01*
Y376049D01*
X326196D01*
G37*
G36*
G01X327414Y379587D02*
X326931Y380270D01*
X327381Y381049D01*
X328214Y380972D01*
X328366Y380885D01*
X327565Y379499D01*
X327414Y379587D01*
G37*
G36*
G01X329073Y385145D02*
X328313Y385495D01*
Y386395D01*
X329073Y386745D01*
X329248D01*
Y385145D01*
X329073D01*
G37*
G36*
G01Y389045D02*
X328313Y389395D01*
Y390295D01*
X329073Y390645D01*
X329248D01*
Y389045D01*
X329073D01*
G37*
G36*
G01Y396845D02*
X328313Y397195D01*
Y398095D01*
X329073Y398445D01*
X329248D01*
Y396845D01*
X329073D01*
G37*
G36*
G01Y400745D02*
X328313Y401095D01*
Y401995D01*
X329073Y402345D01*
X329248D01*
Y400745D01*
X329073D01*
G37*
G36*
G01Y392945D02*
X328313Y393295D01*
Y394195D01*
X329073Y394545D01*
X329248D01*
Y392945D01*
X329073D01*
G37*
G36*
G01X326196Y356549D02*
X325526Y356899D01*
Y357769D01*
X326196Y358119D01*
X326371D01*
Y356549D01*
X326196D01*
G37*
G36*
G01Y348749D02*
X325526Y349099D01*
Y349969D01*
X326196Y350319D01*
X326371D01*
Y348749D01*
X326196D01*
G37*
G36*
G01Y352649D02*
X325526Y352999D01*
Y353869D01*
X326196Y354219D01*
X326371D01*
Y352649D01*
X326196D01*
G37*
G36*
G01Y344849D02*
X325526Y345199D01*
Y346069D01*
X326196Y346419D01*
X326371D01*
Y344849D01*
X326196D01*
G37*
G36*
G01Y360449D02*
X325526Y360799D01*
Y361669D01*
X326196Y362019D01*
X326371D01*
Y360449D01*
X326196D01*
G37*
G36*
G01Y364349D02*
X325526Y364699D01*
Y365569D01*
X326196Y365919D01*
X326371D01*
Y364349D01*
X326196D01*
G37*
G36*
G01Y368200D02*
X325526Y368550D01*
Y369420D01*
X326196Y369770D01*
X326371D01*
Y368200D01*
X326196D01*
G37*
G36*
G01Y372124D02*
X325526Y372474D01*
Y373344D01*
X326196Y373694D01*
X326371D01*
Y372124D01*
X326196D01*
G37*
G36*
G01X329166Y380422D02*
X329649Y379739D01*
X329198Y378960D01*
X328365Y379037D01*
X328214Y379125D01*
X329014Y380510D01*
X329166Y380422D01*
G37*
G36*
G01X330171Y386745D02*
X330931Y386395D01*
Y385495D01*
X330171Y385145D01*
X329996D01*
Y386745D01*
X330171D01*
G37*
G36*
G01Y390645D02*
X330931Y390295D01*
Y389395D01*
X330171Y389045D01*
X329996D01*
Y390645D01*
X330171D01*
G37*
G36*
G01Y402345D02*
X330931Y401995D01*
Y401095D01*
X330171Y400745D01*
X329996D01*
Y402345D01*
X330171D01*
G37*
G36*
G01Y394545D02*
X330931Y394195D01*
Y393295D01*
X330171Y392945D01*
X329996D01*
Y394545D01*
X330171D01*
G37*
G36*
G01Y398445D02*
X330931Y398095D01*
Y397195D01*
X330171Y396845D01*
X329996D01*
Y398445D01*
X330171D01*
G37*
G36*
G01X327820Y360020D02*
X328490Y359670D01*
Y358800D01*
X327820Y358450D01*
X327645D01*
Y360020D01*
X327820D01*
G37*
G36*
G01Y352220D02*
X328490Y351870D01*
Y351000D01*
X327820Y350650D01*
X327645D01*
Y352220D01*
X327820D01*
G37*
G36*
G01Y356120D02*
X328490Y355770D01*
Y354900D01*
X327820Y354550D01*
X327645D01*
Y356120D01*
X327820D01*
G37*
G36*
G01Y344420D02*
X328490Y344070D01*
Y343200D01*
X327820Y342850D01*
X327645D01*
Y344420D01*
X327820D01*
G37*
G36*
G01Y348320D02*
X328490Y347970D01*
Y347100D01*
X327820Y346750D01*
X327645D01*
Y348320D01*
X327820D01*
G37*
G36*
G01Y363920D02*
X328490Y363570D01*
Y362700D01*
X327820Y362350D01*
X327645D01*
Y363920D01*
X327820D01*
G37*
G36*
G01Y367845D02*
X328490Y367495D01*
Y366625D01*
X327820Y366275D01*
X327645D01*
Y367845D01*
X327820D01*
G37*
G36*
G01Y371769D02*
X328490Y371419D01*
Y370549D01*
X327820Y370199D01*
X327645D01*
Y371769D01*
X327820D01*
G37*
G36*
G01Y375620D02*
X328490Y375270D01*
Y374400D01*
X327820Y374050D01*
X327645D01*
Y375620D01*
X327820D01*
G37*
G36*
G01X309296Y385750D02*
X308626Y386100D01*
Y386970D01*
X309296Y387320D01*
X309471D01*
Y385750D01*
X309296D01*
G37*
G36*
G01Y381850D02*
X308626Y382200D01*
Y383070D01*
X309296Y383420D01*
X309471D01*
Y381850D01*
X309296D01*
G37*
G36*
G01Y377950D02*
X308626Y378300D01*
Y379170D01*
X309296Y379520D01*
X309471D01*
Y377950D01*
X309296D01*
G37*
G36*
G01X308812Y390358D02*
X308027Y390068D01*
X307391Y390704D01*
X307681Y391489D01*
X307804Y391613D01*
X308936Y390481D01*
X308812Y390358D01*
G37*
G36*
G01X305173Y397190D02*
X304413Y397540D01*
Y398440D01*
X305173Y398790D01*
X305348D01*
Y397190D01*
X305173D01*
G37*
G36*
G01X309296Y358450D02*
X308626Y358800D01*
Y359670D01*
X309296Y360020D01*
X309471D01*
Y358450D01*
X309296D01*
G37*
G36*
G01Y350650D02*
X308626Y351000D01*
Y351870D01*
X309296Y352220D01*
X309471D01*
Y350650D01*
X309296D01*
G37*
G36*
G01Y354550D02*
X308626Y354900D01*
Y355770D01*
X309296Y356120D01*
X309471D01*
Y354550D01*
X309296D01*
G37*
G36*
G01Y342850D02*
X308626Y343200D01*
Y344070D01*
X309296Y344420D01*
X309471D01*
Y342850D01*
X309296D01*
G37*
G36*
G01Y346750D02*
X308626Y347100D01*
Y347970D01*
X309296Y348320D01*
X309471D01*
Y346750D01*
X309296D01*
G37*
G36*
G01Y366275D02*
X308626Y366625D01*
Y367495D01*
X309296Y367845D01*
X309471D01*
Y366275D01*
X309296D01*
G37*
G36*
G01Y362350D02*
X308626Y362700D01*
Y363570D01*
X309296Y363920D01*
X309471D01*
Y362350D01*
X309296D01*
G37*
G36*
G01Y374050D02*
X308626Y374400D01*
Y375270D01*
X309296Y375620D01*
X309471D01*
Y374050D01*
X309296D01*
G37*
G36*
G01Y370199D02*
X308626Y370549D01*
Y371419D01*
X309296Y371769D01*
X309471D01*
Y370199D01*
X309296D01*
G37*
G36*
G01X310920Y377619D02*
X311590Y377269D01*
Y376399D01*
X310920Y376049D01*
X310745D01*
Y377619D01*
X310920D01*
G37*
G36*
G01Y381519D02*
X311590Y381169D01*
Y380299D01*
X310920Y379949D01*
X310745D01*
Y381519D01*
X310920D01*
G37*
G36*
G01Y385419D02*
X311590Y385069D01*
Y384199D01*
X310920Y383849D01*
X310745D01*
Y385419D01*
X310920D01*
G37*
G36*
G01X308457Y392265D02*
X309242Y392555D01*
X309878Y391919D01*
X309588Y391134D01*
X309465Y391010D01*
X308333Y392142D01*
X308457Y392265D01*
G37*
G36*
G01X306271Y398790D02*
X307031Y398440D01*
Y397540D01*
X306271Y397190D01*
X306096D01*
Y398790D01*
X306271D01*
G37*
G36*
G01X310920Y358119D02*
X311590Y357769D01*
Y356899D01*
X310920Y356549D01*
X310745D01*
Y358119D01*
X310920D01*
G37*
G36*
G01Y350319D02*
X311590Y349969D01*
Y349099D01*
X310920Y348749D01*
X310745D01*
Y350319D01*
X310920D01*
G37*
G36*
G01Y354219D02*
X311590Y353869D01*
Y352999D01*
X310920Y352649D01*
X310745D01*
Y354219D01*
X310920D01*
G37*
G36*
G01Y346419D02*
X311590Y346069D01*
Y345199D01*
X310920Y344849D01*
X310745D01*
Y346419D01*
X310920D01*
G37*
G36*
G01Y362019D02*
X311590Y361669D01*
Y360799D01*
X310920Y360449D01*
X310745D01*
Y362019D01*
X310920D01*
G37*
G36*
G01Y365919D02*
X311590Y365569D01*
Y364699D01*
X310920Y364349D01*
X310745D01*
Y365919D01*
X310920D01*
G37*
G36*
G01Y369770D02*
X311590Y369420D01*
Y368550D01*
X310920Y368200D01*
X310745D01*
Y369770D01*
X310920D01*
G37*
G36*
G01Y373694D02*
X311590Y373344D01*
Y372474D01*
X310920Y372124D01*
X310745D01*
Y373694D01*
X310920D01*
G37*
G36*
G01X321773Y397501D02*
X321013Y397851D01*
Y398751D01*
X321773Y399101D01*
X321948D01*
Y397501D01*
X321773D01*
G37*
G36*
G01X323518Y381913D02*
X322758Y382263D01*
Y383163D01*
X323518Y383513D01*
X323693D01*
Y381913D01*
X323518D01*
G37*
G36*
G01X322816Y377950D02*
X322146Y378300D01*
Y379170D01*
X322816Y379520D01*
X322991D01*
Y377950D01*
X322816D01*
G37*
G36*
G01X322773Y389301D02*
X322013Y389651D01*
Y390551D01*
X322773Y390901D01*
X322948D01*
Y389301D01*
X322773D01*
G37*
G36*
G01Y393201D02*
X322013Y393551D01*
Y394451D01*
X322773Y394801D01*
X322948D01*
Y393201D01*
X322773D01*
G37*
G36*
G01X322816Y358450D02*
X322146Y358800D01*
Y359670D01*
X322816Y360020D01*
X322991D01*
Y358450D01*
X322816D01*
G37*
G36*
G01Y350650D02*
X322146Y351000D01*
Y351870D01*
X322816Y352220D01*
X322991D01*
Y350650D01*
X322816D01*
G37*
G36*
G01Y354550D02*
X322146Y354900D01*
Y355770D01*
X322816Y356120D01*
X322991D01*
Y354550D01*
X322816D01*
G37*
G36*
G01Y342850D02*
X322146Y343200D01*
Y344070D01*
X322816Y344420D01*
X322991D01*
Y342850D01*
X322816D01*
G37*
G36*
G01Y346750D02*
X322146Y347100D01*
Y347970D01*
X322816Y348320D01*
X322991D01*
Y346750D01*
X322816D01*
G37*
G36*
G01Y366275D02*
X322146Y366625D01*
Y367495D01*
X322816Y367845D01*
X322991D01*
Y366275D01*
X322816D01*
G37*
G36*
G01Y370199D02*
X322146Y370549D01*
Y371419D01*
X322816Y371769D01*
X322991D01*
Y370199D01*
X322816D01*
G37*
G36*
G01Y374050D02*
X322146Y374400D01*
Y375270D01*
X322816Y375620D01*
X322991D01*
Y374050D01*
X322816D01*
G37*
G36*
G01Y362350D02*
X322146Y362700D01*
Y363570D01*
X322816Y363920D01*
X322991D01*
Y362350D01*
X322816D01*
G37*
G36*
G01X324440Y377619D02*
X325110Y377269D01*
Y376399D01*
X324440Y376049D01*
X324265D01*
Y377619D01*
X324440D01*
G37*
G36*
G01X324616Y383513D02*
X325376Y383163D01*
Y382263D01*
X324616Y381913D01*
X324441D01*
Y383513D01*
X324616D01*
G37*
G36*
G01X323871Y390901D02*
X324631Y390551D01*
Y389651D01*
X323871Y389301D01*
X323696D01*
Y390901D01*
X323871D01*
G37*
G36*
G01Y394801D02*
X324631Y394451D01*
Y393551D01*
X323871Y393201D01*
X323696D01*
Y394801D01*
X323871D01*
G37*
G36*
G01X322871Y399101D02*
X323631Y398751D01*
Y397851D01*
X322871Y397501D01*
X322696D01*
Y399101D01*
X322871D01*
G37*
G36*
G01X324440Y358119D02*
X325110Y357769D01*
Y356899D01*
X324440Y356549D01*
X324265D01*
Y358119D01*
X324440D01*
G37*
G36*
G01Y350319D02*
X325110Y349969D01*
Y349099D01*
X324440Y348749D01*
X324265D01*
Y350319D01*
X324440D01*
G37*
G36*
G01Y354219D02*
X325110Y353869D01*
Y352999D01*
X324440Y352649D01*
X324265D01*
Y354219D01*
X324440D01*
G37*
G36*
G01Y346419D02*
X325110Y346069D01*
Y345199D01*
X324440Y344849D01*
X324265D01*
Y346419D01*
X324440D01*
G37*
G36*
G01Y362019D02*
X325110Y361669D01*
Y360799D01*
X324440Y360449D01*
X324265D01*
Y362019D01*
X324440D01*
G37*
G36*
G01Y365919D02*
X325110Y365569D01*
Y364699D01*
X324440Y364349D01*
X324265D01*
Y365919D01*
X324440D01*
G37*
G36*
G01Y369770D02*
X325110Y369420D01*
Y368550D01*
X324440Y368200D01*
X324265D01*
Y369770D01*
X324440D01*
G37*
G36*
G01Y373694D02*
X325110Y373344D01*
Y372474D01*
X324440Y372124D01*
X324265D01*
Y373694D01*
X324440D01*
G37*
G36*
G01X296009Y403918D02*
X295225Y403628D01*
X294588Y404265D01*
X294878Y405049D01*
X295002Y405173D01*
X296133Y404042D01*
X296009Y403918D01*
G37*
G36*
G01X295655Y405826D02*
X296440Y406116D01*
X297076Y405480D01*
X296786Y404695D01*
X296663Y404571D01*
X295531Y405703D01*
X295655Y405826D01*
G37*
G36*
G01X319193Y404521D02*
X318433Y404871D01*
Y405771D01*
X319193Y406121D01*
X319368D01*
Y404521D01*
X319193D01*
G37*
G36*
G01X320293Y406121D02*
X321053Y405771D01*
Y404871D01*
X320293Y404521D01*
X320118D01*
Y406121D01*
X320293D01*
G37*
G36*
G01X466158Y-13158D02*
X464720Y-11720D01*
G02X464949Y-11041I283J283D01*
G03X465783Y-8695I-191J1389D01*
G02X465798Y-8134I292J273D01*
G03X465826Y-5993I-1040J1084D01*
G02X465820Y-5436I284J282D01*
G03X465773Y-3318I-1088J1035D01*
G02X465757Y-2757I277J289D01*
G03X463707I-1025J956D01*
G02X463691Y-3318I-293J-272D01*
G03X463664Y-5458I1041J-1083D01*
G02X463670Y-6015I-284J-282D01*
G03X463718Y-8134I1088J-1035D01*
G02X463733Y-8695I-277J-288D01*
G03X463369Y-9461I1025J-957D01*
G02X462690Y-9690I-396J54D01*
G01X461801Y-8801D01*
X461934Y-8660D01*
G03X459697Y-7000I-1022J960D01*
G01X455647D01*
G03X453419I-1114J-851D01*
G01X449143D01*
X449106Y-6847D01*
G03X446382I-1362J-333D01*
G01X446345Y-7000D01*
X436247D01*
X436216Y-6838D01*
G03X433464I-1376J-270D01*
G01X433433Y-7000D01*
X429554D01*
X429523Y-6838D01*
G03X426771I-1376J-270D01*
G01X426740Y-7000D01*
X422961D01*
X422931Y-6836D01*
G03X419977I-1477J-272D01*
G01X419947Y-7000D01*
X416268D01*
X416238Y-6836D01*
G03X413284I-1477J-272D01*
G01X413254Y-7000D01*
X409575D01*
X409545Y-6836D01*
G03X406591I-1477J-272D01*
G01X406561Y-7000D01*
X402782D01*
X402751Y-6838D01*
G03X399999I-1376J-270D01*
G01X399968Y-7000D01*
X399000D01*
X397509Y-8491D01*
X397470Y-8507D01*
G03X396635Y-9342I559J-1394D01*
G01X396619Y-9381D01*
X396260Y-9740D01*
G02X395581Y-9511I-283J283D01*
G03X394003Y-11089I-1389J-189D01*
G02X394232Y-11768I-54J-396D01*
G01X394000Y-12000D01*
X390409D01*
G02X390187Y-11267I0J400D01*
G03X391788Y-8272I-2001J2995D01*
G01Y-3372D01*
G03X384586I-3601J0D01*
G01Y-8272D01*
G03X386187Y-11267I3602J0D01*
G02X385965Y-12000I-222J-333D01*
G01X381892D01*
G02X381524Y-11445I1J400D01*
G03X379212Y-9938I-1292J545D01*
G02X378626Y-9933I-291J275D01*
G03X376307Y-11440I-1034J-947D01*
G02X375940Y-12000I-367J-160D01*
G01X375737D01*
Y-11771D01*
X375746Y-11743D01*
G03X373013Y-11544I-1345J397D01*
G02X372617Y-12000I-396J-56D01*
G01X370500D01*
X369078Y-10578D01*
X369148Y-10447D01*
G03X367901Y-8384I-1237J661D01*
G02X367700Y-8184I-1J200D01*
G01Y-3460D01*
G02X367901Y-3260I200J0D01*
G03Y-456I10J1402D01*
G02X367700Y-256I-1J200D01*
G01Y7512D01*
G02X367901Y7712I200J0D01*
G03Y10516I10J1402D01*
G02X367700Y10716I-1J200D01*
G01Y15440D01*
G02X367901Y15640I200J0D01*
G03Y18444I10J1402D01*
G02X367700Y18644I-1J200D01*
G01Y21500D01*
X371200Y25000D01*
X379380D01*
X379395Y24817D01*
G03X382189I1397J116D01*
G01X382204Y25000D01*
X476500D01*
X482168Y19332D01*
G02X481844Y18651I-283J-283D01*
G03X483185Y17310I-153J-1494D01*
G02X483866Y17634I398J41D01*
G01X484708Y16792D01*
G02X484561Y16133I-283J-283D01*
G03X484051Y13817I476J-1319D01*
G02X484037Y13234I-281J-285D01*
G03X486037I1000J-1120D01*
G02X486023Y13817I267J298D01*
G03X486356Y14338I-986J997D01*
G02X487015Y14485I376J-136D01*
G01X490118Y11382D01*
X490131Y11359D01*
G03X490675Y10815I1299J755D01*
G01X490698Y10802D01*
X493700Y7800D01*
X494437D01*
X494469Y7789D01*
G03X495385I458J1325D01*
G01X495417Y7800D01*
X501013D01*
X501047Y7787D01*
G03X502041I497J1311D01*
G01X502075Y7800D01*
X511319D01*
X511351Y7789D01*
G03X512267I458J1325D01*
G01X512299Y7800D01*
X518012D01*
X518044Y7789D01*
G03X518960I458J1325D01*
G01X518992Y7800D01*
X520300D01*
X526445Y13945D01*
G02X527053Y13896I283J-283D01*
G03X527184Y13738I1142J813D01*
G02X527180Y13177I-287J-278D01*
G03X529261Y13217I1061J-1063D01*
G02X529234Y13778I271J294D01*
G03X529009Y15852I-1043J936D01*
G02X528960Y16460I234J325D01*
G01X529716Y17216D01*
G02X530396Y16981I283J-283D01*
G03X532064Y18649I1492J176D01*
G02X531829Y19329I48J397D01*
G01X538800Y26300D01*
X635698D01*
G03X639888I2095J5678D01*
G01X650100D01*
X652100Y24300D01*
Y21757D01*
G02X651611Y21367I-400J0D01*
G03X650290Y19027I-311J-1367D01*
G02Y18473I-288J-277D01*
G03X651611Y16133I1010J-973D01*
G02X652100Y15743I89J-390D01*
G01Y13042D01*
X651598Y12540D01*
Y8398D01*
X649000Y5800D01*
X631300D01*
X630678Y5178D01*
X629064D01*
X624644Y758D01*
X624578Y749D01*
G03X623437Y-1075I192J-1389D01*
G02X623044Y-1599I-380J-124D01*
G03X621727Y-3588I-44J-1401D01*
G01X621786Y-3714D01*
X620897Y-4603D01*
X620771Y-4545D01*
G03X618915Y-6401I-579J-1277D01*
G01X618973Y-6527D01*
X616573Y-8927D01*
X616433Y-8813D01*
G03X614461Y-10785I-884J-1088D01*
G01X614575Y-10925D01*
X612342Y-13158D01*
X466158D01*
G37*
G36*
G01X414917Y213658D02*
X414250Y213303D01*
X413533Y213795D01*
X413623Y214545D01*
X413721Y214690D01*
X415016Y213801D01*
X414917Y213658D01*
G37*
G36*
G01X416597Y209537D02*
X415927Y209887D01*
Y210757D01*
X416597Y211107D01*
X416772D01*
Y209537D01*
X416597D01*
G37*
G36*
G01X414016Y200048D02*
X413256Y200398D01*
Y201298D01*
X414016Y201648D01*
X414191D01*
Y200048D01*
X414016D01*
G37*
G36*
G01X411023Y207850D02*
X410263Y208200D01*
Y209100D01*
X411023Y209450D01*
X411198D01*
Y207850D01*
X411023D01*
G37*
G36*
G01Y211750D02*
X410263Y212100D01*
Y213000D01*
X411023Y213350D01*
X411198D01*
Y211750D01*
X411023D01*
G37*
G36*
G01Y217250D02*
X410263Y217600D01*
Y218500D01*
X411023Y218850D01*
X411198D01*
Y217250D01*
X411023D01*
G37*
G36*
G01X412123Y218850D02*
X412883Y218500D01*
Y217600D01*
X412123Y217250D01*
X411948D01*
Y218850D01*
X412123D01*
G37*
G36*
G01Y209450D02*
X412883Y209100D01*
Y208200D01*
X412123Y207850D01*
X411948D01*
Y209450D01*
X412123D01*
G37*
G36*
G01Y213350D02*
X412883Y213000D01*
Y212100D01*
X412123Y211750D01*
X411948D01*
Y213350D01*
X412123D01*
G37*
G36*
G01X415114Y201648D02*
X415874Y201298D01*
Y200398D01*
X415114Y200048D01*
X414939D01*
Y201648D01*
X415114D01*
G37*
G36*
G01X412691Y225201D02*
X412401Y225986D01*
X413038Y226622D01*
X413823Y226332D01*
X413946Y226208D01*
X412815Y225077D01*
X412691Y225201D01*
G37*
G36*
G01X411023Y221150D02*
X410263Y221500D01*
Y222400D01*
X411023Y222750D01*
X411198D01*
Y221150D01*
X411023D01*
G37*
G36*
G01X412123Y222750D02*
X412883Y222400D01*
Y221500D01*
X412123Y221150D01*
X411948D01*
Y222750D01*
X412123D01*
G37*
G36*
G01X413896Y224844D02*
X414186Y224059D01*
X413550Y223423D01*
X412765Y223713D01*
X412641Y223836D01*
X413773Y224968D01*
X413896Y224844D01*
G37*
G36*
G01X629900Y570700D02*
X622900Y577700D01*
Y595700D01*
X620200Y598400D01*
X487000D01*
X483400Y594800D01*
Y594716D01*
X483247Y594563D01*
G02X482939Y594593I-142J141D01*
G03X481201Y592337I-1248J-836D01*
G01X481335Y592291D01*
Y587077D01*
X481205Y587029D01*
G03X481029Y584478I486J-1315D01*
G02X481123Y583843I-189J-352D01*
G01X478742Y581462D01*
X382058D01*
X378487Y585032D01*
X373235D01*
X371759Y583556D01*
X369644D01*
X368030Y585170D01*
X368106Y585303D01*
G03X366664Y587384I-1216J697D01*
G02X366200Y587778I-64J395D01*
G01Y592431D01*
G03X366394Y592601I-889J1211D01*
G02X366955Y592617I289J-277D01*
G03Y594667I956J1025D01*
G02X366394Y594683I-272J293D01*
G03X366200Y594853I-1083J-1041D01*
G01Y603378D01*
G02X366891Y603652I400J0D01*
G03Y605576I1020J962D01*
G02X366200Y605850I-291J274D01*
G01Y610050D01*
G02X366726Y610429I400J-1D01*
G03Y613089I444J1330D01*
G02X366200Y613468I-126J380D01*
G01Y614900D01*
X366630Y615330D01*
X451133D01*
X456258Y620454D01*
Y620858D01*
X457409Y622009D01*
X457446Y622025D01*
G03X458205Y622784I-536J1295D01*
G01X458221Y622821D01*
X459950Y624550D01*
X666709D01*
X668672Y622587D01*
Y620015D01*
X667200Y618543D01*
X663688D01*
X661500Y616355D01*
Y599748D01*
G02X660907Y599398I-400J0D01*
G03Y596942I-677J-1228D01*
G02X661500Y596592I193J-350D01*
G01Y590316D01*
X661387Y590261D01*
G03Y587739I613J-1261D01*
G01X661500Y587684D01*
Y574100D01*
X658562Y571162D01*
X658512Y571147D01*
G03X657825Y570700I388J-1347D01*
G01X643848D01*
X643843Y570895D01*
G03X631743I-6050J-140D01*
G01X631738Y570700D01*
X629900D01*
G37*
G36*
G01X421141Y189202D02*
X420381Y189552D01*
Y190452D01*
X421141Y190802D01*
X421316D01*
Y189202D01*
X421141D01*
G37*
G36*
G01X420022Y194453D02*
X419262Y194803D01*
Y195703D01*
X420022Y196053D01*
X420197D01*
Y194453D01*
X420022D01*
G37*
G36*
G01X419362Y198098D02*
X418578Y197808D01*
X417941Y198445D01*
X418231Y199229D01*
X418355Y199353D01*
X419486Y198222D01*
X419362Y198098D01*
G37*
G36*
G01X417034Y201877D02*
X416274Y202227D01*
Y203127D01*
X417034Y203477D01*
X417209D01*
Y201877D01*
X417034D01*
G37*
G36*
G01X421141Y185302D02*
X420381Y185652D01*
Y186552D01*
X421141Y186902D01*
X421316D01*
Y185302D01*
X421141D01*
G37*
G36*
G01X417034Y205777D02*
X416274Y206127D01*
Y207027D01*
X417034Y207377D01*
X417209D01*
Y205777D01*
X417034D01*
G37*
G36*
G01X422239Y190802D02*
X422999Y190452D01*
Y189552D01*
X422239Y189202D01*
X422064D01*
Y190802D01*
X422239D01*
G37*
G36*
G01X421121Y196053D02*
X421881Y195703D01*
Y194803D01*
X421121Y194453D01*
X420946D01*
Y196053D01*
X421121D01*
G37*
G36*
G01X418502Y200515D02*
X419287Y200805D01*
X419924Y200169D01*
X419634Y199384D01*
X419510Y199260D01*
X418379Y200391D01*
X418502Y200515D01*
G37*
G36*
G01X418132Y203477D02*
X418892Y203127D01*
Y202227D01*
X418132Y201877D01*
X417957D01*
Y203477D01*
X418132D01*
G37*
G36*
G01X422239Y186902D02*
X422999Y186552D01*
Y185652D01*
X422239Y185302D01*
X422064D01*
Y186902D01*
X422239D01*
G37*
G36*
G01X418132Y207377D02*
X418892Y207027D01*
Y206127D01*
X418132Y205777D01*
X417957D01*
Y207377D01*
X418132D01*
G37*
G36*
G01X418201Y213023D02*
X418871Y212673D01*
Y211803D01*
X418200Y211453D01*
X418025D01*
X418026Y213023D01*
X418201D01*
G37*
G36*
G01X432153Y196547D02*
X431393Y196897D01*
Y197797D01*
X432153Y198147D01*
X432328D01*
Y196547D01*
X432153D01*
G37*
G36*
G01X435192Y188413D02*
X434407Y188123D01*
X433771Y188760D01*
X434061Y189545D01*
X434185Y189668D01*
X435316Y188537D01*
X435192Y188413D01*
G37*
G36*
G01X432153Y201347D02*
X431393Y201697D01*
Y202597D01*
X432153Y202947D01*
X432328D01*
Y201347D01*
X432153D01*
G37*
G36*
G01X437950Y185656D02*
X437165Y185366D01*
X436529Y186002D01*
X436819Y186787D01*
X436942Y186911D01*
X438074Y185779D01*
X437950Y185656D01*
G37*
G36*
G01X440708Y182898D02*
X439923Y182608D01*
X439286Y183244D01*
X439576Y184029D01*
X439700Y184153D01*
X440831Y183022D01*
X440708Y182898D01*
G37*
G36*
G01X430754Y208704D02*
X429994Y209054D01*
Y209954D01*
X430754Y210304D01*
X430929D01*
Y208704D01*
X430754D01*
G37*
G36*
G01X430231Y217326D02*
X429561Y217676D01*
Y218546D01*
X430231Y218896D01*
X430406D01*
Y217326D01*
X430231D01*
G37*
G36*
G01Y213419D02*
X429561Y213769D01*
Y214639D01*
X430231Y214989D01*
X430406D01*
Y213419D01*
X430231D01*
G37*
G36*
G01X434837Y190321D02*
X435622Y190611D01*
X436259Y189975D01*
X435969Y189190D01*
X435845Y189066D01*
X434714Y190197D01*
X434837Y190321D01*
G37*
G36*
G01X433253Y198147D02*
X434013Y197797D01*
Y196897D01*
X433253Y196547D01*
X433078D01*
Y198147D01*
X433253D01*
G37*
G36*
G01Y202947D02*
X434013Y202597D01*
Y201697D01*
X433253Y201347D01*
X433078D01*
Y202947D01*
X433253D01*
G37*
G36*
G01X440353Y184806D02*
X441138Y185096D01*
X441774Y184459D01*
X441484Y183674D01*
X441360Y183551D01*
X440229Y184682D01*
X440353Y184806D01*
G37*
G36*
G01X437595Y187563D02*
X438380Y187853D01*
X439016Y187217D01*
X438726Y186432D01*
X438603Y186308D01*
X437471Y187440D01*
X437595Y187563D01*
G37*
G36*
G01X431852Y210304D02*
X432612Y209954D01*
Y209054D01*
X431852Y208704D01*
X431677D01*
Y210304D01*
X431852D01*
G37*
G36*
G01X431856Y217017D02*
X432526Y216667D01*
Y215797D01*
X431856Y215447D01*
X431681D01*
Y217017D01*
X431856D01*
G37*
G36*
G01X417003Y193322D02*
X416243Y193672D01*
Y194572D01*
X417003Y194922D01*
X417178D01*
Y193322D01*
X417003D01*
G37*
G36*
G01X418123Y187622D02*
X417363Y187972D01*
Y188872D01*
X418123Y189222D01*
X418298D01*
Y187622D01*
X418123D01*
G37*
G36*
G01Y183722D02*
X417363Y184072D01*
Y184972D01*
X418123Y185322D01*
X418298D01*
Y183722D01*
X418123D01*
G37*
G36*
G01X418102Y194922D02*
X418862Y194572D01*
Y193672D01*
X418102Y193322D01*
X417927D01*
Y194922D01*
X418102D01*
G37*
G36*
G01X419221Y189222D02*
X419981Y188872D01*
Y187972D01*
X419221Y187622D01*
X419046D01*
Y189222D01*
X419221D01*
G37*
G36*
G01Y185322D02*
X419981Y184972D01*
Y184072D01*
X419221Y183722D01*
X419046D01*
Y185322D01*
X419221D01*
G37*
G36*
G01X429133Y196747D02*
X428373Y197097D01*
Y197997D01*
X429133Y198347D01*
X429308D01*
Y196747D01*
X429133D01*
G37*
G36*
G01Y200647D02*
X428373Y200997D01*
Y201897D01*
X429133Y202247D01*
X429308D01*
Y200647D01*
X429133D01*
G37*
G36*
G01X432581Y186757D02*
X431796Y186467D01*
X431160Y187103D01*
X431450Y187888D01*
X431573Y188012D01*
X432705Y186880D01*
X432581Y186757D01*
G37*
G36*
G01X435339Y183999D02*
X434554Y183709D01*
X433918Y184345D01*
X434208Y185130D01*
X434331Y185254D01*
X435463Y184122D01*
X435339Y183999D01*
G37*
G36*
G01X426852Y211509D02*
X426182Y211859D01*
Y212729D01*
X426852Y213079D01*
X427027D01*
Y211509D01*
X426852D01*
G37*
G36*
G01Y215411D02*
X426182Y215761D01*
Y216631D01*
X426852Y216981D01*
X427027D01*
Y215411D01*
X426852D01*
G37*
G36*
G01X427744Y207154D02*
X426984Y207504D01*
Y208404D01*
X427744Y208754D01*
X427919D01*
Y207154D01*
X427744D01*
G37*
G36*
G01X430233Y198347D02*
X430993Y197997D01*
Y197097D01*
X430233Y196747D01*
X430058D01*
Y198347D01*
X430233D01*
G37*
G36*
G01X432226Y188664D02*
X433011Y188954D01*
X433647Y188318D01*
X433357Y187533D01*
X433234Y187409D01*
X432102Y188541D01*
X432226Y188664D01*
G37*
G36*
G01X430233Y202247D02*
X430993Y201897D01*
Y200997D01*
X430233Y200647D01*
X430058D01*
Y202247D01*
X430233D01*
G37*
G36*
G01X434984Y185906D02*
X435769Y186196D01*
X436405Y185560D01*
X436115Y184775D01*
X435992Y184651D01*
X434860Y185783D01*
X434984Y185906D01*
G37*
G36*
G01X428476Y218930D02*
X429146Y218580D01*
Y217710D01*
X428476Y217360D01*
X428301D01*
Y218930D01*
X428476D01*
G37*
G36*
G01Y215030D02*
X429146Y214680D01*
Y213810D01*
X428476Y213460D01*
X428301D01*
Y215030D01*
X428476D01*
G37*
G36*
G01X428844Y208754D02*
X429604Y208404D01*
Y207504D01*
X428844Y207154D01*
X428669D01*
Y208754D01*
X428844D01*
G37*
G36*
G01X471509Y204532D02*
X470754Y204500D01*
X470319Y205253D01*
X470724Y205891D01*
X470876Y205979D01*
X471660Y204619D01*
X471509Y204532D01*
G37*
G36*
G01X470790Y217326D02*
X470120Y217676D01*
Y218546D01*
X470790Y218896D01*
X470965D01*
Y217326D01*
X470790D01*
G37*
G36*
G01Y213437D02*
X470120Y213787D01*
Y214657D01*
X470790Y215007D01*
X470965D01*
Y213437D01*
X470790D01*
G37*
G36*
G01Y209537D02*
X470120Y209887D01*
Y210757D01*
X470790Y211107D01*
X470965D01*
Y209537D01*
X470790D01*
G37*
G36*
G01X473581Y205172D02*
X474181Y205632D01*
X474969Y205264D01*
X475003Y204509D01*
X474929Y204350D01*
X473507Y205014D01*
X473581Y205172D01*
G37*
G36*
G01X472414Y209206D02*
X473084Y208856D01*
Y207986D01*
X472414Y207636D01*
X472239D01*
Y209206D01*
X472414D01*
G37*
G36*
G01X472415Y217017D02*
X473085Y216667D01*
Y215797D01*
X472415Y215447D01*
X472240D01*
Y217017D01*
X472415D01*
G37*
G36*
G01X472414Y213106D02*
X473084Y212756D01*
Y211886D01*
X472414Y211536D01*
X472239D01*
Y213106D01*
X472414D01*
G37*
G36*
G01X468117Y202603D02*
X467362Y202571D01*
X466927Y203324D01*
X467332Y203962D01*
X467484Y204050D01*
X468268Y202690D01*
X468117Y202603D01*
G37*
G36*
G01X467410Y207636D02*
X466740Y207986D01*
Y208856D01*
X467410Y209206D01*
X467585D01*
Y207636D01*
X467410D01*
G37*
G36*
G01X467411Y215436D02*
X466741Y215786D01*
Y216656D01*
X467411Y217006D01*
X467586D01*
Y215436D01*
X467411D01*
G37*
G36*
G01X467410Y211547D02*
X466740Y211897D01*
Y212767D01*
X467410Y213117D01*
X467585D01*
Y211547D01*
X467410D01*
G37*
G36*
G01X469035Y207231D02*
X469705Y206881D01*
Y206011D01*
X469035Y205661D01*
X468860D01*
Y207231D01*
X469035D01*
G37*
G36*
G01Y218907D02*
X469705Y218557D01*
Y217687D01*
X469035Y217337D01*
X468860D01*
Y218907D01*
X469035D01*
G37*
G36*
G01Y214996D02*
X469705Y214646D01*
Y213776D01*
X469035Y213426D01*
X468860D01*
Y214996D01*
X469035D01*
G37*
G36*
G01Y211096D02*
X469705Y210746D01*
Y209876D01*
X469035Y209526D01*
X468860D01*
Y211096D01*
X469035D01*
G37*
G36*
G01X425309Y190548D02*
X426069Y190198D01*
Y189298D01*
X425309Y188948D01*
X425134D01*
Y190548D01*
X425309D01*
G37*
G36*
G01X424193Y196937D02*
X424953Y196587D01*
Y195687D01*
X424193Y195337D01*
X424018D01*
Y196937D01*
X424193D01*
G37*
G36*
G01X422020Y203634D02*
X422805Y203924D01*
X423441Y203288D01*
X423151Y202503D01*
X423028Y202379D01*
X421896Y203511D01*
X422020Y203634D01*
G37*
G36*
G01X424193Y200837D02*
X424953Y200487D01*
Y199587D01*
X424193Y199237D01*
X424018D01*
Y200837D01*
X424193D01*
G37*
G36*
G01X426437Y185867D02*
X427222Y186157D01*
X427858Y185521D01*
X427568Y184736D01*
X427445Y184612D01*
X426313Y185744D01*
X426437Y185867D01*
G37*
G36*
G01X428801Y182452D02*
X429561Y182102D01*
Y181202D01*
X428801Y180852D01*
X428626D01*
Y182452D01*
X428801D01*
G37*
G36*
G01X419821Y216785D02*
X420459Y217190D01*
X421212Y216755D01*
X421180Y216000D01*
X421093Y215849D01*
X419733Y216633D01*
X419821Y216785D01*
G37*
G36*
G01X421714Y212798D02*
X422474Y212448D01*
Y211548D01*
X421714Y211198D01*
X421539D01*
Y212798D01*
X421714D01*
G37*
G36*
G01X421231Y207295D02*
X421991Y206945D01*
Y206045D01*
X421231Y205695D01*
X421056D01*
Y207295D01*
X421231D01*
G37*
G36*
G01X475794Y218907D02*
X476464Y218557D01*
Y217687D01*
X475794Y217337D01*
X475619D01*
Y218907D01*
X475794D01*
G37*
G36*
G01Y215007D02*
X476464Y214657D01*
Y213787D01*
X475794Y213437D01*
X475619D01*
Y215007D01*
X475794D01*
G37*
G36*
G01Y211107D02*
X476464Y210757D01*
Y209887D01*
X475794Y209537D01*
X475619D01*
Y211107D01*
X475794D01*
G37*
G36*
G01X477280Y207033D02*
X477918Y207438D01*
X478671Y207003D01*
X478639Y206248D01*
X478552Y206096D01*
X477192Y206882D01*
X477280Y207033D01*
G37*
G36*
G01X426113Y195468D02*
X425353Y195818D01*
Y196718D01*
X426113Y197068D01*
X426288D01*
Y195468D01*
X426113D01*
G37*
G36*
G01Y199368D02*
X425353Y199718D01*
Y200618D01*
X426113Y200968D01*
X426288D01*
Y199368D01*
X426113D01*
G37*
G36*
G01X425393Y202976D02*
X424609Y202686D01*
X423972Y203323D01*
X424262Y204107D01*
X424386Y204231D01*
X425517Y203100D01*
X425393Y202976D01*
G37*
G36*
G01X428769Y186297D02*
X427985Y186007D01*
X427348Y186644D01*
X427638Y187428D01*
X427762Y187552D01*
X428893Y186421D01*
X428769Y186297D01*
G37*
G36*
G01X431527Y183539D02*
X430743Y183249D01*
X430106Y183886D01*
X430396Y184670D01*
X430520Y184794D01*
X431651Y183663D01*
X431527Y183539D01*
G37*
G36*
G01X421985Y217560D02*
X421348Y217155D01*
X420594Y217589D01*
X420626Y218344D01*
X420714Y218497D01*
X422073Y217711D01*
X421985Y217560D01*
G37*
G36*
G01X423994Y209603D02*
X423234Y209953D01*
Y210853D01*
X423994Y211203D01*
X424169D01*
Y209603D01*
X423994D01*
G37*
G36*
G01Y213503D02*
X423234Y213853D01*
Y214753D01*
X423994Y215103D01*
X424169D01*
Y213503D01*
X423994D01*
G37*
G36*
G01X423093Y197137D02*
X422333Y197487D01*
Y198387D01*
X423093Y198737D01*
X423268D01*
Y197137D01*
X423093D01*
G37*
G36*
G01X424209Y188948D02*
X423449Y189298D01*
Y190198D01*
X424209Y190548D01*
X424384D01*
Y188948D01*
X424209D01*
G37*
G36*
G01X423093Y193237D02*
X422333Y193587D01*
Y194487D01*
X423093Y194837D01*
X423268D01*
Y193237D01*
X423093D01*
G37*
G36*
G01X421973Y202125D02*
X421189Y201835D01*
X420552Y202472D01*
X420842Y203256D01*
X420966Y203380D01*
X422097Y202249D01*
X421973Y202125D01*
G37*
G36*
G01X426790Y183958D02*
X426006Y183668D01*
X425369Y184305D01*
X425659Y185089D01*
X425783Y185213D01*
X426914Y184082D01*
X426790Y183958D01*
G37*
G36*
G01X427701Y180852D02*
X426941Y181202D01*
Y182102D01*
X427701Y182452D01*
X427876D01*
Y180852D01*
X427701D01*
G37*
G36*
G01X418617Y215585D02*
X417967Y215199D01*
X417226Y215655D01*
X417279Y216409D01*
X417371Y216558D01*
X418708Y215734D01*
X418617Y215585D01*
G37*
G36*
G01X420614Y211198D02*
X419854Y211548D01*
Y212448D01*
X420614Y212798D01*
X420789D01*
Y211198D01*
X420614D01*
G37*
G36*
G01X420131Y205695D02*
X419371Y206045D01*
Y206945D01*
X420131Y207295D01*
X420306D01*
Y205695D01*
X420131D01*
G37*
G36*
G01X474881Y206496D02*
X474126Y206464D01*
X473691Y207217D01*
X474096Y207855D01*
X474248Y207943D01*
X475032Y206583D01*
X474881Y206496D01*
G37*
G36*
G01X474170Y215436D02*
X473500Y215786D01*
Y216656D01*
X474170Y217006D01*
X474345D01*
Y215436D01*
X474170D01*
G37*
G36*
G01Y211536D02*
X473500Y211886D01*
Y212756D01*
X474170Y213106D01*
X474345D01*
Y211536D01*
X474170D01*
G37*
G36*
G01X427213Y197068D02*
X427973Y196718D01*
Y195818D01*
X427213Y195468D01*
X427038D01*
Y197068D01*
X427213D01*
G37*
G36*
G01X428416Y188206D02*
X429201Y188496D01*
X429837Y187860D01*
X429547Y187075D01*
X429424Y186951D01*
X428292Y188083D01*
X428416Y188206D01*
G37*
G36*
G01X427213Y200968D02*
X427973Y200618D01*
Y199718D01*
X427213Y199368D01*
X427038D01*
Y200968D01*
X427213D01*
G37*
G36*
G01X425340Y204585D02*
X426125Y204875D01*
X426761Y204239D01*
X426471Y203454D01*
X426348Y203330D01*
X425216Y204462D01*
X425340Y204585D01*
G37*
G36*
G01X431174Y185448D02*
X431959Y185738D01*
X432595Y185102D01*
X432305Y184317D01*
X432182Y184193D01*
X431050Y185325D01*
X431174Y185448D01*
G37*
G36*
G01X425094Y215503D02*
X425854Y215153D01*
Y214253D01*
X425094Y213903D01*
X424919D01*
Y215503D01*
X425094D01*
G37*
G36*
G01Y211603D02*
X425854Y211253D01*
Y210353D01*
X425094Y210003D01*
X424919D01*
Y211603D01*
X425094D01*
G37*
G36*
G01X478257Y208453D02*
X477502Y208421D01*
X477067Y209174D01*
X477472Y209812D01*
X477624Y209900D01*
X478408Y208540D01*
X478257Y208453D01*
G37*
G36*
G01X477550Y217337D02*
X476880Y217687D01*
Y218557D01*
X477550Y218907D01*
X477725D01*
Y217337D01*
X477550D01*
G37*
G36*
G01Y213437D02*
X476880Y213787D01*
Y214657D01*
X477550Y215007D01*
X477725D01*
Y213437D01*
X477550D01*
G37*
G36*
G01X443751Y217337D02*
X443081Y217687D01*
Y218557D01*
X443751Y218907D01*
X443926D01*
Y217337D01*
X443751D01*
G37*
G36*
G01Y213437D02*
X443081Y213787D01*
Y214657D01*
X443751Y215007D01*
X443926D01*
Y213437D01*
X443751D01*
G37*
G36*
G01X443518Y207323D02*
X442758Y207673D01*
Y208573D01*
X443518Y208923D01*
X443693D01*
Y207323D01*
X443518D01*
G37*
G36*
G01X449817Y196635D02*
X449057Y196985D01*
Y197885D01*
X449817Y198235D01*
X449992D01*
Y196635D01*
X449817D01*
G37*
G36*
G01X447504Y201541D02*
X446719Y201251D01*
X446083Y201887D01*
X446373Y202672D01*
X446496Y202796D01*
X447628Y201664D01*
X447504Y201541D01*
G37*
G36*
G01X455034Y189979D02*
X454249Y189689D01*
X453613Y190326D01*
X453903Y191111D01*
X454027Y191234D01*
X455158Y190103D01*
X455034Y189979D01*
G37*
G36*
G01X452277Y192737D02*
X451492Y192447D01*
X450856Y193084D01*
X451146Y193869D01*
X451270Y193992D01*
X452401Y192861D01*
X452277Y192737D01*
G37*
G36*
G01X445375Y217006D02*
X446045Y216656D01*
Y215786D01*
X445375Y215436D01*
X445200D01*
Y217006D01*
X445375D01*
G37*
G36*
G01Y213106D02*
X446045Y212756D01*
Y211886D01*
X445375Y211536D01*
X445200D01*
Y213106D01*
X445375D01*
G37*
G36*
G01X444618Y208923D02*
X445378Y208573D01*
Y207673D01*
X444618Y207323D01*
X444443D01*
Y208923D01*
X444618D01*
G37*
G36*
G01X447151Y203450D02*
X447935Y203740D01*
X448572Y203103D01*
X448282Y202319D01*
X448158Y202195D01*
X447027Y203326D01*
X447151Y203450D01*
G37*
G36*
G01X451924Y194647D02*
X452709Y194937D01*
X453346Y194301D01*
X453056Y193516D01*
X452932Y193392D01*
X451801Y194523D01*
X451924Y194647D01*
G37*
G36*
G01X450917Y198235D02*
X451677Y197885D01*
Y196985D01*
X450917Y196635D01*
X450742D01*
Y198235D01*
X450917D01*
G37*
G36*
G01X454682Y191889D02*
X455467Y192179D01*
X456103Y191543D01*
X455813Y190758D01*
X455690Y190634D01*
X454558Y191766D01*
X454682Y191889D01*
G37*
G36*
G01X468441Y195704D02*
X467656Y195414D01*
X467019Y196050D01*
X467309Y196835D01*
X467433Y196959D01*
X468564Y195828D01*
X468441Y195704D01*
G37*
G36*
G01X463292Y203614D02*
X462507Y203324D01*
X461871Y203960D01*
X462161Y204745D01*
X462284Y204869D01*
X463416Y203737D01*
X463292Y203614D01*
G37*
G36*
G01X471198Y192946D02*
X470413Y192656D01*
X469777Y193293D01*
X470067Y194078D01*
X470191Y194201D01*
X471322Y193070D01*
X471198Y192946D01*
G37*
G36*
G01X473157Y187853D02*
X472397Y188203D01*
Y189103D01*
X473157Y189453D01*
X473332D01*
Y187853D01*
X473157D01*
G37*
G36*
G01X457271Y213437D02*
X456601Y213787D01*
Y214657D01*
X457271Y215007D01*
X457446D01*
Y213437D01*
X457271D01*
G37*
G36*
G01Y217337D02*
X456601Y217687D01*
Y218557D01*
X457271Y218907D01*
X457446D01*
Y217337D01*
X457271D01*
G37*
G36*
G01X460534Y206371D02*
X459749Y206081D01*
X459113Y206717D01*
X459403Y207502D01*
X459526Y207626D01*
X460658Y206494D01*
X460534Y206371D01*
G37*
G36*
G01X468088Y197614D02*
X468873Y197904D01*
X469509Y197267D01*
X469219Y196482D01*
X469095Y196359D01*
X467964Y197490D01*
X468088Y197614D01*
G37*
G36*
G01X470845Y194856D02*
X471630Y195146D01*
X472267Y194510D01*
X471977Y193725D01*
X471853Y193601D01*
X470722Y194732D01*
X470845Y194856D01*
G37*
G36*
G01X474347Y189453D02*
X475107Y189103D01*
Y188203D01*
X474347Y187853D01*
X474172D01*
Y189453D01*
X474347D01*
G37*
G36*
G01X458895Y213081D02*
X459565Y212731D01*
Y211861D01*
X458895Y211511D01*
X458720D01*
Y213081D01*
X458895D01*
G37*
G36*
G01Y217006D02*
X459565Y216656D01*
Y215786D01*
X458895Y215436D01*
X458720D01*
Y217006D01*
X458895D01*
G37*
G36*
G01X460235Y208334D02*
X461020Y208624D01*
X461656Y207988D01*
X461366Y207203D01*
X461243Y207079D01*
X460111Y208211D01*
X460235Y208334D01*
G37*
G36*
G01X462993Y205577D02*
X463778Y205867D01*
X464414Y205230D01*
X464124Y204445D01*
X464000Y204322D01*
X462869Y205453D01*
X462993Y205577D01*
G37*
G36*
G01X445474Y199211D02*
X444689Y198921D01*
X444053Y199557D01*
X444343Y200342D01*
X444466Y200466D01*
X445598Y199334D01*
X445474Y199211D01*
G37*
G36*
G01X442716Y201968D02*
X441931Y201678D01*
X441295Y202315D01*
X441585Y203100D01*
X441709Y203223D01*
X442840Y202092D01*
X442716Y201968D01*
G37*
G36*
G01X440371Y215436D02*
X439701Y215786D01*
Y216656D01*
X440371Y217006D01*
X440546D01*
Y215436D01*
X440371D01*
G37*
G36*
G01Y211536D02*
X439701Y211886D01*
Y212756D01*
X440371Y213106D01*
X440546D01*
Y211536D01*
X440371D01*
G37*
G36*
G01X450258Y190418D02*
X449473Y190128D01*
X448837Y190764D01*
X449127Y191549D01*
X449250Y191673D01*
X450382Y190541D01*
X450258Y190418D01*
G37*
G36*
G01X446667Y195746D02*
X445907Y196096D01*
Y196995D01*
X446667Y197345D01*
X446842Y197346D01*
Y195745D01*
X446667Y195746D01*
G37*
G36*
G01X450447Y185826D02*
X449687Y186176D01*
Y187076D01*
X450447Y187426D01*
X450622D01*
Y185826D01*
X450447D01*
G37*
G36*
G01X442363Y203878D02*
X443148Y204168D01*
X443784Y203531D01*
X443494Y202746D01*
X443370Y202623D01*
X442239Y203754D01*
X442363Y203878D01*
G37*
G36*
G01X445121Y201120D02*
X445905Y201410D01*
X446542Y200773D01*
X446252Y199989D01*
X446128Y199865D01*
X444997Y200996D01*
X445121Y201120D01*
G37*
G36*
G01X441995Y218907D02*
X442665Y218557D01*
Y217687D01*
X441995Y217337D01*
X441820D01*
Y218907D01*
X441995D01*
G37*
G36*
G01Y215007D02*
X442665Y214657D01*
Y213787D01*
X441995Y213437D01*
X441820D01*
Y215007D01*
X441995D01*
G37*
G36*
G01Y211107D02*
X442665Y210757D01*
Y209887D01*
X441995Y209537D01*
X441820D01*
Y211107D01*
X441995D01*
G37*
G36*
G01X447767Y197346D02*
X448527Y196996D01*
Y196096D01*
X447767Y195746D01*
X447592D01*
Y197346D01*
X447767D01*
G37*
G36*
G01X449904Y192327D02*
X450689Y192617D01*
X451326Y191981D01*
X451036Y191196D01*
X450912Y191072D01*
X449781Y192203D01*
X449904Y192327D01*
G37*
G36*
G01X451671Y187426D02*
X452431Y187076D01*
Y186176D01*
X451671Y185826D01*
X451496D01*
Y187426D01*
X451671D01*
G37*
G36*
G01X465147Y194626D02*
X464362Y194336D01*
X463726Y194972D01*
X464016Y195757D01*
X464139Y195881D01*
X465271Y194749D01*
X465147Y194626D01*
G37*
G36*
G01X468237Y187672D02*
X467477Y188022D01*
Y188922D01*
X468237Y189272D01*
X468412D01*
Y187672D01*
X468237D01*
G37*
G36*
G01X467905Y191868D02*
X467120Y191578D01*
X466483Y192214D01*
X466773Y192999D01*
X466897Y193123D01*
X468028Y191992D01*
X467905Y191868D01*
G37*
G36*
G01X462015Y200368D02*
X461231Y200078D01*
X460594Y200715D01*
X460884Y201499D01*
X461008Y201623D01*
X462139Y200492D01*
X462015Y200368D01*
G37*
G36*
G01X459257Y203126D02*
X458473Y202836D01*
X457836Y203473D01*
X458126Y204257D01*
X458250Y204381D01*
X459381Y203250D01*
X459257Y203126D01*
G37*
G36*
G01X453891Y215436D02*
X453221Y215786D01*
Y216656D01*
X453891Y217006D01*
X454066D01*
Y215436D01*
X453891D01*
G37*
G36*
G01Y211536D02*
X453221Y211886D01*
Y212756D01*
X453891Y213106D01*
X454066D01*
Y211536D01*
X453891D01*
G37*
G36*
G01X464795Y196536D02*
X465580Y196826D01*
X466216Y196189D01*
X465926Y195404D01*
X465802Y195281D01*
X464671Y196412D01*
X464795Y196536D01*
G37*
G36*
G01X467552Y193778D02*
X468337Y194068D01*
X468973Y193431D01*
X468683Y192646D01*
X468559Y192523D01*
X467428Y193654D01*
X467552Y193778D01*
G37*
G36*
G01X458999Y205130D02*
X459784Y205420D01*
X460420Y204784D01*
X460130Y203999D01*
X460007Y203875D01*
X458875Y205007D01*
X458999Y205130D01*
G37*
G36*
G01X461757Y202372D02*
X462542Y202662D01*
X463178Y202026D01*
X462888Y201241D01*
X462765Y201117D01*
X461633Y202249D01*
X461757Y202372D01*
G37*
G36*
G01X469337Y189272D02*
X470097Y188922D01*
Y188022D01*
X469337Y187672D01*
X469162D01*
Y189272D01*
X469337D01*
G37*
G36*
G01X455515Y215007D02*
X456185Y214657D01*
Y213787D01*
X455515Y213437D01*
X455340D01*
Y215007D01*
X455515D01*
G37*
G36*
G01Y218907D02*
X456185Y218557D01*
Y217687D01*
X455515Y217337D01*
X455340D01*
Y218907D01*
X455515D01*
G37*
G36*
G01X448755D02*
X449425Y218557D01*
Y217687D01*
X448755Y217337D01*
X448580D01*
Y218907D01*
X448755D01*
G37*
G36*
G01Y215007D02*
X449425Y214657D01*
Y213787D01*
X448755Y213437D01*
X448580D01*
Y215007D01*
X448755D01*
G37*
G36*
G01X451576Y203994D02*
X452360Y204284D01*
X452997Y203647D01*
X452707Y202863D01*
X452583Y202739D01*
X451452Y203870D01*
X451576Y203994D01*
G37*
G36*
G01X453767Y200615D02*
X454527Y200265D01*
Y199365D01*
X453767Y199015D01*
X453592D01*
Y200615D01*
X453767D01*
G37*
G36*
G01X455227Y195734D02*
X456012Y196024D01*
X456648Y195388D01*
X456358Y194603D01*
X456235Y194479D01*
X455103Y195611D01*
X455227Y195734D01*
G37*
G36*
G01X457984Y192976D02*
X458769Y193266D01*
X459405Y192630D01*
X459115Y191845D01*
X458992Y191721D01*
X457860Y192853D01*
X457984Y192976D01*
G37*
G36*
G01X460921Y188812D02*
X461681Y188462D01*
Y187562D01*
X460921Y187212D01*
X460746D01*
Y188812D01*
X460921D01*
G37*
G36*
G01X459114Y197855D02*
X459899Y198145D01*
X460535Y197509D01*
X460245Y196724D01*
X460122Y196600D01*
X458990Y197732D01*
X459114Y197855D01*
G37*
G36*
G01X461872Y195098D02*
X462657Y195388D01*
X463293Y194751D01*
X463003Y193966D01*
X462879Y193843D01*
X461748Y194974D01*
X461872Y195098D01*
G37*
G36*
G01X464784Y190040D02*
X465544Y189690D01*
Y188790D01*
X464784Y188440D01*
X464609D01*
Y190040D01*
X464784D01*
G37*
G36*
G01X452135Y217006D02*
X452805Y216656D01*
Y215786D01*
X452135Y215436D01*
X451960D01*
Y217006D01*
X452135D01*
G37*
G36*
G01X454470Y205299D02*
X455255Y205589D01*
X455891Y204953D01*
X455601Y204168D01*
X455478Y204044D01*
X454346Y205176D01*
X454470Y205299D01*
G37*
G36*
G01X447131Y215436D02*
X446461Y215786D01*
Y216656D01*
X447131Y217006D01*
X447306D01*
Y215436D01*
X447131D01*
G37*
G36*
G01Y211511D02*
X446461Y211861D01*
Y212731D01*
X447131Y213081D01*
X447306D01*
Y211511D01*
X447131D01*
G37*
G36*
G01X451929Y202085D02*
X451144Y201795D01*
X450508Y202431D01*
X450798Y203216D01*
X450921Y203340D01*
X452053Y202208D01*
X451929Y202085D01*
G37*
G36*
G01X452667Y199015D02*
X451907Y199365D01*
Y200265D01*
X452667Y200615D01*
X452842D01*
Y199015D01*
X452667D01*
G37*
G36*
G01X455580Y193825D02*
X454796Y193535D01*
X454159Y194172D01*
X454449Y194956D01*
X454573Y195080D01*
X455704Y193949D01*
X455580Y193825D01*
G37*
G36*
G01X458337Y191067D02*
X457553Y190777D01*
X456916Y191414D01*
X457206Y192198D01*
X457330Y192322D01*
X458461Y191191D01*
X458337Y191067D01*
G37*
G36*
G01X459821Y187212D02*
X459061Y187562D01*
Y188462D01*
X459821Y188812D01*
X459996D01*
Y187212D01*
X459821D01*
G37*
G36*
G01X454823Y203390D02*
X454039Y203100D01*
X453402Y203737D01*
X453692Y204521D01*
X453816Y204645D01*
X454947Y203514D01*
X454823Y203390D01*
G37*
G36*
G01X459467Y195946D02*
X458683Y195656D01*
X458046Y196293D01*
X458336Y197077D01*
X458460Y197201D01*
X459591Y196070D01*
X459467Y195946D01*
G37*
G36*
G01X463684Y188440D02*
X462924Y188790D01*
Y189690D01*
X463684Y190040D01*
X463859D01*
Y188440D01*
X463684D01*
G37*
G36*
G01X462225Y193188D02*
X461441Y192898D01*
X460804Y193535D01*
X461094Y194319D01*
X461218Y194443D01*
X462349Y193312D01*
X462225Y193188D01*
G37*
G36*
G01X450511Y213437D02*
X449841Y213787D01*
Y214657D01*
X450511Y215007D01*
X450686D01*
Y213437D01*
X450511D01*
G37*
G36*
G01Y217337D02*
X449841Y217687D01*
Y218557D01*
X450511Y218907D01*
X450686D01*
Y217337D01*
X450511D01*
G37*
G36*
G01X428752Y221456D02*
X428114Y221051D01*
X427361Y221486D01*
X427393Y222241D01*
X427480Y222393D01*
X428840Y221607D01*
X428752Y221456D01*
G37*
G36*
G01X431856Y220917D02*
X432526Y220567D01*
Y219697D01*
X431856Y219347D01*
X431681D01*
Y220917D01*
X431856D01*
G37*
G36*
G01X429937Y222648D02*
X430575Y223054D01*
X431328Y222619D01*
X431296Y221864D01*
X431209Y221712D01*
X429850Y222498D01*
X429937Y222648D01*
G37*
G36*
G01X425366Y219510D02*
X424728Y219105D01*
X423975Y219540D01*
X424007Y220295D01*
X424094Y220447D01*
X425454Y219661D01*
X425366Y219510D01*
G37*
G36*
G01X426575Y220688D02*
X427213Y221093D01*
X427966Y220659D01*
X427934Y219904D01*
X427847Y219751D01*
X426488Y220537D01*
X426575Y220688D01*
G37*
G36*
G01X424087Y221770D02*
X423531Y222281D01*
X423756Y223121D01*
X424493Y223286D01*
X424662Y223241D01*
X424256Y221724D01*
X424087Y221770D01*
G37*
G36*
G01X469311Y225356D02*
X468673Y224951D01*
X467920Y225386D01*
X467952Y226141D01*
X468039Y226293D01*
X469399Y225507D01*
X469311Y225356D01*
G37*
G36*
G01X470790Y221226D02*
X470120Y221576D01*
Y222446D01*
X470790Y222796D01*
X470965D01*
Y221226D01*
X470790D01*
G37*
G36*
G01X467135Y228487D02*
X467773Y228892D01*
X468526Y228457D01*
X468494Y227702D01*
X468407Y227550D01*
X467047Y228336D01*
X467135Y228487D01*
G37*
G36*
G01X472415Y220917D02*
X473085Y220567D01*
Y219697D01*
X472415Y219347D01*
X472240D01*
Y220917D01*
X472415D01*
G37*
G36*
G01X477265Y238242D02*
X477903Y238647D01*
X478656Y238212D01*
X478624Y237457D01*
X478537Y237305D01*
X477177Y238091D01*
X477265Y238242D01*
G37*
G36*
G01X467411Y219336D02*
X466741Y219686D01*
Y220556D01*
X467411Y220906D01*
X467586D01*
Y219336D01*
X467411D01*
G37*
G36*
G01X465925Y223410D02*
X465287Y223005D01*
X464534Y223440D01*
X464566Y224195D01*
X464653Y224346D01*
X466013Y223561D01*
X465925Y223410D01*
G37*
G36*
G01X460651Y230987D02*
X459981Y231337D01*
Y232207D01*
X460651Y232557D01*
X460826D01*
Y230987D01*
X460651D01*
G37*
G36*
G01X463761Y226533D02*
X464399Y226938D01*
X465152Y226503D01*
X465120Y225748D01*
X465033Y225596D01*
X463673Y226382D01*
X463761Y226533D01*
G37*
G36*
G01X467134Y224588D02*
X467772Y224993D01*
X468525Y224559D01*
X468493Y223804D01*
X468407Y223652D01*
X467046Y224437D01*
X467134Y224588D01*
G37*
G36*
G01X462274Y230676D02*
X462944Y230326D01*
Y229456D01*
X462274Y229106D01*
X462099D01*
Y230676D01*
X462274D01*
G37*
G36*
G01X477274Y234337D02*
X477912Y234742D01*
X478665Y234307D01*
X478633Y233552D01*
X478546Y233400D01*
X477186Y234186D01*
X477274Y234337D01*
G37*
G36*
G01X470514Y230438D02*
X471152Y230843D01*
X471905Y230408D01*
X471873Y229653D01*
X471786Y229502D01*
X470426Y230287D01*
X470514Y230438D01*
G37*
G36*
G01X475794Y222807D02*
X476464Y222457D01*
Y221587D01*
X475794Y221237D01*
X475619D01*
Y222807D01*
X475794D01*
G37*
G36*
G01X472415Y240417D02*
X473085Y240067D01*
Y239197D01*
X472415Y238847D01*
X472240D01*
Y240417D01*
X472415D01*
G37*
G36*
G01Y236506D02*
X473085Y236156D01*
Y235286D01*
X472415Y234936D01*
X472240D01*
Y236506D01*
X472415D01*
G37*
G36*
G01X472682Y227313D02*
X472044Y226908D01*
X471291Y227343D01*
X471323Y228098D01*
X471410Y228250D01*
X472770Y227464D01*
X472682Y227313D01*
G37*
G36*
G01X474170Y223236D02*
X473500Y223586D01*
Y224456D01*
X474170Y224806D01*
X474345D01*
Y223236D01*
X474170D01*
G37*
G36*
G01Y219336D02*
X473500Y219686D01*
Y220556D01*
X474170Y220906D01*
X474345D01*
Y219336D01*
X474170D01*
G37*
G36*
G01X423145Y218716D02*
X423782Y219121D01*
X424536Y218686D01*
X424504Y217931D01*
X424416Y217779D01*
X423057Y218564D01*
X423145Y218716D01*
G37*
G36*
G01X421716Y226732D02*
X422386Y226382D01*
Y225512D01*
X421716Y225162D01*
X421541D01*
Y226732D01*
X421716D01*
G37*
G36*
G01X476079Y229251D02*
X475441Y228846D01*
X474688Y229281D01*
X474720Y230036D01*
X474807Y230188D01*
X476167Y229402D01*
X476079Y229251D01*
G37*
G36*
G01X477550Y225137D02*
X476880Y225487D01*
Y226357D01*
X477550Y226707D01*
X477725D01*
Y225137D01*
X477550D01*
G37*
G36*
G01Y221237D02*
X476880Y221587D01*
Y222457D01*
X477550Y222807D01*
X477725D01*
Y221237D01*
X477550D01*
G37*
G36*
G01X470790Y236826D02*
X470120Y237176D01*
Y238046D01*
X470790Y238396D01*
X470965D01*
Y236826D01*
X470790D01*
G37*
G36*
G01X443751Y221237D02*
X443081Y221587D01*
Y222457D01*
X443751Y222807D01*
X443926D01*
Y221237D01*
X443751D01*
G37*
G36*
G01Y225137D02*
X443081Y225487D01*
Y226357D01*
X443751Y226707D01*
X443926D01*
Y225137D01*
X443751D01*
G37*
G36*
G01Y229062D02*
X443081Y229412D01*
Y230282D01*
X443751Y230632D01*
X443926D01*
Y229062D01*
X443751D01*
G37*
G36*
G01X445375Y228706D02*
X446045Y228356D01*
Y227486D01*
X445375Y227136D01*
X445200D01*
Y228706D01*
X445375D01*
G37*
G36*
G01Y220906D02*
X446045Y220556D01*
Y219686D01*
X445375Y219336D01*
X445200D01*
Y220906D01*
X445375D01*
G37*
G36*
G01Y224806D02*
X446045Y224456D01*
Y223586D01*
X445375Y223236D01*
X445200D01*
Y224806D01*
X445375D01*
G37*
G36*
G01X446627Y236134D02*
X447366Y236296D01*
X447925Y235630D01*
X447637Y234931D01*
X447503Y234819D01*
X446493Y236021D01*
X446627Y236134D01*
G37*
G36*
G01X457271Y221237D02*
X456601Y221587D01*
Y222457D01*
X457271Y222807D01*
X457446D01*
Y221237D01*
X457271D01*
G37*
G36*
G01Y225137D02*
X456601Y225487D01*
Y226357D01*
X457271Y226707D01*
X457446D01*
Y225137D01*
X457271D01*
G37*
G36*
G01Y229062D02*
X456601Y229412D01*
Y230282D01*
X457271Y230632D01*
X457446D01*
Y229062D01*
X457271D01*
G37*
G36*
G01X458895Y220906D02*
X459565Y220556D01*
Y219686D01*
X458895Y219336D01*
X458720D01*
Y220906D01*
X458895D01*
G37*
G36*
G01Y224806D02*
X459565Y224456D01*
Y223586D01*
X458895Y223236D01*
X458720D01*
Y224806D01*
X458895D01*
G37*
G36*
G01Y228706D02*
X459565Y228356D01*
Y227486D01*
X458895Y227136D01*
X458720D01*
Y228706D01*
X458895D01*
G37*
G36*
G01Y232557D02*
X459565Y232207D01*
Y231337D01*
X458895Y230987D01*
X458720D01*
Y232557D01*
X458895D01*
G37*
G36*
G01X440371Y219336D02*
X439701Y219686D01*
Y220556D01*
X440371Y220906D01*
X440546D01*
Y219336D01*
X440371D01*
G37*
G36*
G01Y223236D02*
X439701Y223586D01*
Y224456D01*
X440371Y224806D01*
X440546D01*
Y223236D01*
X440371D01*
G37*
G36*
G01Y227136D02*
X439701Y227486D01*
Y228356D01*
X440371Y228706D01*
X440546D01*
Y227136D01*
X440371D01*
G37*
G36*
G01Y230987D02*
X439701Y231337D01*
Y232207D01*
X440371Y232557D01*
X440546D01*
Y230987D01*
X440371D01*
G37*
G36*
G01X441995Y222807D02*
X442665Y222457D01*
Y221587D01*
X441995Y221237D01*
X441820D01*
Y222807D01*
X441995D01*
G37*
G36*
G01Y226707D02*
X442665Y226357D01*
Y225487D01*
X441995Y225137D01*
X441820D01*
Y226707D01*
X441995D01*
G37*
G36*
G01Y230632D02*
X442665Y230282D01*
Y229412D01*
X441995Y229062D01*
X441820D01*
Y230632D01*
X441995D01*
G37*
G36*
G01X453891Y219336D02*
X453221Y219686D01*
Y220556D01*
X453891Y220906D01*
X454066D01*
Y219336D01*
X453891D01*
G37*
G36*
G01Y223236D02*
X453221Y223586D01*
Y224456D01*
X453891Y224806D01*
X454066D01*
Y223236D01*
X453891D01*
G37*
G36*
G01Y227136D02*
X453221Y227486D01*
Y228356D01*
X453891Y228706D01*
X454066D01*
Y227136D01*
X453891D01*
G37*
G36*
G01X455515Y222807D02*
X456185Y222457D01*
Y221587D01*
X455515Y221237D01*
X455340D01*
Y222807D01*
X455515D01*
G37*
G36*
G01Y226707D02*
X456185Y226357D01*
Y225487D01*
X455515Y225137D01*
X455340D01*
Y226707D01*
X455515D01*
G37*
G36*
G01Y230632D02*
X456185Y230282D01*
Y229412D01*
X455515Y229062D01*
X455340D01*
Y230632D01*
X455515D01*
G37*
G36*
G01Y234556D02*
X456185Y234206D01*
Y233336D01*
X455515Y232986D01*
X455340D01*
Y234556D01*
X455515D01*
G37*
G36*
G01X448755Y226707D02*
X449425Y226357D01*
Y225487D01*
X448755Y225137D01*
X448580D01*
Y226707D01*
X448755D01*
G37*
G36*
G01Y222807D02*
X449425Y222457D01*
Y221587D01*
X448755Y221237D01*
X448580D01*
Y222807D01*
X448755D01*
G37*
G36*
G01X452135Y228706D02*
X452805Y228356D01*
Y227486D01*
X452135Y227136D01*
X451960D01*
Y228706D01*
X452135D01*
G37*
G36*
G01Y224806D02*
X452805Y224456D01*
Y223586D01*
X452135Y223236D01*
X451960D01*
Y224806D01*
X452135D01*
G37*
G36*
G01Y220906D02*
X452805Y220556D01*
Y219686D01*
X452135Y219336D01*
X451960D01*
Y220906D01*
X452135D01*
G37*
G36*
G01Y232557D02*
X452805Y232207D01*
Y231337D01*
X452135Y230987D01*
X451960D01*
Y232557D01*
X452135D01*
G37*
G36*
G01Y236481D02*
X452805Y236131D01*
Y235261D01*
X452135Y234911D01*
X451960D01*
Y236481D01*
X452135D01*
G37*
G36*
G01X447131Y227136D02*
X446461Y227486D01*
Y228356D01*
X447131Y228706D01*
X447306D01*
Y227136D01*
X447131D01*
G37*
G36*
G01Y223236D02*
X446461Y223586D01*
Y224456D01*
X447131Y224806D01*
X447306D01*
Y223236D01*
X447131D01*
G37*
G36*
G01Y219336D02*
X446461Y219686D01*
Y220556D01*
X447131Y220906D01*
X447306D01*
Y219336D01*
X447131D01*
G37*
G36*
G01X450511Y229062D02*
X449841Y229412D01*
Y230282D01*
X450511Y230632D01*
X450686D01*
Y229062D01*
X450511D01*
G37*
G36*
G01Y225137D02*
X449841Y225487D01*
Y226357D01*
X450511Y226707D01*
X450686D01*
Y225137D01*
X450511D01*
G37*
G36*
G01Y221237D02*
X449841Y221587D01*
Y222457D01*
X450511Y222807D01*
X450686D01*
Y221237D01*
X450511D01*
G37*
G36*
G01Y232962D02*
X449841Y233312D01*
Y234182D01*
X450511Y234532D01*
X450686D01*
Y232962D01*
X450511D01*
G37*
G36*
G01Y236837D02*
X449841Y237187D01*
Y238057D01*
X450511Y238407D01*
X450686D01*
Y236837D01*
X450511D01*
G37*
G36*
G01X603880Y171520D02*
X568430Y206970D01*
X562523D01*
G02X562127Y207427I0J400D01*
G03X559351I-1388J198D01*
G02X558955Y206970I-396J-57D01*
G01X558401D01*
X558364Y207124D01*
G03X555636I-1364J-324D01*
G01X555599Y206970D01*
X539938D01*
X539882Y207080D01*
G03X537380I-1251J-633D01*
G01X537324Y206970D01*
X536732D01*
G02X536403Y207598I0J400D01*
G03X534099I-1152J799D01*
G02X533770Y206970I-329J-228D01*
G01X533178D01*
X533122Y207080D01*
G03X530620I-1251J-633D01*
G01X530564Y206970D01*
X529972D01*
G02X529643Y207598I0J400D01*
G03X527339I-1152J799D01*
G02X527010Y206970I-329J-228D01*
G01X526418D01*
X526362Y207080D01*
G03X523860I-1251J-633D01*
G01X523804Y206970D01*
X523212D01*
G02X522883Y207598I0J400D01*
G03X520579I-1152J799D01*
G02X520250Y206970I-329J-228D01*
G01X519658D01*
X519602Y207079D01*
G03X517102I-1250J-634D01*
G01X517046Y206970D01*
X516453D01*
G02X516124Y207598I0J400D01*
G03X513820I-1152J799D01*
G02X513491Y206970I-329J-228D01*
G01X512899D01*
X512843Y207080D01*
G03X510341I-1251J-633D01*
G01X510285Y206970D01*
X505554D01*
X502071Y210453D01*
G02X502154Y211082I283J283D01*
G03X500238Y212998I-702J1214D01*
G02X499609Y212915I-346J200D01*
G01X499167Y213357D01*
X499254Y213492D01*
G03X496866Y214963I-1182J755D01*
G02X496240Y214884I-344J204D01*
G01X495794Y215330D01*
G03X493440Y216827I-1102J867D01*
G02X492800Y216724I-357J180D01*
G01X490378Y219146D01*
Y238546D01*
X488049Y240874D01*
X488102Y240999D01*
G03X485496Y242031I-1290J548D01*
G01X485448Y241900D01*
X484780D01*
G02X484481Y242565I0J400D01*
G03X482383I-1049J931D01*
G02X482084Y241900I-299J-265D01*
G01X481416D01*
X481368Y242031D01*
G03X478736I-1316J-484D01*
G01X478688Y241900D01*
X478020D01*
G02X477721Y242565I0J400D01*
G03X475984Y242274I-1049J931D01*
G01X476086Y242217D01*
Y241900D01*
X475700D01*
X473964Y243636D01*
G02X474035Y244258I283J283D01*
G03X471931Y245782I-743J1189D01*
G01X471893Y245630D01*
X471088D01*
G02X470827Y246333I0J400D01*
G03X468999I-914J1063D01*
G02X468738Y245630I-261J-303D01*
G01X467932D01*
X467894Y245782D01*
G03X465172I-1361J-335D01*
G01X465134Y245630D01*
X464328D01*
G02X464067Y246333I0J400D01*
G03X462239I-914J1063D01*
G02X461978Y245630I-261J-303D01*
G01X461172D01*
X461134Y245782D01*
G03X458412I-1361J-335D01*
G01X458374Y245630D01*
X457568D01*
G02X457307Y246333I0J400D01*
G03X455479I-914J1063D01*
G02X455218Y245630I-261J-303D01*
G01X454412D01*
X454374Y245782D01*
G03X451652I-1361J-335D01*
G01X451614Y245630D01*
X450808D01*
G02X450547Y246333I0J400D01*
G03X448719I-914J1063D01*
G02X448458Y245630I-261J-303D01*
G01X447652D01*
X447614Y245782D01*
G03X445133Y244603I-1361J-335D01*
G01X444689Y244159D01*
G02X444066Y244232I-283J283D01*
G03X442137Y242303I-1193J-736D01*
G02X442210Y241680I-210J-340D01*
G01X439940Y239410D01*
X437517D01*
X437515Y239608D01*
G03X434711I-1402J-12D01*
G01X434709Y239410D01*
X433890D01*
X433500Y239800D01*
G02X433550Y240408I283J283D01*
G03X431594Y242364I-817J1139D01*
G02X430986Y242314I-325J233D01*
G01X430760Y242540D01*
Y250120D01*
X434751Y254111D01*
X434845Y254102D01*
G03X436378Y255635I138J1395D01*
G01X436369Y255729D01*
X437233Y256593D01*
X437374Y256452D01*
G03X439357Y258435I989J994D01*
G01X439216Y258576D01*
X439751Y259111D01*
G02X440413Y258954I282J-283D01*
G03X442186Y260727I1330J443D01*
G02X442029Y261389I126J380D01*
G01X443792Y263152D01*
X443930Y263052D01*
G03X444054Y262972I821J1137D01*
G02X444136Y262342I-200J-346D01*
G03X445821Y262562I987J-996D01*
G02X445739Y263192I200J346D01*
G03X445153Y265531I-987J996D01*
G01X445010Y265574D01*
Y266039D01*
G03Y268571I-602J1266D01*
G01Y291006D01*
G02X445570Y291373I400J0D01*
G03X447385Y291754I639J1469D01*
G02X447972Y291753I293J-272D01*
G03X449695Y291335I1176J1088D01*
G02X450200Y291115I137J-376D01*
G03X453085Y290978I1475J624D01*
G02X453794Y290967I352J-190D01*
G03X455207Y293288I1432J719D01*
G02X454802Y293687I-5J400D01*
G03X454796Y293819I-1402J2D01*
G02X455139Y294254I398J39D01*
G03X453700Y296877I-217J1587D01*
G02X453079Y296889I-306J258D01*
G03X450524Y296851I-1263J-985D01*
G02X449919Y296805I-322J237D01*
G01X446178Y300546D01*
Y312954D01*
X468624Y335400D01*
X475996D01*
G02X476395Y335033I0J-400D01*
G03X478774Y334146I1397J114D01*
G02X479055Y334145I140J-143D01*
G01X479784Y333416D01*
X479776Y333323D01*
G03X480500Y331966I1396J-127D01*
G01Y330526D01*
G03Y328066I672J-1230D01*
G01Y326626D01*
G03Y324166I672J-1230D01*
G01Y322726D01*
G03Y320266I672J-1230D01*
G01Y318826D01*
G03Y316366I672J-1230D01*
G01Y315200D01*
X478342Y313042D01*
X478226Y313080D01*
G03X476459Y311313I-434J-1333D01*
G01X476497Y311197D01*
X471777Y306477D01*
G02X471143Y306568I-283J283D01*
G03X470759Y304778I-1230J-672D01*
G02X471400Y304459I241J-319D01*
G01Y287833D01*
G02X470759Y287514I-400J0D01*
G03X470459Y285105I-846J-1118D01*
G02X471014Y284736I155J-369D01*
G01Y278914D01*
X468463Y276363D01*
X468412Y276349D01*
G03X467431Y275368I371J-1352D01*
G01X467417Y275317D01*
X466900Y274800D01*
Y268478D01*
G03X466527Y266556I3013J-1582D01*
G02X466354Y266338I-199J-20D01*
G03X465392Y265762I179J-1391D01*
G02X464784Y265711I-326J232D01*
G01X464371Y266124D01*
X460534D01*
G03Y263770I-761J-1177D01*
G01X463395D01*
X465142Y262022D01*
X466502D01*
X468412Y260112D01*
X468535D01*
G02X468707Y259811I0J-200D01*
G03X471119I1206J-715D01*
G02X471291Y260112I172J101D01*
G01X471418D01*
X471562Y260257D01*
G02X472166Y260212I283J-283D01*
G03X474344Y260120I1126J835D01*
G02X474927Y260138I300J-265D01*
G01X474983Y260082D01*
G02X475346Y259552I-15J-400D01*
G03X477774Y258229I1326J-456D01*
G02X478351Y258282I314J-248D01*
G01X478407D01*
G02X478772Y257719I0J-400D01*
G03X481257Y256430I1280J-572D01*
G01X481835D01*
G02X482189Y255845I0J-400D01*
G03X484745Y254705I1243J-649D01*
G02X485403Y254847I375J-140D01*
G01X485776Y254474D01*
G02X485781Y254197I-142J-141D01*
G03X488153Y252838I1031J-950D01*
G01X488196Y252980D01*
X492070D01*
X493346Y251704D01*
X493323Y251597D01*
G03X494993Y249927I1369J-301D01*
G01X495100Y249950D01*
X498410Y246640D01*
X500271D01*
G03X502633I1181J756D01*
G01X503214D01*
G02X503573Y246064I0J-400D01*
G03X506091I1259J-617D01*
G02X506450Y246640I359J176D01*
G01X507031D01*
G03X509326Y246545I1181J756D01*
G02X509602Y246586I159J-121D01*
G03X510195Y246244I1988J2762D01*
G02X510297Y245985I-83J-182D01*
G03X512887I1295J-538D01*
G02X512989Y246244I185J77D01*
G03X513582Y246586I-1395J3104D01*
G02X513858Y246545I117J-162D01*
G03X516086I1114J851D01*
G02X516362Y246586I159J-121D01*
G03X516955Y246244I1988J2762D01*
G02X517057Y245985I-82J-182D01*
G03X519647I1295J-538D01*
G02X519749Y246244I185J77D01*
G03X520341Y246586I-1398J3103D01*
G02X520617Y246545I117J-163D01*
G03X522845I1114J851D01*
G02X523121Y246586I159J-121D01*
G03X523714Y246244I1988J2762D01*
G02X523816Y245985I-83J-182D01*
G03X526407Y244912I1295J-538D01*
G02X527059Y245042I369J-153D01*
G01X527550Y244551D01*
X527429Y244411D01*
G03X529762Y242904I1062J-915D01*
G01X533980D01*
G03X536522I1271J592D01*
G01X537104D01*
G02X537443Y242292I0J-400D01*
G03X539819I1188J-745D01*
G02X540158Y242904I339J212D01*
G01X540740D01*
G03X543282I1271J592D01*
G01X543864D01*
G02X544203Y242292I0J-400D01*
G03X546579I1188J-745D01*
G02X546918Y242904I339J212D01*
G01X547500D01*
G03X550042I1271J592D01*
G01X550624D01*
G02X550963Y242292I0J-400D01*
G03X553339I1188J-745D01*
G02X553678Y242904I339J212D01*
G01X554260D01*
G03X556707Y244259I1271J592D01*
G02X557043Y244877I335J218D01*
G01X561079D01*
G02X561415Y244259I1J-400D01*
G03X563576Y242499I1177J-762D01*
G02X564139I282J-285D01*
G03X566187Y242582I985J997D01*
G02X566796Y242579I303J-261D01*
G03X568802Y244528I1072J903D01*
G02X568935Y244877I133J149D01*
G01X569218D01*
X569882Y245541D01*
X582933D01*
X583266Y245874D01*
X612730D01*
G02X613113Y245359I0J-400D01*
G03X615799I1343J-403D01*
G02X616182Y245874I383J115D01*
G01X641074D01*
X658982Y227966D01*
Y176342D01*
X654160Y171520D01*
X642693D01*
G02X642293Y171922I0J400D01*
G03X634789I-3752J23D01*
G02X634389Y171520I-400J-2D01*
G01X603880D01*
G37*
G36*
G01X421216Y398698D02*
X420456Y399048D01*
Y399948D01*
X421216Y400298D01*
X421391D01*
Y398698D01*
X421216D01*
G37*
G36*
G01Y394798D02*
X420456Y395148D01*
Y396048D01*
X421216Y396398D01*
X421391D01*
Y394798D01*
X421216D01*
G37*
G36*
G01Y390898D02*
X420456Y391248D01*
Y392148D01*
X421216Y392498D01*
X421391D01*
Y390898D01*
X421216D01*
G37*
G36*
G01X422314Y396398D02*
X423074Y396048D01*
Y395148D01*
X422314Y394798D01*
X422139D01*
Y396398D01*
X422314D01*
G37*
G36*
G01Y400298D02*
X423074Y399948D01*
Y399048D01*
X422314Y398698D01*
X422139D01*
Y400298D01*
X422314D01*
G37*
G36*
G01X432976Y386634D02*
X433646Y386284D01*
Y385414D01*
X432976Y385064D01*
X432801D01*
Y386634D01*
X432976D01*
G37*
G36*
G01X432123Y387014D02*
X431453Y387364D01*
Y388234D01*
X432123Y388584D01*
X432298D01*
Y387014D01*
X432123D01*
G37*
G36*
G01X435272Y391502D02*
X435240Y392257D01*
X435993Y392692D01*
X436631Y392287D01*
X436719Y392135D01*
X435359Y391351D01*
X435272Y391502D01*
G37*
G36*
G01X438115Y400708D02*
X437355Y401058D01*
Y401958D01*
X438115Y402308D01*
X438290D01*
Y400708D01*
X438115D01*
G37*
G36*
G01Y396808D02*
X437355Y397158D01*
Y398058D01*
X438115Y398408D01*
X438290D01*
Y396808D01*
X438115D01*
G37*
G36*
G01X439213Y402308D02*
X439973Y401958D01*
Y401058D01*
X439213Y400708D01*
X439038D01*
Y402308D01*
X439213D01*
G37*
G36*
G01Y398408D02*
X439973Y398058D01*
Y397158D01*
X439213Y396808D01*
X439038D01*
Y398408D01*
X439213D01*
G37*
G36*
G01X439735Y394449D02*
X440405Y394099D01*
X440404Y393230D01*
X439735Y392880D01*
X439559Y392879D01*
X439560Y394450D01*
X439735Y394449D01*
G37*
G36*
G01X439179Y391881D02*
X439211Y391126D01*
X438457Y390692D01*
X437820Y391097D01*
X437731Y391248D01*
X439092Y392033D01*
X439179Y391881D01*
G37*
G36*
G01X435799Y389931D02*
X435831Y389176D01*
X435077Y388742D01*
X434440Y389147D01*
X434351Y389298D01*
X435712Y390083D01*
X435799Y389931D01*
G37*
G36*
G01X421216Y383156D02*
X420456Y383506D01*
Y384406D01*
X421216Y384756D01*
X421391D01*
Y383156D01*
X421216D01*
G37*
G36*
G01Y379256D02*
X420456Y379606D01*
Y380506D01*
X421216Y380856D01*
X421391D01*
Y379256D01*
X421216D01*
G37*
G36*
G01X420407Y386254D02*
X419623Y385964D01*
X418986Y386601D01*
X419276Y387385D01*
X419400Y387509D01*
X420531Y386378D01*
X420407Y386254D01*
G37*
G36*
G01X418364Y400577D02*
X417604Y400927D01*
Y401827D01*
X418364Y402177D01*
X418539D01*
Y400577D01*
X418364D01*
G37*
G36*
G01Y396677D02*
X417604Y397027D01*
Y397927D01*
X418364Y398277D01*
X418539D01*
Y396677D01*
X418364D01*
G37*
G36*
G01Y392777D02*
X417604Y393127D01*
Y394027D01*
X418364Y394377D01*
X418539D01*
Y392777D01*
X418364D01*
G37*
G36*
G01X422314Y384756D02*
X423074Y384406D01*
Y383506D01*
X422314Y383156D01*
X422139D01*
Y384756D01*
X422314D01*
G37*
G36*
G01X420053Y388162D02*
X420837Y388452D01*
X421474Y387815D01*
X421184Y387031D01*
X421060Y386907D01*
X419929Y388038D01*
X420053Y388162D01*
G37*
G36*
G01X419464Y402177D02*
X420224Y401827D01*
Y400927D01*
X419464Y400577D01*
X419289D01*
Y402177D01*
X419464D01*
G37*
G36*
G01Y398277D02*
X420224Y397927D01*
Y397027D01*
X419464Y396677D01*
X419289D01*
Y398277D01*
X419464D01*
G37*
G36*
G01Y394377D02*
X420224Y394027D01*
Y393127D01*
X419464Y392777D01*
X419289D01*
Y394377D01*
X419464D01*
G37*
G36*
G01X428723Y385042D02*
X428053Y385392D01*
Y386262D01*
X428723Y386612D01*
X428898D01*
Y385042D01*
X428723D01*
G37*
G36*
G01X429596Y388606D02*
X430266Y388256D01*
Y387386D01*
X429596Y387036D01*
X429421D01*
Y388606D01*
X429596D01*
G37*
G36*
G01X435097Y395259D02*
X434337Y395609D01*
Y396509D01*
X435097Y396859D01*
X435272D01*
Y395259D01*
X435097D01*
G37*
G36*
G01Y399159D02*
X434337Y399509D01*
Y400409D01*
X435097Y400759D01*
X435272D01*
Y399159D01*
X435097D01*
G37*
G36*
G01X431887Y393448D02*
X431855Y394203D01*
X432608Y394638D01*
X433246Y394233D01*
X433334Y394081D01*
X431974Y393297D01*
X431887Y393448D01*
G37*
G36*
G01X436195Y396859D02*
X436955Y396509D01*
Y395609D01*
X436195Y395259D01*
X436020D01*
Y396859D01*
X436195D01*
G37*
G36*
G01Y400759D02*
X436955Y400409D01*
Y399509D01*
X436195Y399159D01*
X436020D01*
Y400759D01*
X436195D01*
G37*
G36*
G01X432435Y391891D02*
X432467Y391136D01*
X431714Y390701D01*
X431076Y391106D01*
X430988Y391257D01*
X432348Y392043D01*
X432435Y391891D01*
G37*
G36*
G01X435815Y393841D02*
X435847Y393086D01*
X435094Y392651D01*
X434456Y393056D01*
X434368Y393207D01*
X435728Y393993D01*
X435815Y393841D01*
G37*
G36*
G01X471912Y379211D02*
X471242Y379561D01*
Y380431D01*
X471912Y380781D01*
X472087D01*
Y379211D01*
X471912D01*
G37*
G36*
G01Y383111D02*
X471242Y383461D01*
Y384331D01*
X471912Y384681D01*
X472087D01*
Y383111D01*
X471912D01*
G37*
G36*
G01Y387011D02*
X471242Y387361D01*
Y388231D01*
X471912Y388581D01*
X472087D01*
Y387011D01*
X471912D01*
G37*
G36*
G01X471911Y394836D02*
X471241Y395186D01*
Y396056D01*
X471911Y396406D01*
X472086D01*
Y394836D01*
X471911D01*
G37*
G36*
G01Y398736D02*
X471241Y399086D01*
Y399956D01*
X471911Y400306D01*
X472086D01*
Y398736D01*
X471911D01*
G37*
G36*
G01Y390936D02*
X471241Y391286D01*
Y392156D01*
X471911Y392506D01*
X472086D01*
Y390936D01*
X471911D01*
G37*
G36*
G01Y402636D02*
X471241Y402986D01*
Y403856D01*
X471911Y404206D01*
X472086D01*
Y402636D01*
X471911D01*
G37*
G36*
G01X472541Y375018D02*
X473296Y375050D01*
X473731Y374296D01*
X473326Y373658D01*
X473174Y373571D01*
X472389Y374930D01*
X472541Y375018D01*
G37*
G36*
G01X473536Y386631D02*
X474206Y386281D01*
Y385411D01*
X473536Y385061D01*
X473361D01*
Y386631D01*
X473536D01*
G37*
G36*
G01Y382731D02*
X474206Y382381D01*
Y381511D01*
X473536Y381161D01*
X473361D01*
Y382731D01*
X473536D01*
G37*
G36*
G01Y390531D02*
X474206Y390181D01*
Y389311D01*
X473536Y388961D01*
X473361D01*
Y390531D01*
X473536D01*
G37*
G36*
G01X473535Y402207D02*
X474205Y401857D01*
Y400987D01*
X473535Y400637D01*
X473360D01*
Y402207D01*
X473535D01*
G37*
G36*
G01Y398307D02*
X474205Y397957D01*
Y397087D01*
X473535Y396737D01*
X473360D01*
Y398307D01*
X473535D01*
G37*
G36*
G01Y394407D02*
X474205Y394057D01*
Y393187D01*
X473535Y392837D01*
X473360D01*
Y394407D01*
X473535D01*
G37*
G36*
G01X468532Y377261D02*
X467862Y377611D01*
Y378481D01*
X468532Y378831D01*
X468707D01*
Y377261D01*
X468532D01*
G37*
G36*
G01Y381161D02*
X467862Y381511D01*
Y382381D01*
X468532Y382731D01*
X468707D01*
Y381161D01*
X468532D01*
G37*
G36*
G01Y385061D02*
X467862Y385411D01*
Y386281D01*
X468532Y386631D01*
X468707D01*
Y385061D01*
X468532D01*
G37*
G36*
G01Y388961D02*
X467862Y389311D01*
Y390181D01*
X468532Y390531D01*
X468707D01*
Y388961D01*
X468532D01*
G37*
G36*
G01X468531Y400637D02*
X467861Y400987D01*
Y401857D01*
X468531Y402207D01*
X468706D01*
Y400637D01*
X468531D01*
G37*
G36*
G01Y392837D02*
X467861Y393187D01*
Y394057D01*
X468531Y394407D01*
X468706D01*
Y392837D01*
X468531D01*
G37*
G36*
G01Y396737D02*
X467861Y397087D01*
Y397957D01*
X468531Y398307D01*
X468706D01*
Y396737D01*
X468531D01*
G37*
G36*
G01X470156Y380781D02*
X470826Y380431D01*
Y379561D01*
X470156Y379211D01*
X469981D01*
Y380781D01*
X470156D01*
G37*
G36*
G01Y384681D02*
X470826Y384331D01*
Y383461D01*
X470156Y383111D01*
X469981D01*
Y384681D01*
X470156D01*
G37*
G36*
G01Y388581D02*
X470826Y388231D01*
Y387361D01*
X470156Y387011D01*
X469981D01*
Y388581D01*
X470156D01*
G37*
G36*
G01X470155Y404206D02*
X470825Y403856D01*
Y402986D01*
X470155Y402636D01*
X469980D01*
Y404206D01*
X470155D01*
G37*
G36*
G01Y400306D02*
X470825Y399956D01*
Y399086D01*
X470155Y398736D01*
X469980D01*
Y400306D01*
X470155D01*
G37*
G36*
G01Y396406D02*
X470825Y396056D01*
Y395186D01*
X470155Y394836D01*
X469980D01*
Y396406D01*
X470155D01*
G37*
G36*
G01Y392506D02*
X470825Y392156D01*
Y391286D01*
X470155Y390936D01*
X469980D01*
Y392506D01*
X470155D01*
G37*
G36*
G01X426216Y386634D02*
X426886Y386284D01*
Y385414D01*
X426216Y385064D01*
X426041D01*
Y386634D01*
X426216D01*
G37*
G36*
G01Y390534D02*
X426886Y390184D01*
Y389314D01*
X426216Y388964D01*
X426041D01*
Y390534D01*
X426216D01*
G37*
G36*
G01X428779Y403844D02*
X429069Y403060D01*
X428432Y402423D01*
X427648Y402713D01*
X427524Y402837D01*
X428655Y403968D01*
X428779Y403844D01*
G37*
G36*
G01X426215Y400225D02*
X426975Y399875D01*
Y398975D01*
X426215Y398625D01*
X426040D01*
Y400225D01*
X426215D01*
G37*
G36*
G01Y396325D02*
X426975Y395975D01*
Y395075D01*
X426215Y394725D01*
X426040D01*
Y396325D01*
X426215D01*
G37*
G36*
G01X476914Y372981D02*
X477584Y372631D01*
Y371761D01*
X476914Y371411D01*
X476739D01*
Y372981D01*
X476914D01*
G37*
G36*
G01Y376881D02*
X477584Y376531D01*
Y375661D01*
X476914Y375311D01*
X476739D01*
Y376881D01*
X476914D01*
G37*
G36*
G01Y384681D02*
X477584Y384331D01*
Y383461D01*
X476914Y383111D01*
X476739D01*
Y384681D01*
X476914D01*
G37*
G36*
G01Y380781D02*
X477584Y380431D01*
Y379561D01*
X476914Y379211D01*
X476739D01*
Y380781D01*
X476914D01*
G37*
G36*
G01Y388581D02*
X477584Y388231D01*
Y387361D01*
X476914Y387011D01*
X476739D01*
Y388581D01*
X476914D01*
G37*
G36*
G01X476915Y400317D02*
X477585Y399967D01*
Y399097D01*
X476915Y398747D01*
X476740D01*
Y400317D01*
X476915D01*
G37*
G36*
G01Y396417D02*
X477585Y396067D01*
Y395197D01*
X476915Y394847D01*
X476740D01*
Y396417D01*
X476915D01*
G37*
G36*
G01Y392517D02*
X477585Y392167D01*
Y391297D01*
X476915Y390947D01*
X476740D01*
Y392517D01*
X476915D01*
G37*
G36*
G01X429700Y396469D02*
X429410Y397254D01*
X430046Y397890D01*
X430831Y397600D01*
X430955Y397477D01*
X429824Y396345D01*
X429700Y396469D01*
G37*
G36*
G01X432077Y399067D02*
X431317Y399417D01*
Y400317D01*
X432077Y400667D01*
X432252D01*
Y399067D01*
X432077D01*
G37*
G36*
G01X424592Y383114D02*
X423922Y383464D01*
Y384334D01*
X424592Y384684D01*
X424767D01*
Y383114D01*
X424592D01*
G37*
G36*
G01Y387014D02*
X423922Y387364D01*
Y388234D01*
X424592Y388584D01*
X424767D01*
Y387014D01*
X424592D01*
G37*
G36*
G01X425115Y398625D02*
X424355Y398975D01*
Y399875D01*
X425115Y400225D01*
X425290D01*
Y398625D01*
X425115D01*
G37*
G36*
G01Y394725D02*
X424355Y395075D01*
Y395975D01*
X425115Y396325D01*
X425290D01*
Y394725D01*
X425115D01*
G37*
G36*
G01X424592Y390914D02*
X423922Y391264D01*
Y392134D01*
X424592Y392484D01*
X424767D01*
Y390914D01*
X424592D01*
G37*
G36*
G01X475290Y377261D02*
X474620Y377611D01*
Y378481D01*
X475290Y378831D01*
X475465D01*
Y377261D01*
X475290D01*
G37*
G36*
G01Y373361D02*
X474620Y373711D01*
Y374581D01*
X475290Y374931D01*
X475465D01*
Y373361D01*
X475290D01*
G37*
G36*
G01Y385061D02*
X474620Y385411D01*
Y386281D01*
X475290Y386631D01*
X475465D01*
Y385061D01*
X475290D01*
G37*
G36*
G01Y381161D02*
X474620Y381511D01*
Y382381D01*
X475290Y382731D01*
X475465D01*
Y381161D01*
X475290D01*
G37*
G36*
G01Y388926D02*
X474620Y389276D01*
Y390146D01*
X475290Y390496D01*
X475465D01*
Y388926D01*
X475290D01*
G37*
G36*
G01Y396726D02*
X474620Y397076D01*
Y397946D01*
X475290Y398296D01*
X475465D01*
Y396726D01*
X475290D01*
G37*
G36*
G01Y392826D02*
X474620Y393176D01*
Y394046D01*
X475290Y394396D01*
X475465D01*
Y392826D01*
X475290D01*
G37*
G36*
G01Y400626D02*
X474620Y400976D01*
Y401846D01*
X475290Y402196D01*
X475465D01*
Y400626D01*
X475290D01*
G37*
G36*
G01X433177Y400667D02*
X433937Y400317D01*
Y399417D01*
X433177Y399067D01*
X433002D01*
Y400667D01*
X433177D01*
G37*
G36*
G01X431609Y396823D02*
X431899Y396038D01*
X431263Y395401D01*
X430478Y395691D01*
X430354Y395815D01*
X431486Y396946D01*
X431609Y396823D01*
G37*
G36*
G01X451631Y375313D02*
X450961Y375663D01*
Y376533D01*
X451631Y376883D01*
X451806D01*
Y375313D01*
X451631D01*
G37*
G36*
G01Y379213D02*
X450961Y379563D01*
Y380433D01*
X451631Y380783D01*
X451806D01*
Y379213D01*
X451631D01*
G37*
G36*
G01Y383113D02*
X450961Y383463D01*
Y384333D01*
X451631Y384683D01*
X451806D01*
Y383113D01*
X451631D01*
G37*
G36*
G01Y387013D02*
X450961Y387363D01*
Y388233D01*
X451631Y388583D01*
X451806D01*
Y387013D01*
X451631D01*
G37*
G36*
G01Y402636D02*
X450961Y402986D01*
Y403856D01*
X451631Y404206D01*
X451806D01*
Y402636D01*
X451631D01*
G37*
G36*
G01Y390913D02*
X450961Y391263D01*
Y392133D01*
X451631Y392483D01*
X451806D01*
Y390913D01*
X451631D01*
G37*
G36*
G01Y394836D02*
X450961Y395186D01*
Y396056D01*
X451631Y396406D01*
X451806D01*
Y394836D01*
X451631D01*
G37*
G36*
G01Y398736D02*
X450961Y399086D01*
Y399956D01*
X451631Y400306D01*
X451806D01*
Y398736D01*
X451631D01*
G37*
G36*
G01X452483Y374764D02*
X453238Y374722D01*
X453596Y373929D01*
X453130Y373334D01*
X452971Y373262D01*
X452324Y374692D01*
X452483Y374764D01*
G37*
G36*
G01X453255Y386633D02*
X453925Y386283D01*
Y385413D01*
X453255Y385063D01*
X453080D01*
Y386633D01*
X453255D01*
G37*
G36*
G01Y382733D02*
X453925Y382383D01*
Y381513D01*
X453255Y381163D01*
X453080D01*
Y382733D01*
X453255D01*
G37*
G36*
G01Y390533D02*
X453925Y390183D01*
Y389313D01*
X453255Y388963D01*
X453080D01*
Y390533D01*
X453255D01*
G37*
G36*
G01Y402207D02*
X453925Y401857D01*
Y400987D01*
X453255Y400637D01*
X453080D01*
Y402207D01*
X453255D01*
G37*
G36*
G01Y398307D02*
X453925Y397957D01*
Y397087D01*
X453255Y396737D01*
X453080D01*
Y398307D01*
X453255D01*
G37*
G36*
G01Y394433D02*
X453925Y394083D01*
Y393213D01*
X453255Y392863D01*
X453080D01*
Y394433D01*
X453255D01*
G37*
G36*
G01X462384Y374071D02*
X461874Y374629D01*
X462172Y375447D01*
X462921Y375547D01*
X463085Y375487D01*
X462549Y374011D01*
X462384Y374071D01*
G37*
G36*
G01X465151Y379213D02*
X464481Y379563D01*
Y380433D01*
X465151Y380783D01*
X465326D01*
Y379213D01*
X465151D01*
G37*
G36*
G01Y383113D02*
X464481Y383463D01*
Y384333D01*
X465151Y384683D01*
X465326D01*
Y383113D01*
X465151D01*
G37*
G36*
G01Y387013D02*
X464481Y387363D01*
Y388233D01*
X465151Y388583D01*
X465326D01*
Y387013D01*
X465151D01*
G37*
G36*
G01Y402611D02*
X464481Y402961D01*
Y403831D01*
X465151Y404181D01*
X465326D01*
Y402611D01*
X465151D01*
G37*
G36*
G01Y390913D02*
X464481Y391263D01*
Y392133D01*
X465151Y392483D01*
X465326D01*
Y390913D01*
X465151D01*
G37*
G36*
G01Y394786D02*
X464481Y395136D01*
Y396006D01*
X465151Y396356D01*
X465326D01*
Y394786D01*
X465151D01*
G37*
G36*
G01Y398675D02*
X464481Y399025D01*
Y399895D01*
X465151Y400245D01*
X465326D01*
Y398675D01*
X465151D01*
G37*
G36*
G01X466775Y378833D02*
X467445Y378483D01*
Y377613D01*
X466775Y377263D01*
X466600D01*
Y378833D01*
X466775D01*
G37*
G36*
G01Y386633D02*
X467445Y386283D01*
Y385413D01*
X466775Y385063D01*
X466600D01*
Y386633D01*
X466775D01*
G37*
G36*
G01Y382733D02*
X467445Y382383D01*
Y381513D01*
X466775Y381163D01*
X466600D01*
Y382733D01*
X466775D01*
G37*
G36*
G01Y390533D02*
X467445Y390183D01*
Y389313D01*
X466775Y388963D01*
X466600D01*
Y390533D01*
X466775D01*
G37*
G36*
G01Y402255D02*
X467445Y401905D01*
Y401035D01*
X466775Y400685D01*
X466600D01*
Y402255D01*
X466775D01*
G37*
G36*
G01Y398365D02*
X467445Y398015D01*
Y397145D01*
X466775Y396795D01*
X466600D01*
Y398365D01*
X466775D01*
G37*
G36*
G01Y394455D02*
X467445Y394105D01*
Y393235D01*
X466775Y392885D01*
X466600D01*
Y394455D01*
X466775D01*
G37*
G36*
G01X448251Y373363D02*
X447581Y373713D01*
Y374583D01*
X448251Y374933D01*
X448426D01*
Y373363D01*
X448251D01*
G37*
G36*
G01Y377263D02*
X447581Y377613D01*
Y378483D01*
X448251Y378833D01*
X448426D01*
Y377263D01*
X448251D01*
G37*
G36*
G01Y381163D02*
X447581Y381513D01*
Y382383D01*
X448251Y382733D01*
X448426D01*
Y381163D01*
X448251D01*
G37*
G36*
G01Y385063D02*
X447581Y385413D01*
Y386283D01*
X448251Y386633D01*
X448426D01*
Y385063D01*
X448251D01*
G37*
G36*
G01Y388963D02*
X447581Y389313D01*
Y390183D01*
X448251Y390533D01*
X448426D01*
Y388963D01*
X448251D01*
G37*
G36*
G01Y400637D02*
X447581Y400987D01*
Y401857D01*
X448251Y402207D01*
X448426D01*
Y400637D01*
X448251D01*
G37*
G36*
G01Y392837D02*
X447581Y393187D01*
Y394057D01*
X448251Y394407D01*
X448426D01*
Y392837D01*
X448251D01*
G37*
G36*
G01Y396737D02*
X447581Y397087D01*
Y397957D01*
X448251Y398307D01*
X448426D01*
Y396737D01*
X448251D01*
G37*
G36*
G01X449875Y384683D02*
X450545Y384333D01*
Y383463D01*
X449875Y383113D01*
X449700D01*
Y384683D01*
X449875D01*
G37*
G36*
G01Y380783D02*
X450545Y380433D01*
Y379563D01*
X449875Y379213D01*
X449700D01*
Y380783D01*
X449875D01*
G37*
G36*
G01Y388583D02*
X450545Y388233D01*
Y387363D01*
X449875Y387013D01*
X449700D01*
Y388583D01*
X449875D01*
G37*
G36*
G01Y404206D02*
X450545Y403856D01*
Y402986D01*
X449875Y402636D01*
X449700D01*
Y404206D01*
X449875D01*
G37*
G36*
G01Y400306D02*
X450545Y399956D01*
Y399086D01*
X449875Y398736D01*
X449700D01*
Y400306D01*
X449875D01*
G37*
G36*
G01Y396406D02*
X450545Y396056D01*
Y395186D01*
X449875Y394836D01*
X449700D01*
Y396406D01*
X449875D01*
G37*
G36*
G01Y392506D02*
X450545Y392156D01*
Y391286D01*
X449875Y390936D01*
X449700D01*
Y392506D01*
X449875D01*
G37*
G36*
G01X459142Y371412D02*
X458472Y371762D01*
Y372632D01*
X459142Y372982D01*
X459317D01*
Y371412D01*
X459142D01*
G37*
G36*
G01X461771Y381163D02*
X461101Y381513D01*
Y382383D01*
X461771Y382733D01*
X461946D01*
Y381163D01*
X461771D01*
G37*
G36*
G01Y385063D02*
X461101Y385413D01*
Y386283D01*
X461771Y386633D01*
X461946D01*
Y385063D01*
X461771D01*
G37*
G36*
G01X461772Y388962D02*
X461102Y389312D01*
Y390182D01*
X461772Y390532D01*
X461947D01*
Y388962D01*
X461772D01*
G37*
G36*
G01X461771Y400660D02*
X461101Y401010D01*
Y401880D01*
X461771Y402230D01*
X461946D01*
Y400660D01*
X461771D01*
G37*
G36*
G01Y396784D02*
X461101Y397134D01*
Y398004D01*
X461771Y398354D01*
X461946D01*
Y396784D01*
X461771D01*
G37*
G36*
G01X461772Y392862D02*
X461102Y393212D01*
Y394082D01*
X461772Y394432D01*
X461947D01*
Y392862D01*
X461772D01*
G37*
G36*
G01X463395Y384706D02*
X464065Y384356D01*
Y383486D01*
X463395Y383136D01*
X463220D01*
Y384706D01*
X463395D01*
G37*
G36*
G01Y380806D02*
X464065Y380456D01*
Y379586D01*
X463395Y379236D01*
X463220D01*
Y380806D01*
X463395D01*
G37*
G36*
G01Y388606D02*
X464065Y388256D01*
Y387386D01*
X463395Y387036D01*
X463220D01*
Y388606D01*
X463395D01*
G37*
G36*
G01Y404205D02*
X464065Y403855D01*
Y402985D01*
X463395Y402635D01*
X463220D01*
Y404205D01*
X463395D01*
G37*
G36*
G01Y400280D02*
X464065Y399930D01*
Y399060D01*
X463395Y398710D01*
X463220D01*
Y400280D01*
X463395D01*
G37*
G36*
G01Y396355D02*
X464065Y396005D01*
Y395135D01*
X463395Y394785D01*
X463220D01*
Y396355D01*
X463395D01*
G37*
G36*
G01Y392506D02*
X464065Y392156D01*
Y391286D01*
X463395Y390936D01*
X463220D01*
Y392506D01*
X463395D01*
G37*
G36*
G01X456635Y376881D02*
X457305Y376531D01*
Y375661D01*
X456635Y375311D01*
X456460D01*
Y376881D01*
X456635D01*
G37*
G36*
G01Y372957D02*
X457305Y372607D01*
Y371737D01*
X456635Y371387D01*
X456460D01*
Y372957D01*
X456635D01*
G37*
G36*
G01Y384706D02*
X457305Y384356D01*
Y383486D01*
X456635Y383136D01*
X456460D01*
Y384706D01*
X456635D01*
G37*
G36*
G01Y380806D02*
X457305Y380456D01*
Y379586D01*
X456635Y379236D01*
X456460D01*
Y380806D01*
X456635D01*
G37*
G36*
G01Y388606D02*
X457305Y388256D01*
Y387386D01*
X456635Y387036D01*
X456460D01*
Y388606D01*
X456635D01*
G37*
G36*
G01Y404206D02*
X457305Y403856D01*
Y402986D01*
X456635Y402636D01*
X456460D01*
Y404206D01*
X456635D01*
G37*
G36*
G01Y400306D02*
X457305Y399956D01*
Y399086D01*
X456635Y398736D01*
X456460D01*
Y400306D01*
X456635D01*
G37*
G36*
G01Y396406D02*
X457305Y396056D01*
Y395186D01*
X456635Y394836D01*
X456460D01*
Y396406D01*
X456635D01*
G37*
G36*
G01Y392506D02*
X457305Y392156D01*
Y391286D01*
X456635Y390936D01*
X456460D01*
Y392506D01*
X456635D01*
G37*
G36*
G01X458391Y383113D02*
X457721Y383463D01*
Y384333D01*
X458391Y384683D01*
X458566D01*
Y383113D01*
X458391D01*
G37*
G36*
G01Y387013D02*
X457721Y387363D01*
Y388233D01*
X458391Y388583D01*
X458566D01*
Y387013D01*
X458391D01*
G37*
G36*
G01Y394846D02*
X457721Y395196D01*
Y396066D01*
X458391Y396416D01*
X458566D01*
Y394846D01*
X458391D01*
G37*
G36*
G01Y398746D02*
X457721Y399096D01*
Y399966D01*
X458391Y400316D01*
X458566D01*
Y398746D01*
X458391D01*
G37*
G36*
G01Y390913D02*
X457721Y391263D01*
Y392133D01*
X458391Y392483D01*
X458566D01*
Y390913D01*
X458391D01*
G37*
G36*
G01Y402646D02*
X457721Y402996D01*
Y403866D01*
X458391Y404216D01*
X458566D01*
Y402646D01*
X458391D01*
G37*
G36*
G01X455011Y381137D02*
X454341Y381487D01*
Y382357D01*
X455011Y382707D01*
X455186D01*
Y381137D01*
X455011D01*
G37*
G36*
G01Y385037D02*
X454341Y385387D01*
Y386257D01*
X455011Y386607D01*
X455186D01*
Y385037D01*
X455011D01*
G37*
G36*
G01Y369486D02*
X454341Y369836D01*
Y370706D01*
X455011Y371056D01*
X455186D01*
Y369486D01*
X455011D01*
G37*
G36*
G01Y373386D02*
X454341Y373736D01*
Y374606D01*
X455011Y374956D01*
X455186D01*
Y373386D01*
X455011D01*
G37*
G36*
G01Y377237D02*
X454341Y377587D01*
Y378457D01*
X455011Y378807D01*
X455186D01*
Y377237D01*
X455011D01*
G37*
G36*
G01Y388937D02*
X454341Y389287D01*
Y390157D01*
X455011Y390507D01*
X455186D01*
Y388937D01*
X455011D01*
G37*
G36*
G01Y400637D02*
X454341Y400987D01*
Y401857D01*
X455011Y402207D01*
X455186D01*
Y400637D01*
X455011D01*
G37*
G36*
G01Y396737D02*
X454341Y397087D01*
Y397957D01*
X455011Y398307D01*
X455186D01*
Y396737D01*
X455011D01*
G37*
G36*
G01Y392837D02*
X454341Y393187D01*
Y394057D01*
X455011Y394407D01*
X455186D01*
Y392837D01*
X455011D01*
G37*
G36*
G01X460015Y386633D02*
X460685Y386283D01*
Y385413D01*
X460015Y385063D01*
X459840D01*
Y386633D01*
X460015D01*
G37*
G36*
G01Y382733D02*
X460685Y382383D01*
Y381513D01*
X460015Y381163D01*
X459840D01*
Y382733D01*
X460015D01*
G37*
G36*
G01Y390533D02*
X460685Y390183D01*
Y389313D01*
X460015Y388963D01*
X459840D01*
Y390533D01*
X460015D01*
G37*
G36*
G01Y402196D02*
X460685Y401846D01*
Y400976D01*
X460015Y400626D01*
X459840D01*
Y402196D01*
X460015D01*
G37*
G36*
G01Y398296D02*
X460685Y397946D01*
Y397076D01*
X460015Y396726D01*
X459840D01*
Y398296D01*
X460015D01*
G37*
G36*
G01Y394407D02*
X460685Y394057D01*
Y393187D01*
X460015Y392837D01*
X459840D01*
Y394407D01*
X460015D01*
G37*
G36*
G01X424936Y411149D02*
X424176Y411499D01*
Y412399D01*
X424936Y412749D01*
X425111D01*
Y411149D01*
X424936D01*
G37*
G36*
G01Y407249D02*
X424176Y407599D01*
Y408499D01*
X424936Y408849D01*
X425111D01*
Y407249D01*
X424936D01*
G37*
G36*
G01Y415049D02*
X424176Y415399D01*
Y416299D01*
X424936Y416649D01*
X425111D01*
Y415049D01*
X424936D01*
G37*
G36*
G01X422561Y404753D02*
X422271Y405538D01*
X422907Y406174D01*
X423692Y405884D01*
X423816Y405761D01*
X422684Y404629D01*
X422561Y404753D01*
G37*
G36*
G01X426034Y412749D02*
X426794Y412399D01*
Y411499D01*
X426034Y411149D01*
X425859D01*
Y412749D01*
X426034D01*
G37*
G36*
G01Y408849D02*
X426794Y408499D01*
Y407599D01*
X426034Y407249D01*
X425859D01*
Y408849D01*
X426034D01*
G37*
G36*
G01Y416649D02*
X426794Y416299D01*
Y415399D01*
X426034Y415049D01*
X425859D01*
Y416649D01*
X426034D01*
G37*
G36*
G01X424468Y405108D02*
X424758Y404323D01*
X424122Y403687D01*
X423337Y403977D01*
X423213Y404100D01*
X424345Y405232D01*
X424468Y405108D01*
G37*
G36*
G01X439733Y405446D02*
X439443Y406230D01*
X440080Y406867D01*
X440864Y406577D01*
X440988Y406453D01*
X439857Y405322D01*
X439733Y405446D01*
G37*
G36*
G01X441859Y406020D02*
X442149Y405236D01*
X441512Y404599D01*
X440728Y404889D01*
X440604Y405013D01*
X441735Y406144D01*
X441859Y406020D01*
G37*
G36*
G01X419966Y406795D02*
X419206Y407145D01*
Y408045D01*
X419966Y408395D01*
X420141D01*
Y406795D01*
X419966D01*
G37*
G36*
G01Y410695D02*
X419206Y411045D01*
Y411945D01*
X419966Y412295D01*
X420141D01*
Y410695D01*
X419966D01*
G37*
G36*
G01X421066Y408395D02*
X421826Y408045D01*
Y407145D01*
X421066Y406795D01*
X420891D01*
Y408395D01*
X421066D01*
G37*
G36*
G01Y412295D02*
X421826Y411945D01*
Y411045D01*
X421066Y410695D01*
X420891D01*
Y412295D01*
X421066D01*
G37*
G36*
G01X437260Y407835D02*
X436500Y408185D01*
Y409085D01*
X437260Y409435D01*
X437435D01*
Y407835D01*
X437260D01*
G37*
G36*
G01X435097Y403059D02*
X434337Y403409D01*
Y404309D01*
X435097Y404659D01*
X435272D01*
Y403059D01*
X435097D01*
G37*
G36*
G01X436195Y404659D02*
X436955Y404309D01*
Y403409D01*
X436195Y403059D01*
X436020D01*
Y404659D01*
X436195D01*
G37*
G36*
G01X438358Y409435D02*
X439118Y409085D01*
Y408185D01*
X438358Y407835D01*
X438183D01*
Y409435D01*
X438358D01*
G37*
G36*
G01X475290Y412326D02*
X474620Y412676D01*
Y413546D01*
X475290Y413896D01*
X475465D01*
Y412326D01*
X475290D01*
G37*
G36*
G01X475831Y414903D02*
X475799Y415658D01*
X476553Y416092D01*
X477190Y415687D01*
X477278Y415536D01*
X475919Y414750D01*
X475831Y414903D01*
G37*
G36*
G01X475290Y408426D02*
X474620Y408776D01*
Y409646D01*
X475290Y409996D01*
X475465D01*
Y408426D01*
X475290D01*
G37*
G36*
G01X476375Y405540D02*
X476406Y404785D01*
X475653Y404350D01*
X475015Y404755D01*
X474927Y404907D01*
X476287Y405692D01*
X476375Y405540D01*
G37*
G36*
G01X476915Y408117D02*
X477585Y407767D01*
Y406897D01*
X476915Y406547D01*
X476740D01*
Y408117D01*
X476915D01*
G37*
G36*
G01Y412017D02*
X477585Y411667D01*
Y410797D01*
X476915Y410447D01*
X476740D01*
Y412017D01*
X476915D01*
G37*
G36*
G01X468531Y404537D02*
X467861Y404887D01*
Y405757D01*
X468531Y406107D01*
X468706D01*
Y404537D01*
X468531D01*
G37*
G36*
G01X469073Y407104D02*
X469041Y407859D01*
X469794Y408293D01*
X470432Y407888D01*
X470520Y407737D01*
X469159Y406952D01*
X469073Y407104D01*
G37*
G36*
G01X471911Y410436D02*
X471241Y410786D01*
Y411656D01*
X471911Y412006D01*
X472086D01*
Y410436D01*
X471911D01*
G37*
G36*
G01Y414336D02*
X471241Y414686D01*
Y415556D01*
X471911Y415906D01*
X472086D01*
Y414336D01*
X471911D01*
G37*
G36*
G01X472467Y416862D02*
X472435Y417617D01*
X473189Y418051D01*
X473826Y417646D01*
X473915Y417495D01*
X472554Y416710D01*
X472467Y416862D01*
G37*
G36*
G01X475820Y418796D02*
X475788Y419551D01*
X476541Y419986D01*
X477179Y419581D01*
X477267Y419430D01*
X475907Y418645D01*
X475820Y418796D01*
G37*
G36*
G01X473535Y410007D02*
X474205Y409657D01*
Y408787D01*
X473535Y408437D01*
X473360D01*
Y410007D01*
X473535D01*
G37*
G36*
G01X472979Y407481D02*
X473011Y406726D01*
X472257Y406292D01*
X471620Y406697D01*
X471531Y406848D01*
X472892Y407633D01*
X472979Y407481D01*
G37*
G36*
G01X476374Y417241D02*
X476406Y416486D01*
X475653Y416051D01*
X475015Y416456D01*
X474927Y416607D01*
X476287Y417393D01*
X476374Y417241D01*
G37*
G36*
G01X473535Y413907D02*
X474205Y413557D01*
Y412687D01*
X473535Y412337D01*
X473360D01*
Y413907D01*
X473535D01*
G37*
G36*
G01X430753Y410626D02*
X431513Y410276D01*
Y409376D01*
X430753Y409026D01*
X430578D01*
Y410626D01*
X430753D01*
G37*
G36*
G01Y414526D02*
X431513Y414176D01*
Y413276D01*
X430753Y412926D01*
X430578D01*
Y414526D01*
X430753D01*
G37*
G36*
G01X433103Y410952D02*
X432343Y411302D01*
Y412202D01*
X433103Y412552D01*
X433278D01*
Y410952D01*
X433103D01*
G37*
G36*
G01X432077Y402967D02*
X431317Y403317D01*
Y404217D01*
X432077Y404567D01*
X432252D01*
Y402967D01*
X432077D01*
G37*
G36*
G01X433103Y407052D02*
X432343Y407402D01*
Y408302D01*
X433103Y408652D01*
X433278D01*
Y407052D01*
X433103D01*
G37*
G36*
G01Y414852D02*
X432343Y415202D01*
Y416102D01*
X433103Y416452D01*
X433278D01*
Y414852D01*
X433103D01*
G37*
G36*
G01X426870Y403491D02*
X426580Y404276D01*
X427216Y404912D01*
X428001Y404622D01*
X428125Y404499D01*
X426993Y403367D01*
X426870Y403491D01*
G37*
G36*
G01X429653Y412926D02*
X428893Y413276D01*
Y414176D01*
X429653Y414526D01*
X429828D01*
Y412926D01*
X429653D01*
G37*
G36*
G01Y409026D02*
X428893Y409376D01*
Y410276D01*
X429653Y410626D01*
X429828D01*
Y409026D01*
X429653D01*
G37*
G36*
G01X475831Y403203D02*
X475799Y403958D01*
X476553Y404392D01*
X477190Y403987D01*
X477278Y403836D01*
X475919Y403050D01*
X475831Y403203D01*
G37*
G36*
G01X433177Y404567D02*
X433937Y404217D01*
Y403317D01*
X433177Y402967D01*
X433002D01*
Y404567D01*
X433177D01*
G37*
G36*
G01X434203Y416452D02*
X434963Y416102D01*
Y415202D01*
X434203Y414852D01*
X434028D01*
Y416452D01*
X434203D01*
G37*
G36*
G01Y408652D02*
X434963Y408302D01*
Y407402D01*
X434203Y407052D01*
X434028D01*
Y408652D01*
X434203D01*
G37*
G36*
G01Y412552D02*
X434963Y412202D01*
Y411302D01*
X434203Y410952D01*
X434028D01*
Y412552D01*
X434203D01*
G37*
G36*
G01X451631Y406536D02*
X450961Y406886D01*
Y407756D01*
X451631Y408106D01*
X451806D01*
Y406536D01*
X451631D01*
G37*
G36*
G01Y410436D02*
X450961Y410786D01*
Y411656D01*
X451631Y412006D01*
X451806D01*
Y410436D01*
X451631D01*
G37*
G36*
G01Y414294D02*
X450961Y414644D01*
X450962Y415513D01*
X451631Y415863D01*
X451807Y415864D01*
X451806Y414293D01*
X451631Y414294D01*
G37*
G36*
G01X452187Y416862D02*
X452155Y417617D01*
X452909Y418051D01*
X453546Y417646D01*
X453635Y417495D01*
X452274Y416710D01*
X452187Y416862D01*
G37*
G36*
G01X453255Y410007D02*
X453925Y409657D01*
Y408787D01*
X453255Y408437D01*
X453080D01*
Y410007D01*
X453255D01*
G37*
G36*
G01Y406107D02*
X453925Y405757D01*
Y404887D01*
X453255Y404537D01*
X453080D01*
Y406107D01*
X453255D01*
G37*
G36*
G01X456115Y417253D02*
X456147Y416498D01*
X455394Y416063D01*
X454756Y416468D01*
X454668Y416619D01*
X456028Y417405D01*
X456115Y417253D01*
G37*
G36*
G01X453255Y413907D02*
X453925Y413557D01*
Y412687D01*
X453255Y412337D01*
X453080D01*
Y413907D01*
X453255D01*
G37*
G36*
G01X456635Y419806D02*
X457305Y419456D01*
Y418586D01*
X456635Y418236D01*
X456460D01*
Y419806D01*
X456635D01*
G37*
G36*
G01X465151Y406536D02*
X464481Y406886D01*
Y407756D01*
X465151Y408106D01*
X465326D01*
Y406536D01*
X465151D01*
G37*
G36*
G01X465686Y409048D02*
X465654Y409803D01*
X466407Y410238D01*
X467045Y409833D01*
X467133Y409682D01*
X465773Y408896D01*
X465686Y409048D01*
G37*
G36*
G01X468531Y412337D02*
X467861Y412687D01*
Y413557D01*
X468531Y413907D01*
X468706D01*
Y412337D01*
X468531D01*
G37*
G36*
G01X468510Y416237D02*
X467840Y416587D01*
Y417457D01*
X468510Y417807D01*
X468685D01*
Y416237D01*
X468510D01*
G37*
G36*
G01X469072Y418802D02*
X469040Y419557D01*
X469793Y419992D01*
X470431Y419587D01*
X470519Y419436D01*
X469159Y418650D01*
X469072Y418802D01*
G37*
G36*
G01X469614Y409441D02*
X469646Y408686D01*
X468893Y408251D01*
X468255Y408656D01*
X468167Y408807D01*
X469527Y409593D01*
X469614Y409441D01*
G37*
G36*
G01X466775Y406107D02*
X467445Y405757D01*
Y404887D01*
X466775Y404537D01*
X466600D01*
Y406107D01*
X466775D01*
G37*
G36*
G01X470155Y412006D02*
X470825Y411656D01*
Y410786D01*
X470155Y410436D01*
X469980D01*
Y412006D01*
X470155D01*
G37*
G36*
G01Y415906D02*
X470825Y415556D01*
Y414686D01*
X470155Y414336D01*
X469980D01*
Y415906D01*
X470155D01*
G37*
G36*
G01X473000Y419195D02*
X473032Y418440D01*
X472279Y418005D01*
X471641Y418410D01*
X471553Y418561D01*
X472913Y419347D01*
X473000Y419195D01*
G37*
G36*
G01X448251Y404537D02*
X447581Y404887D01*
Y405757D01*
X448251Y406107D01*
X448426D01*
Y404537D01*
X448251D01*
G37*
G36*
G01Y412337D02*
X447581Y412687D01*
Y413557D01*
X448251Y413907D01*
X448426D01*
Y412337D01*
X448251D01*
G37*
G36*
G01X449773Y419424D02*
X449013Y419774D01*
Y420674D01*
X449773Y421024D01*
X449948D01*
Y419424D01*
X449773D01*
G37*
G36*
G01X449875Y415906D02*
X450545Y415556D01*
Y414686D01*
X449875Y414336D01*
X449700D01*
Y415906D01*
X449875D01*
G37*
G36*
G01Y412006D02*
X450545Y411656D01*
Y410786D01*
X449875Y410436D01*
X449700D01*
Y412006D01*
X449875D01*
G37*
G36*
G01Y408106D02*
X450545Y407756D01*
Y406886D01*
X449875Y406536D01*
X449700D01*
Y408106D01*
X449875D01*
G37*
G36*
G01X450873Y420810D02*
X451633Y420460D01*
Y419560D01*
X450873Y419210D01*
X450698D01*
Y420810D01*
X450873D01*
G37*
G36*
G01X461771Y408426D02*
X461101Y408776D01*
Y409646D01*
X461771Y409996D01*
X461946D01*
Y408426D01*
X461771D01*
G37*
G36*
G01Y404526D02*
X461101Y404876D01*
Y405746D01*
X461771Y406096D01*
X461946D01*
Y404526D01*
X461771D01*
G37*
G36*
G01X462312Y411003D02*
X462280Y411758D01*
X463034Y412192D01*
X463671Y411787D01*
X463760Y411636D01*
X462399Y410851D01*
X462312Y411003D01*
G37*
G36*
G01X465151Y414336D02*
X464481Y414686D01*
Y415556D01*
X465151Y415906D01*
X465326D01*
Y414336D01*
X465151D01*
G37*
G36*
G01X466219Y411381D02*
X466251Y410626D01*
X465497Y410192D01*
X464860Y410597D01*
X464771Y410748D01*
X466132Y411533D01*
X466219Y411381D01*
G37*
G36*
G01X463395Y408116D02*
X464065Y407766D01*
Y406896D01*
X463395Y406546D01*
X463220D01*
Y408116D01*
X463395D01*
G37*
G36*
G01X466775Y413949D02*
X467445Y413599D01*
X467444Y412730D01*
X466775Y412380D01*
X466599Y412379D01*
X466600Y413950D01*
X466775Y413949D01*
G37*
G36*
G01X466770Y417849D02*
X467440Y417499D01*
X467439Y416630D01*
X466770Y416280D01*
X466594Y416279D01*
X466595Y417850D01*
X466770Y417849D01*
G37*
G36*
G01X456635Y412006D02*
X457305Y411656D01*
Y410786D01*
X456635Y410436D01*
X456460D01*
Y412006D01*
X456635D01*
G37*
G36*
G01Y408106D02*
X457305Y407756D01*
Y406886D01*
X456635Y406536D01*
X456460D01*
Y408106D01*
X456635D01*
G37*
G36*
G01X459455Y415279D02*
X459487Y414524D01*
X458734Y414089D01*
X458096Y414495D01*
X458008Y414646D01*
X459368Y415431D01*
X459455Y415279D01*
G37*
G36*
G01X458391Y410446D02*
X457721Y410796D01*
Y411666D01*
X458391Y412016D01*
X458566D01*
Y410446D01*
X458391D01*
G37*
G36*
G01Y406546D02*
X457721Y406896D01*
Y407766D01*
X458391Y408116D01*
X458566D01*
Y406546D01*
X458391D01*
G37*
G36*
G01X458993Y412987D02*
X458961Y413743D01*
X459715Y414178D01*
X460353Y413772D01*
X460441Y413621D01*
X459081Y412836D01*
X458993Y412987D01*
G37*
G36*
G01X461771Y416226D02*
X461101Y416576D01*
Y417446D01*
X461771Y417796D01*
X461946D01*
Y416226D01*
X461771D01*
G37*
G36*
G01X462973Y420256D02*
X462213Y420606D01*
Y421506D01*
X462973Y421856D01*
X463148D01*
Y420256D01*
X462973D01*
G37*
G36*
G01X455011Y404537D02*
X454341Y404887D01*
Y405757D01*
X455011Y406107D01*
X455186D01*
Y404537D01*
X455011D01*
G37*
G36*
G01Y408437D02*
X454341Y408787D01*
Y409657D01*
X455011Y410007D01*
X455186D01*
Y408437D01*
X455011D01*
G37*
G36*
G01Y412337D02*
X454341Y412687D01*
Y413557D01*
X455011Y413907D01*
X455186D01*
Y412337D01*
X455011D01*
G37*
G36*
G01X455553Y414904D02*
X455521Y415659D01*
X456274Y416093D01*
X456912Y415688D01*
X457000Y415537D01*
X455639Y414752D01*
X455553Y414904D01*
G37*
G36*
G01X460015Y409996D02*
X460685Y409646D01*
Y408776D01*
X460015Y408426D01*
X459840D01*
Y409996D01*
X460015D01*
G37*
G36*
G01Y406096D02*
X460685Y405746D01*
Y404876D01*
X460015Y404526D01*
X459840D01*
Y406096D01*
X460015D01*
G37*
G36*
G01X463395Y415916D02*
X464064Y415566D01*
Y414696D01*
X463394Y414346D01*
X463219D01*
Y415916D01*
X463395D01*
G37*
G36*
G01X462855Y413339D02*
X462886Y412584D01*
X462133Y412149D01*
X461495Y412554D01*
X461407Y412706D01*
X462767Y413491D01*
X462855Y413339D01*
G37*
G36*
G01X464073Y421700D02*
X464833Y421350D01*
Y420450D01*
X464073Y420100D01*
X463898D01*
Y421700D01*
X464073D01*
G37*
G36*
G01X479650Y199847D02*
X478865Y199557D01*
X478229Y200193D01*
X478519Y200978D01*
X478642Y201102D01*
X479774Y199970D01*
X479650Y199847D01*
G37*
G36*
G01X479295Y201754D02*
X480080Y202044D01*
X480716Y201408D01*
X480426Y200623D01*
X480303Y200499D01*
X479171Y201631D01*
X479295Y201754D01*
G37*
G36*
G01X484310Y217337D02*
X483640Y217687D01*
Y218557D01*
X484310Y218907D01*
X484485D01*
Y217337D01*
X484310D01*
G37*
G36*
G01Y213437D02*
X483640Y213787D01*
Y214657D01*
X484310Y215007D01*
X484485D01*
Y213437D01*
X484310D01*
G37*
G36*
G01X485934Y217006D02*
X486604Y216656D01*
Y215786D01*
X485934Y215436D01*
X485759D01*
Y217006D01*
X485934D01*
G37*
G36*
G01X486204Y207809D02*
X485566Y207404D01*
X484813Y207839D01*
X484845Y208594D01*
X484932Y208746D01*
X486292Y207960D01*
X486204Y207809D01*
G37*
G36*
G01X491479Y206216D02*
X490694Y205926D01*
X490058Y206562D01*
X490348Y207347D01*
X490471Y207471D01*
X491603Y206339D01*
X491479Y206216D01*
G37*
G36*
G01X480930Y215436D02*
X480260Y215786D01*
Y216656D01*
X480930Y217006D01*
X481105D01*
Y215436D01*
X480930D01*
G37*
G36*
G01Y211536D02*
X480260Y211886D01*
Y212756D01*
X480930Y213106D01*
X481105D01*
Y211536D01*
X480930D01*
G37*
G36*
G01X484040Y210933D02*
X484678Y211338D01*
X485431Y210903D01*
X485399Y210148D01*
X485312Y209996D01*
X483952Y210782D01*
X484040Y210933D01*
G37*
G36*
G01X491126Y208125D02*
X491910Y208415D01*
X492547Y207778D01*
X492257Y206994D01*
X492133Y206870D01*
X491002Y208001D01*
X491126Y208125D01*
G37*
G36*
G01X482554Y218907D02*
X483224Y218557D01*
Y217687D01*
X482554Y217337D01*
X482379D01*
Y218907D01*
X482554D01*
G37*
G36*
G01Y215007D02*
X483224Y214657D01*
Y213787D01*
X482554Y213437D01*
X482379D01*
Y215007D01*
X482554D01*
G37*
G36*
G01X483426Y202935D02*
X484210Y203225D01*
X484847Y202588D01*
X484557Y201804D01*
X484433Y201680D01*
X483302Y202811D01*
X483426Y202935D01*
G37*
G36*
G01X480607Y209015D02*
X481245Y209420D01*
X481998Y208985D01*
X481966Y208230D01*
X481879Y208078D01*
X480519Y208864D01*
X480607Y209015D01*
G37*
G36*
G01X479174Y213081D02*
X479844Y212731D01*
Y211861D01*
X479174Y211511D01*
X478999D01*
Y213081D01*
X479174D01*
G37*
G36*
G01Y217006D02*
X479844Y216656D01*
Y215786D01*
X479174Y215436D01*
X478999D01*
Y217006D01*
X479174D01*
G37*
G36*
G01X483779Y201026D02*
X482994Y200736D01*
X482358Y201372D01*
X482648Y202157D01*
X482771Y202281D01*
X483903Y201149D01*
X483779Y201026D01*
G37*
G36*
G01X484310Y225137D02*
X483640Y225487D01*
Y226357D01*
X484310Y226707D01*
X484485D01*
Y225137D01*
X484310D01*
G37*
G36*
G01Y221237D02*
X483640Y221587D01*
Y222457D01*
X484310Y222807D01*
X484485D01*
Y221237D01*
X484310D01*
G37*
G36*
G01Y229062D02*
X483640Y229412D01*
Y230282D01*
X484310Y230632D01*
X484485D01*
Y229062D01*
X484310D01*
G37*
G36*
G01X482824Y233159D02*
X482186Y232754D01*
X481433Y233189D01*
X481465Y233944D01*
X481552Y234096D01*
X482912Y233310D01*
X482824Y233159D01*
G37*
G36*
G01X479459Y235101D02*
X478821Y234696D01*
X478068Y235131D01*
X478100Y235886D01*
X478187Y236038D01*
X479547Y235252D01*
X479459Y235101D01*
G37*
G36*
G01X485934Y220906D02*
X486604Y220556D01*
Y219686D01*
X485934Y219336D01*
X485759D01*
Y220906D01*
X485934D01*
G37*
G36*
G01Y228706D02*
X486604Y228356D01*
Y227486D01*
X485934Y227136D01*
X485759D01*
Y228706D01*
X485934D01*
G37*
G36*
G01Y224806D02*
X486604Y224456D01*
Y223586D01*
X485934Y223236D01*
X485759D01*
Y224806D01*
X485934D01*
G37*
G36*
G01X484033Y234338D02*
X484671Y234743D01*
X485424Y234309D01*
X485392Y233554D01*
X485305Y233401D01*
X483946Y234187D01*
X484033Y234338D01*
G37*
G36*
G01X480645Y236292D02*
X481283Y236697D01*
X482036Y236262D01*
X482004Y235507D01*
X481917Y235355D01*
X480557Y236141D01*
X480645Y236292D01*
G37*
G36*
G01X480930Y227136D02*
X480260Y227486D01*
Y228356D01*
X480930Y228706D01*
X481105D01*
Y227136D01*
X480930D01*
G37*
G36*
G01Y223236D02*
X480260Y223586D01*
Y224456D01*
X480930Y224806D01*
X481105D01*
Y223236D01*
X480930D01*
G37*
G36*
G01Y219336D02*
X480260Y219686D01*
Y220556D01*
X480930Y220906D01*
X481105D01*
Y219336D01*
X480930D01*
G37*
G36*
G01X482554Y226707D02*
X483224Y226357D01*
Y225487D01*
X482554Y225137D01*
X482379D01*
Y226707D01*
X482554D01*
G37*
G36*
G01Y222807D02*
X483224Y222457D01*
Y221587D01*
X482554Y221237D01*
X482379D01*
Y222807D01*
X482554D01*
G37*
G36*
G01X479174Y224806D02*
X479844Y224456D01*
Y223586D01*
X479174Y223236D01*
X478999D01*
Y224806D01*
X479174D01*
G37*
G36*
G01Y220906D02*
X479844Y220556D01*
Y219686D01*
X479174Y219336D01*
X478999D01*
Y220906D01*
X479174D01*
G37*
G36*
G01X530400Y315300D02*
Y300300D01*
X529330Y299230D01*
X529197Y299307D01*
G03X527114Y298362I-706J-1211D01*
G01X527083Y298200D01*
X523139D01*
X523108Y298362D01*
G03X520354I-1377J-266D01*
G01X520323Y298200D01*
X516380D01*
X516349Y298362D01*
G03X513595I-1377J-266D01*
G01X513564Y298200D01*
X509620D01*
X509589Y298362D01*
G03X506835I-1377J-266D01*
G01X506804Y298200D01*
X503900D01*
X502700Y299400D01*
Y301356D01*
X502719Y301396D01*
G03Y302596I-1267J600D01*
G01X502700Y302636D01*
Y305256D01*
X502719Y305296D01*
G03Y306496I-1267J600D01*
G01X502700Y306536D01*
Y309157D01*
X502719Y309197D01*
G03Y310397I-1267J600D01*
G01X502700Y310437D01*
Y313056D01*
X502719Y313096D01*
G03X502805Y314063I-1267J600D01*
G01X502775Y314175D01*
X503265Y314665D01*
G02X503833Y314663I283J-283D01*
G03X506189Y315999I999J984D01*
G02X506576Y316500I387J101D01*
G01X507338D01*
G03X509086I874J1096D01*
G01X509848D01*
G02X510235Y315999I0J-400D01*
G03X512949I1357J-352D01*
G02X513336Y316500I387J101D01*
G01X514098D01*
G03X515846I874J1096D01*
G01X516608D01*
G02X516995Y315999I0J-400D01*
G03X519709I1357J-352D01*
G02X520096Y316500I387J101D01*
G01X520857D01*
G03X522605I874J1096D01*
G01X523367D01*
G02X523754Y315999I0J-400D01*
G03X526468I1357J-352D01*
G02X526855Y316500I387J101D01*
G01X527617D01*
G03X529145Y316356I874J1096D01*
G01X529275Y316425D01*
X530400Y315300D01*
G37*
G36*
G01X485430Y379236D02*
X484760Y379586D01*
Y380456D01*
X485430Y380806D01*
X485605D01*
Y379236D01*
X485430D01*
G37*
G36*
G01X482923Y373001D02*
X483593Y372651D01*
Y371781D01*
X482923Y371431D01*
X482748D01*
Y373001D01*
X482923D01*
G37*
G36*
G01Y369101D02*
X483593Y368751D01*
Y367881D01*
X482923Y367531D01*
X482748D01*
Y369101D01*
X482923D01*
G37*
G36*
G01X485430Y383136D02*
X484760Y383486D01*
Y384356D01*
X485430Y384706D01*
X485605D01*
Y383136D01*
X485430D01*
G37*
G36*
G01Y387036D02*
X484760Y387386D01*
Y388256D01*
X485430Y388606D01*
X485605D01*
Y387036D01*
X485430D01*
G37*
G36*
G01X488810Y400637D02*
X488140Y400987D01*
Y401857D01*
X488810Y402207D01*
X488985D01*
Y400637D01*
X488810D01*
G37*
G36*
G01X485430Y390936D02*
X484760Y391286D01*
Y392156D01*
X485430Y392506D01*
X485605D01*
Y390936D01*
X485430D01*
G37*
G36*
G01Y394836D02*
X484760Y395186D01*
Y396056D01*
X485430Y396406D01*
X485605D01*
Y394836D01*
X485430D01*
G37*
G36*
G01X485965Y397349D02*
X485933Y398104D01*
X486686Y398539D01*
X487324Y398134D01*
X487411Y397983D01*
X486051Y397198D01*
X485965Y397349D01*
G37*
G36*
G01X486342Y376138D02*
X486678Y375460D01*
X486166Y374757D01*
X485418Y374869D01*
X485277Y374972D01*
X486201Y376241D01*
X486342Y376138D01*
G37*
G36*
G01X487054Y378807D02*
X487724Y378457D01*
Y377587D01*
X487054Y377237D01*
X486879D01*
Y378807D01*
X487054D01*
G37*
G36*
G01Y386607D02*
X487724Y386257D01*
Y385387D01*
X487054Y385037D01*
X486879D01*
Y386607D01*
X487054D01*
G37*
G36*
G01Y382707D02*
X487724Y382357D01*
Y381487D01*
X487054Y381137D01*
X486879D01*
Y382707D01*
X487054D01*
G37*
G36*
G01Y390507D02*
X487724Y390157D01*
Y389287D01*
X487054Y388937D01*
X486879D01*
Y390507D01*
X487054D01*
G37*
G36*
G01X490434Y404206D02*
X491104Y403856D01*
Y402986D01*
X490434Y402636D01*
X490259D01*
Y404206D01*
X490434D01*
G37*
G36*
G01X489899Y397744D02*
X489931Y396989D01*
X489178Y396554D01*
X488540Y396959D01*
X488452Y397110D01*
X489812Y397896D01*
X489899Y397744D01*
G37*
G36*
G01X487054Y394432D02*
X487724Y394082D01*
Y393212D01*
X487054Y392862D01*
X486879D01*
Y394432D01*
X487054D01*
G37*
G36*
G01X490433Y400324D02*
X491103Y399974D01*
Y399104D01*
X490433Y398754D01*
X490258Y398753D01*
Y400324D01*
X490433D01*
G37*
G36*
G01X480478Y369515D02*
X479723Y369563D01*
X479370Y370358D01*
X479841Y370950D01*
X480001Y371020D01*
X480638Y369585D01*
X480478Y369515D01*
G37*
G36*
G01X480253Y374970D02*
X480924Y374622D01*
X480927Y373752D01*
X480258Y373400D01*
X480083D01*
X480078Y374970D01*
X480253D01*
G37*
G36*
G01X482050Y381161D02*
X481380Y381511D01*
Y382381D01*
X482050Y382731D01*
X482225D01*
Y381161D01*
X482050D01*
G37*
G36*
G01Y385061D02*
X481380Y385411D01*
Y386281D01*
X482050Y386631D01*
X482225D01*
Y385061D01*
X482050D01*
G37*
G36*
G01X482051Y388961D02*
X481381Y389311D01*
Y390181D01*
X482051Y390531D01*
X482226D01*
Y388961D01*
X482051D01*
G37*
G36*
G01X485430Y402636D02*
X484760Y402986D01*
Y403856D01*
X485430Y404206D01*
X485605D01*
Y402636D01*
X485430D01*
G37*
G36*
G01X482050Y396737D02*
X481380Y397087D01*
Y397957D01*
X482050Y398307D01*
X482225D01*
Y396737D01*
X482050D01*
G37*
G36*
G01Y392837D02*
X481380Y393187D01*
Y394057D01*
X482050Y394407D01*
X482225D01*
Y392837D01*
X482050D01*
G37*
G36*
G01X482592Y399304D02*
X482560Y400059D01*
X483313Y400493D01*
X483951Y400088D01*
X484039Y399937D01*
X482679Y399151D01*
X482592Y399304D01*
G37*
G36*
G01X483104Y377901D02*
X483365Y377191D01*
X482781Y376547D01*
X482049Y376738D01*
X481920Y376855D01*
X482974Y378018D01*
X483104Y377901D01*
G37*
G36*
G01X483674Y384681D02*
X484344Y384331D01*
Y383461D01*
X483674Y383111D01*
X483499D01*
Y384681D01*
X483674D01*
G37*
G36*
G01X483673Y380781D02*
X484343Y380431D01*
Y379561D01*
X483673Y379211D01*
X483498D01*
Y380781D01*
X483673D01*
G37*
G36*
G01X483674Y388581D02*
X484344Y388231D01*
Y387361D01*
X483674Y387011D01*
X483499D01*
Y388581D01*
X483674D01*
G37*
G36*
G01X487054Y402207D02*
X487724Y401857D01*
Y400987D01*
X487054Y400637D01*
X486879D01*
Y402207D01*
X487054D01*
G37*
G36*
G01X486498Y399681D02*
X486530Y398926D01*
X485776Y398492D01*
X485139Y398897D01*
X485050Y399048D01*
X486410Y399834D01*
X486498Y399681D01*
G37*
G36*
G01X483674Y396406D02*
X484344Y396056D01*
Y395186D01*
X483674Y394836D01*
X483499D01*
Y396406D01*
X483674D01*
G37*
G36*
G01Y392506D02*
X484344Y392156D01*
Y391286D01*
X483674Y390936D01*
X483499D01*
Y392506D01*
X483674D01*
G37*
G36*
G01X479738Y403581D02*
X479770Y402826D01*
X479016Y402392D01*
X478379Y402797D01*
X478291Y402948D01*
X479651Y403733D01*
X479738Y403581D01*
G37*
G36*
G01X478670Y383113D02*
X478000Y383463D01*
Y384333D01*
X478670Y384683D01*
X478845D01*
Y383113D01*
X478670D01*
G37*
G36*
G01Y387013D02*
X478000Y387363D01*
Y388233D01*
X478670Y388583D01*
X478845D01*
Y387013D01*
X478670D01*
G37*
G36*
G01X479226Y401262D02*
X479194Y402017D01*
X479948Y402451D01*
X480585Y402046D01*
X480673Y401895D01*
X479314Y401109D01*
X479226Y401262D01*
G37*
G36*
G01X478670Y398736D02*
X478000Y399086D01*
Y399956D01*
X478670Y400306D01*
X478845D01*
Y398736D01*
X478670D01*
G37*
G36*
G01Y390936D02*
X478000Y391286D01*
Y392156D01*
X478670Y392506D01*
X478845D01*
Y390936D01*
X478670D01*
G37*
G36*
G01Y394836D02*
X478000Y395186D01*
Y396056D01*
X478670Y396406D01*
X478845D01*
Y394836D01*
X478670D01*
G37*
G36*
G01X480294Y386633D02*
X480964Y386283D01*
Y385413D01*
X480294Y385063D01*
X480119D01*
Y386633D01*
X480294D01*
G37*
G36*
G01Y382733D02*
X480964Y382383D01*
Y381513D01*
X480294Y381163D01*
X480119D01*
Y382733D01*
X480294D01*
G37*
G36*
G01Y390533D02*
X480964Y390183D01*
Y389313D01*
X480294Y388963D01*
X480119D01*
Y390533D01*
X480294D01*
G37*
G36*
G01X483674Y404206D02*
X484344Y403856D01*
Y402986D01*
X483674Y402636D01*
X483499D01*
Y404206D01*
X483674D01*
G37*
G36*
G01X483132Y401639D02*
X483164Y400884D01*
X482411Y400450D01*
X481773Y400855D01*
X481686Y401006D01*
X483046Y401791D01*
X483132Y401639D01*
G37*
G36*
G01X480294Y394407D02*
X480964Y394057D01*
Y393187D01*
X480294Y392837D01*
X480119D01*
Y394407D01*
X480294D01*
G37*
G36*
G01Y398307D02*
X480964Y397957D01*
Y397087D01*
X480294Y396737D01*
X480119D01*
Y398307D01*
X480294D01*
G37*
G36*
G01X479205Y416848D02*
X479173Y417603D01*
X479926Y418038D01*
X480564Y417633D01*
X480652Y417482D01*
X479292Y416696D01*
X479205Y416848D01*
G37*
G36*
G01X483135Y417241D02*
X483167Y416486D01*
X482414Y416051D01*
X481776Y416456D01*
X481688Y416607D01*
X483048Y417393D01*
X483135Y417241D01*
G37*
G36*
G01X479759Y415295D02*
X479791Y414540D01*
X479038Y414105D01*
X478400Y414510D01*
X478312Y414661D01*
X479672Y415447D01*
X479759Y415295D01*
G37*
G36*
G01X489352Y407104D02*
X489320Y407859D01*
X490073Y408293D01*
X490711Y407888D01*
X490798Y407737D01*
X489438Y406952D01*
X489352Y407104D01*
G37*
G36*
G01X488810Y404537D02*
X488140Y404887D01*
Y405757D01*
X488810Y406107D01*
X488985D01*
Y404537D01*
X488810D01*
G37*
G36*
G01X492725Y409048D02*
X492693Y409803D01*
X493446Y410238D01*
X494084Y409833D01*
X494172Y409682D01*
X492812Y408896D01*
X492725Y409048D01*
G37*
G36*
G01X496105Y410998D02*
X496073Y411753D01*
X496826Y412188D01*
X497464Y411783D01*
X497552Y411632D01*
X496192Y410846D01*
X496105Y410998D01*
G37*
G36*
G01X496659Y409444D02*
X496691Y408689D01*
X495938Y408254D01*
X495300Y408659D01*
X495212Y408810D01*
X496572Y409595D01*
X496659Y409444D01*
G37*
G36*
G01X493279Y407495D02*
X493311Y406740D01*
X492558Y406305D01*
X491920Y406710D01*
X491832Y406861D01*
X493192Y407647D01*
X493279Y407495D01*
G37*
G36*
G01X479765Y419196D02*
X479797Y418441D01*
X479044Y418006D01*
X478406Y418411D01*
X478318Y418562D01*
X479678Y419347D01*
X479765Y419196D01*
G37*
G36*
G01X485430Y406536D02*
X484760Y406886D01*
Y407756D01*
X485430Y408106D01*
X485605D01*
Y406536D01*
X485430D01*
G37*
G36*
G01X489351Y411002D02*
X489319Y411757D01*
X490072Y412192D01*
X490710Y411787D01*
X490798Y411636D01*
X489438Y410850D01*
X489351Y411002D01*
G37*
G36*
G01X492725Y412948D02*
X492693Y413703D01*
X493446Y414138D01*
X494084Y413733D01*
X494172Y413582D01*
X492812Y412796D01*
X492725Y412948D01*
G37*
G36*
G01X489893Y409441D02*
X489925Y408686D01*
X489172Y408251D01*
X488534Y408656D01*
X488446Y408807D01*
X489806Y409593D01*
X489893Y409441D01*
G37*
G36*
G01X487054Y406107D02*
X487724Y405757D01*
Y404887D01*
X487054Y404537D01*
X486879D01*
Y406107D01*
X487054D01*
G37*
G36*
G01X493279Y411395D02*
X493311Y410640D01*
X492558Y410205D01*
X491920Y410610D01*
X491832Y410761D01*
X493192Y411547D01*
X493279Y411395D01*
G37*
G36*
G01X496659Y413344D02*
X496691Y412589D01*
X495938Y412154D01*
X495300Y412559D01*
X495212Y412710D01*
X496572Y413495D01*
X496659Y413344D01*
G37*
G36*
G01X480294Y406107D02*
X480964Y405757D01*
Y404887D01*
X480294Y404537D01*
X480119D01*
Y406107D01*
X480294D01*
G37*
G36*
G01Y410007D02*
X480964Y409657D01*
Y408787D01*
X480294Y408437D01*
X480119D01*
Y410007D01*
X480294D01*
G37*
G36*
G01X486519Y415295D02*
X486551Y414540D01*
X485798Y414105D01*
X485160Y414510D01*
X485072Y414661D01*
X486432Y415447D01*
X486519Y415295D01*
G37*
G36*
G01X483133Y413341D02*
X483165Y412586D01*
X482412Y412151D01*
X481774Y412556D01*
X481686Y412707D01*
X483046Y413493D01*
X483133Y413341D01*
G37*
G36*
G01X482050Y408437D02*
X481380Y408787D01*
Y409657D01*
X482050Y410007D01*
X482225D01*
Y408437D01*
X482050D01*
G37*
G36*
G01Y404537D02*
X481380Y404887D01*
Y405757D01*
X482050Y406107D01*
X482225D01*
Y404537D01*
X482050D01*
G37*
G36*
G01X482592Y411004D02*
X482560Y411759D01*
X483313Y412193D01*
X483951Y411788D01*
X484039Y411637D01*
X482679Y410851D01*
X482592Y411004D01*
G37*
G36*
G01X489351Y414902D02*
X489319Y415657D01*
X490072Y416092D01*
X490710Y415687D01*
X490798Y415536D01*
X489438Y414750D01*
X489351Y414902D01*
G37*
G36*
G01X485965Y412949D02*
X485933Y413704D01*
X486686Y414138D01*
X487324Y413733D01*
X487412Y413582D01*
X486052Y412796D01*
X485965Y412949D01*
G37*
G36*
G01X478670Y410436D02*
X478000Y410786D01*
Y411656D01*
X478670Y412006D01*
X478845D01*
Y410436D01*
X478670D01*
G37*
G36*
G01X482591Y414902D02*
X482559Y415657D01*
X483312Y416092D01*
X483950Y415687D01*
X484038Y415536D01*
X482678Y414750D01*
X482591Y414902D01*
G37*
G36*
G01X478670Y406536D02*
X478000Y406886D01*
Y407756D01*
X478670Y408106D01*
X478845D01*
Y406536D01*
X478670D01*
G37*
G36*
G01X479226Y412962D02*
X479194Y413717D01*
X479948Y414151D01*
X480585Y413746D01*
X480673Y413595D01*
X479314Y412809D01*
X479226Y412962D01*
G37*
G36*
G01X486519Y411395D02*
X486551Y410640D01*
X485798Y410205D01*
X485160Y410610D01*
X485072Y410761D01*
X486432Y411547D01*
X486519Y411395D01*
G37*
G36*
G01X483674Y408106D02*
X484344Y407756D01*
Y406886D01*
X483674Y406536D01*
X483499D01*
Y408106D01*
X483674D01*
G37*
G36*
G01X489893Y413341D02*
X489925Y412586D01*
X489172Y412151D01*
X488534Y412556D01*
X488446Y412707D01*
X489806Y413493D01*
X489893Y413341D01*
G37*
G36*
G01X493279Y415295D02*
X493311Y414540D01*
X492558Y414105D01*
X491920Y414510D01*
X491832Y414661D01*
X493192Y415447D01*
X493279Y415295D01*
G37*
G36*
G01X702700Y198800D02*
X699700Y201800D01*
Y223598D01*
G02X700288Y223951I400J0D01*
G03X703075Y223931I1413J2649D01*
G03X707042Y225085I1375J2669D01*
G03X707353Y224977I612J1261D01*
G02X707510Y224764I-42J-195D01*
G03X710601Y221500I2990J-264D01*
G02X710807Y221315I6J-200D01*
G03X712761Y218728I2993J229D01*
G03X712725Y218306I2966J-466D01*
G03X713781Y212870I1666J-2497D01*
G03X716470Y213643I1319J475D01*
G03X717393Y215770I-2079J2166D01*
G03X716766Y221083I-1666J2497D01*
G03X716453Y222948I-2966J461D01*
G03X712380Y226840I-2753J1196D01*
G03X709040Y227123I-1880J-2340D01*
G02X708781Y227179I-98J175D01*
G03X707247Y227689I-1128J-832D01*
G03X703075Y229269I-2798J-1089D01*
G03X700288Y229249I-1374J-2669D01*
G02X699700Y229602I-188J353D01*
G01Y234400D01*
X701300Y236000D01*
X726797D01*
G03X729141I1172J770D01*
G01X730700D01*
X734050Y239350D01*
Y245897D01*
G03X734664Y247769I-2388J1820D01*
G01Y249771D01*
X734050Y250385D01*
Y274350D01*
X734600Y274900D01*
Y288600D01*
X741932Y295932D01*
X741985Y295945D01*
G03X743754Y300512I-735J2911D01*
G02X744030Y301129I333J221D01*
G03X742718Y306969I-429J2971D01*
G02X742200Y307352I-118J382D01*
G01Y311339D01*
X742360Y311372D01*
G03X744518Y318544I-848J4166D01*
G01X743064Y319999D01*
Y331240D01*
G02X743710Y331555I400J0D01*
G03Y334077I988J1261D01*
G02X743064Y334392I-246J315D01*
G01Y375512D01*
G03Y377414I-1290J951D01*
G01Y391364D01*
X747600Y395900D01*
X755900D01*
X759100Y399100D01*
X762479D01*
G03X764187I854J1112D01*
G01X776100D01*
X783800Y391400D01*
Y372475D01*
G03Y372325I1600J-75D01*
G01Y219610D01*
X777690Y213500D01*
X774734D01*
Y214033D01*
G03X767730I-3502J0D01*
G01Y210547D01*
X767899Y210379D01*
X766500Y208980D01*
X748280D01*
X738100Y198800D01*
X717946D01*
X717904Y198945D01*
G03X715210I-1347J-388D01*
G01X715168Y198800D01*
X710608D01*
X710577Y198963D01*
G03X707823I-1377J-263D01*
G01X707792Y198800D01*
X702700D01*
G37*
G36*
G01X811300Y206200D02*
X806400D01*
X804291Y204091D01*
X804151Y204207D01*
G03X801662Y203600I-1017J-1238D01*
G01X785400D01*
X784838Y204162D01*
Y213890D01*
X784842Y213894D01*
Y365477D01*
X785625Y366260D01*
X817630D01*
Y366161D01*
X818300Y365490D01*
Y209500D01*
X815700Y206900D01*
X812000D01*
X811300Y206200D01*
G37*
G36*
G01X785896Y368262D02*
X785100Y369058D01*
Y371850D01*
X785075Y371875D01*
Y400423D01*
X785402Y400750D01*
X792640D01*
X794355Y399035D01*
X812665D01*
X816168Y395532D01*
Y377424D01*
X817630Y375963D01*
Y368420D01*
X817471Y368262D01*
X785896D01*
G37*
G36*
G01X823008Y208900D02*
X821308Y210600D01*
Y362700D01*
X822368Y363760D01*
X834200D01*
X844661Y353300D01*
X851124D01*
X895204Y309220D01*
X896080D01*
X900911Y304389D01*
X919015D01*
X919057Y304244D01*
G03X921622Y303662I1443J416D01*
G02X922154Y303721I299J-266D01*
G03X922995Y303274I2074J2887D01*
G03X923368Y303208I371J1010D01*
G01X924297D01*
X924329D01*
G03X926140Y303795I-102J3401D01*
G02X926411Y303751I112J-165D01*
G03X928803I1196J909D01*
G02X929074Y303795I159J-121D01*
G03X930885Y303208I1913J2814D01*
G01X931057D01*
X931089D01*
G03X932900Y303795I-102J3401D01*
G02X933171Y303751I112J-165D01*
G03X935563I1196J909D01*
G02X935834Y303795I159J-121D01*
G03X939660I1913J2814D01*
G02X939931Y303751I112J-165D01*
G03X942570Y304244I1196J909D01*
G01X942612Y304389D01*
X946402D01*
X946444Y304244D01*
G03X949330I1443J416D01*
G01X949372Y304389D01*
X953162D01*
X953204Y304244D01*
G03X956090I1443J416D01*
G01X956132Y304389D01*
X959921D01*
X959963Y304244D01*
G03X962849I1443J416D01*
G01X962891Y304389D01*
X966681D01*
X966723Y304244D01*
G03X969609I1443J416D01*
G01X969651Y304389D01*
X973441D01*
X973483Y304244D01*
G03X976369I1443J416D01*
G01X976411Y304389D01*
X978889D01*
X981561Y307061D01*
X981647Y307059D01*
G03X983187Y308599I39J1501D01*
G01X983185Y308685D01*
X983910Y309410D01*
G02X984178Y309424I142J-141D01*
G03X986151Y311397I888J1085D01*
G01X986037Y311537D01*
X986515Y312015D01*
G02X987164Y311894I283J-283D01*
G03X989012Y313742I1282J566D01*
G02X988891Y314391I162J366D01*
G01X991453Y316953D01*
X991558Y316933D01*
G03X993202Y318577I268J1376D01*
G01X993182Y318682D01*
X993710Y319210D01*
G02X994262Y319223I283J-283D01*
G03X996501Y320798I944J1037D01*
G02X996603Y321057I185J77D01*
G03X998153Y322459I-1397J3103D01*
G03X998607Y324031I-2947J1703D01*
G01X998610Y324110D01*
X999275Y324775D01*
X999301Y324789D01*
G03X999907Y325395I-715J1321D01*
G01X999921Y325421D01*
X1001634Y327134D01*
Y334059D01*
G02X1002019Y334459I400J0D01*
G03X1003260Y336398I-54J1401D01*
G02X1003362Y336657I185J77D01*
G03X1003955Y336999I-1395J3104D01*
G02X1004231Y336958I117J-162D01*
G03X1006640Y338347I1114J851D01*
G02X1006742Y338606I184J77D01*
G03X1007335Y338949I-1399J3102D01*
G02X1007611Y338909I117J-162D01*
G03X1009291Y341043I1114J851D01*
G02X1009086Y341571I161J366D01*
G03X1009160Y341740I-15149J6734D01*
G01X1009175Y341775D01*
X1009900Y342500D01*
Y342893D01*
X1009928Y342941D01*
G03X1010127Y343686I-1203J720D01*
G01X1010125Y343771D01*
X1010624Y344270D01*
X1010693Y344278D01*
G03X1011426Y344382I-2012J16817D01*
G03X1013154Y344679I679J1227D01*
G01X1013214Y344746D01*
X1013346D01*
X1014300Y345700D01*
X1017454D01*
X1017466Y345514D01*
G03X1020264I1399J95D01*
G01X1020276Y345700D01*
X1024214D01*
X1024226Y345514D01*
G03X1027024I1399J95D01*
G01X1027036Y345700D01*
X1027608D01*
X1028267Y346359D01*
X1028395Y346298D01*
G03X1030267Y348170I610J1262D01*
G01X1030206Y348298D01*
X1030643Y348735D01*
G02X1031250Y348687I283J-283D01*
G03X1033207Y350644I1135J822D01*
G02X1033159Y351251I235J324D01*
G01X1033680Y351772D01*
G02X1034363Y351483I283J-282D01*
G03X1035742Y352862I1402J-23D01*
G02X1035453Y353545I-7J400D01*
G01X1035868Y353960D01*
X1035936Y353969D01*
G03X1036872Y354500I-171J1391D01*
G01X1037481D01*
G02X1037850Y353947I0J-400D01*
G03X1040440I1295J-538D01*
G02X1040809Y354500I369J153D01*
G01X1041417D01*
G03X1043631I1107J860D01*
G01X1044240D01*
G02X1044609Y353947I0J-400D01*
G03X1047199I1295J-538D01*
G02X1047568Y354500I369J153D01*
G01X1048177D01*
G03X1050391I1107J860D01*
G01X1051000D01*
G02X1051369Y353947I0J-400D01*
G03X1053959I1295J-538D01*
G02X1054328Y354500I369J153D01*
G01X1059587D01*
G03X1061801I1107J860D01*
G01X1071919D01*
X1071953Y354343D01*
G03X1074528Y353932I1369J304D01*
G02X1075087Y354065I344J-204D01*
G03X1075315Y353933I1617J2530D01*
G02X1075479Y353382I-184J-355D01*
G03X1077925I1223J-686D01*
G02X1078089Y353933I348J196D01*
G03X1078317Y354065I-1389J2662D01*
G02X1078876Y353932I215J-337D01*
G03X1081288I1206J715D01*
G02X1081847Y354065I344J-204D01*
G03X1082075Y353933I1617J2530D01*
G02X1082239Y353382I-184J-355D01*
G03X1084685I1223J-686D01*
G02X1084849Y353933I348J196D01*
G03X1085076Y354064I-1386J2664D01*
G02X1085635Y353931I215J-337D01*
G03X1088047Y353932I1206J716D01*
G02X1088606Y354065I344J-204D01*
G03X1088834Y353933I1617J2530D01*
G02X1088998Y353382I-184J-355D01*
G03X1091425Y351978I1222J-687D01*
G02X1092052Y352056I344J-205D01*
G01X1099708Y344400D01*
X1102300D01*
X1102600Y344100D01*
Y340800D01*
X1100846Y339046D01*
X1098654D01*
X1086800Y327192D01*
Y311466D01*
G02X1086201Y311119I-400J0D01*
G03X1084335Y310681I-699J-1215D01*
G02X1083669I-333J222D01*
G03Y309127I-1167J-777D01*
G02X1084335I333J-222D01*
G03X1086201Y308689I1167J777D01*
G02X1086800Y308342I199J-347D01*
G01Y297574D01*
G02X1086194Y297231I-400J0D01*
G03X1084167Y296920I-827J-1372D01*
G02X1083567I-300J265D01*
G03X1081472Y294530I-1200J-1061D01*
G02X1081527Y293911I-223J-332D01*
G03X1083669Y292127I975J-1007D01*
G02X1084335I333J-222D01*
G03X1086201Y291689I1167J777D01*
G02X1086800Y291342I199J-347D01*
G01Y280707D01*
G02X1086224Y280348I-400J0D01*
G03X1084242Y279879I-706J-1438D01*
G02X1083606I-318J242D01*
G03Y277941I-1276J-969D01*
G02X1084242I318J-242D01*
G03X1086224Y277472I1276J969D01*
G02X1086800Y277113I176J-359D01*
G01Y265900D01*
X1086900Y265800D01*
Y264100D01*
X1086200Y263400D01*
Y255165D01*
X1084900Y254400D01*
X1079754Y254146D01*
X1076214Y250606D01*
X1076092Y250653D01*
G03X1074276Y248837I-510J-1306D01*
G01X1074323Y248715D01*
X1073872Y248264D01*
G02X1073281Y248291I-283J282D01*
G03X1070992Y246687I-1080J-895D01*
G01X1071071Y246554D01*
X1070820Y246303D01*
X1070302Y246822D01*
Y257021D01*
X1070532Y257252D01*
X1073525D01*
X1077928Y261654D01*
Y266257D01*
X1076883Y267302D01*
X1076828D01*
X1076630Y267500D01*
X1038500D01*
Y267404D01*
X1038398Y267302D01*
X1038185D01*
X1022345Y251461D01*
X1022261Y251462D01*
G03X1020843Y250044I-16J-1402D01*
G01X1020844Y249960D01*
X1019927Y249043D01*
X1019786Y249166D01*
G03X1017532Y248542I-921J-1057D01*
G01X1017487Y248404D01*
X1016777D01*
G02X1016490Y249083I0J400D01*
G03X1014480I-1005J977D01*
G02X1014193Y248404I-287J-279D01*
G01X1013483D01*
X1013438Y248542D01*
G03X1010772I-1333J-433D01*
G01X1010727Y248404D01*
X1010017D01*
G02X1009730Y249083I0J400D01*
G03X1007720I-1005J977D01*
G02X1007433Y248404I-287J-279D01*
G01X1006723D01*
X1006678Y248542D01*
G03X1005678Y249471I-1333J-433D01*
G01X1005624Y249484D01*
X1005180Y249928D01*
G02X1005437Y250610I283J283D01*
G03X1003946Y252101I-92J1399D01*
G02X1003264Y251844I-399J26D01*
G01X1002824Y252284D01*
G02X1002854Y252876I283J282D01*
G03X1000881Y254849I-889J1084D01*
G02X1000289Y254819I-310J253D01*
G01X999840Y255268D01*
X999889Y255390D01*
G03X998067Y257212I-1303J519D01*
G01X997945Y257163D01*
X995375Y259733D01*
G02X995558Y260403I283J283D01*
G03X993849Y262112I-352J1357D01*
G02X993179Y261929I-387J100D01*
G01X992885Y262223D01*
G02X992870Y262773I283J283D01*
G03X990890Y264753I-1044J936D01*
G02X990340Y264768I-267J298D01*
G01X989806Y265302D01*
X989825Y265406D01*
G03X988192Y267039I-1379J254D01*
G01X988088Y267020D01*
X985524Y269584D01*
G02X985643Y270231I283J282D01*
G03X983788Y272086I-577J1278D01*
G02X983141Y271967I-365J164D01*
G01X982666Y272442D01*
X982779Y272582D01*
G03X980808Y274553I-1093J878D01*
G01X980668Y274440D01*
X979710Y275398D01*
X979706Y275475D01*
G03X978372Y276809I-1400J-66D01*
G01X978295Y276813D01*
X977877Y277231D01*
G02X978192Y277913I283J283D01*
G03X977146Y278523I114J1397D01*
G01X977239Y278386D01*
X976981Y278127D01*
X976608Y278500D01*
X975742D01*
G03X974110I-816J-1140D01*
G01X973301D01*
G02X972911Y278991I0J400D01*
G03X970181I-1365J319D01*
G02X969791Y278500I-390J-91D01*
G01X968982D01*
G03X967350I-816J-1140D01*
G01X966541D01*
G02X966151Y278991I0J400D01*
G03X963421I-1365J319D01*
G02X963031Y278500I-390J-91D01*
G01X962222D01*
G03X960590I-816J-1140D01*
G01X955463D01*
G03X953831I-816J-1140D01*
G01X948703D01*
G03X947071I-816J-1140D01*
G01X941943D01*
G03X940311I-816J-1140D01*
G01X935183D01*
G03X933551I-816J-1140D01*
G01X928423D01*
G03X926791I-816J-1140D01*
G01X926021D01*
X925426Y278843D01*
X925281Y278751D01*
X925194Y278776D01*
G03X923260I-967J-3367D01*
G01X923173Y278751D01*
X923028Y278843D01*
X921853Y278165D01*
X921860Y277993D01*
X921795Y277930D01*
G03X921193Y277160I2432J-2521D01*
G02X920877Y276962I-346J200D01*
G01X919911D01*
G03X919619Y276925I1J-1177D01*
G01X919539Y276904D01*
X919403Y276983D01*
X918254Y276265D01*
X918258Y276215D01*
G02X918059Y276000I-199J-15D01*
G01X915859D01*
X915178Y276682D01*
X904519D01*
X903838Y276000D01*
X896108D01*
X829008Y208900D01*
X823008D01*
G37*
G36*
G01X908071Y192683D02*
X907781Y193468D01*
X908417Y194104D01*
X909202Y193814D01*
X909326Y193691D01*
X908194Y192559D01*
X908071Y192683D01*
G37*
G36*
G01X909979Y193037D02*
X910269Y192252D01*
X909633Y191616D01*
X908848Y191906D01*
X908724Y192029D01*
X909856Y193161D01*
X909979Y193037D01*
G37*
G36*
G01X907781Y246506D02*
X907021Y246856D01*
Y247756D01*
X907781Y248106D01*
X907956D01*
Y246506D01*
X907781D01*
G37*
G36*
G01X908974Y250238D02*
X908684Y251022D01*
X909321Y251659D01*
X910105Y251369D01*
X910229Y251245D01*
X909098Y250114D01*
X908974Y250238D01*
G37*
G36*
G01X908881Y247906D02*
X909641Y247556D01*
Y246656D01*
X908881Y246306D01*
X908706D01*
Y247906D01*
X908881D01*
G37*
G36*
G01X910883Y250591D02*
X911173Y249806D01*
X910537Y249170D01*
X909752Y249460D01*
X909628Y249583D01*
X910760Y250715D01*
X910883Y250591D01*
G37*
G36*
G01X908578Y254122D02*
X908288Y254907D01*
X908925Y255543D01*
X909710Y255253D01*
X909833Y255129D01*
X908702Y253998D01*
X908578Y254122D01*
G37*
G36*
G01X905821Y251364D02*
X905531Y252149D01*
X906167Y252785D01*
X906952Y252495D01*
X907076Y252372D01*
X905944Y251240D01*
X905821Y251364D01*
G37*
G36*
G01X909128Y253119D02*
X909418Y252334D01*
X908782Y251698D01*
X907997Y251988D01*
X907873Y252111D01*
X909005Y253243D01*
X909128Y253119D01*
G37*
G36*
G01X908306Y341566D02*
X907956Y340806D01*
X907056D01*
X906706Y341566D01*
Y341741D01*
X908306D01*
Y341566D01*
G37*
G36*
G01X908836Y336909D02*
X908486Y336149D01*
X907586D01*
X907236Y336909D01*
Y337084D01*
X908836D01*
Y336909D01*
G37*
G36*
G01X907236Y338009D02*
X907586Y338769D01*
X908486D01*
X908836Y338009D01*
Y337834D01*
X907236D01*
Y338009D01*
G37*
G36*
G01X910513Y352237D02*
X909728Y351947D01*
X909092Y352583D01*
X909382Y353368D01*
X909505Y353492D01*
X910637Y352360D01*
X910513Y352237D01*
G37*
G36*
G01X909611Y378039D02*
X908826Y377749D01*
X908190Y378386D01*
X908480Y379170D01*
X908603Y379294D01*
X909735Y378163D01*
X909611Y378039D01*
G37*
G36*
G01X909256Y379947D02*
X910041Y380237D01*
X910678Y379601D01*
X910388Y378816D01*
X910264Y378692D01*
X909133Y379823D01*
X909256Y379947D01*
G37*
G36*
G01X909902Y346821D02*
X909552Y346151D01*
X908682D01*
X908332Y346821D01*
Y346996D01*
X909902D01*
Y346821D01*
G37*
G36*
G01X906002D02*
X905652Y346151D01*
X904782D01*
X904432Y346821D01*
Y346996D01*
X906002D01*
Y346821D01*
G37*
G36*
G01X908802Y347967D02*
X909152Y348636D01*
X910021D01*
X910371Y347966D01*
Y347791D01*
X908801Y347792D01*
X908802Y347967D01*
G37*
G36*
G01X904902D02*
X905252Y348636D01*
X906121D01*
X906471Y347966D01*
Y347791D01*
X904901Y347792D01*
X904902Y347967D01*
G37*
G36*
G01X906706Y342664D02*
X907056Y343424D01*
X907956D01*
X908306Y342664D01*
Y342489D01*
X906706D01*
Y342664D01*
G37*
G36*
G01X925704Y216745D02*
X925666Y217499D01*
X926415Y217941D01*
X927057Y217540D01*
X927145Y217390D01*
X925793Y216593D01*
X925704Y216745D01*
G37*
G36*
G01X925646Y201116D02*
X925614Y201871D01*
X926367Y202306D01*
X927005Y201901D01*
X927093Y201749D01*
X925733Y200964D01*
X925646Y201116D01*
G37*
G36*
G01X929016Y202218D02*
X928984Y202973D01*
X929737Y203408D01*
X930375Y203003D01*
X930463Y202852D01*
X929103Y202067D01*
X929016Y202218D01*
G37*
G36*
G01X912732Y189104D02*
X912442Y189889D01*
X913078Y190525D01*
X913863Y190235D01*
X913987Y190112D01*
X912855Y188980D01*
X912732Y189104D01*
G37*
G36*
G01X915490Y191862D02*
X915200Y192647D01*
X915836Y193283D01*
X916621Y192993D01*
X916745Y192870D01*
X915613Y191738D01*
X915490Y191862D01*
G37*
G36*
G01X920184Y194961D02*
X919894Y195746D01*
X920531Y196382D01*
X921316Y196092D01*
X921439Y195968D01*
X920308Y194837D01*
X920184Y194961D01*
G37*
G36*
G01X922942Y197719D02*
X922652Y198504D01*
X923289Y199140D01*
X924074Y198850D01*
X924197Y198726D01*
X923066Y197595D01*
X922942Y197719D01*
G37*
G36*
G01X932568Y200201D02*
X932600Y199446D01*
X931847Y199011D01*
X931209Y199416D01*
X931121Y199567D01*
X932481Y200353D01*
X932568Y200201D01*
G37*
G36*
G01X914640Y189458D02*
X914930Y188673D01*
X914294Y188037D01*
X913509Y188327D01*
X913385Y188450D01*
X914517Y189582D01*
X914640Y189458D01*
G37*
G36*
G01X917398Y192216D02*
X917688Y191431D01*
X917052Y190795D01*
X916267Y191085D01*
X916143Y191208D01*
X917275Y192340D01*
X917398Y192216D01*
G37*
G36*
G01X922092Y195315D02*
X922382Y194530D01*
X921746Y193894D01*
X920961Y194184D01*
X920837Y194308D01*
X921968Y195439D01*
X922092Y195315D01*
G37*
G36*
G01X924850Y198073D02*
X925140Y197288D01*
X924504Y196652D01*
X923719Y196942D01*
X923595Y197066D01*
X924726Y198197D01*
X924850Y198073D01*
G37*
G36*
G01X934626Y205370D02*
X935309Y205693D01*
X936002Y205169D01*
X935877Y204424D01*
X935773Y204284D01*
X934519Y205231D01*
X934626Y205370D01*
G37*
G36*
G01X939752Y189625D02*
X939462Y190409D01*
X940099Y191046D01*
X940883Y190756D01*
X941007Y190632D01*
X939876Y189501D01*
X939752Y189625D01*
G37*
G36*
G01X936994Y186867D02*
X936704Y187652D01*
X937341Y188288D01*
X938126Y187998D01*
X938249Y187874D01*
X937118Y186743D01*
X936994Y186867D01*
G37*
G36*
G01X942510Y192382D02*
X942220Y193167D01*
X942856Y193804D01*
X943641Y193514D01*
X943765Y193390D01*
X942634Y192259D01*
X942510Y192382D01*
G37*
G36*
G01X945385Y198550D02*
X944715Y198900D01*
Y199770D01*
X945385Y200120D01*
X945560D01*
Y198550D01*
X945385D01*
G37*
G36*
G01Y202475D02*
X944715Y202825D01*
Y203695D01*
X945385Y204045D01*
X945560D01*
Y202475D01*
X945385D01*
G37*
G36*
G01X941661Y189978D02*
X941951Y189194D01*
X941314Y188557D01*
X940530Y188847D01*
X940406Y188971D01*
X941537Y190102D01*
X941661Y189978D01*
G37*
G36*
G01X938903Y187221D02*
X939193Y186436D01*
X938557Y185799D01*
X937772Y186089D01*
X937648Y186213D01*
X938779Y187344D01*
X938903Y187221D01*
G37*
G36*
G01X944419Y192736D02*
X944709Y191951D01*
X944072Y191315D01*
X943287Y191605D01*
X943164Y191729D01*
X944295Y192860D01*
X944419Y192736D01*
G37*
G36*
G01X947009Y202119D02*
X947679Y201769D01*
Y200899D01*
X947009Y200549D01*
X946834D01*
Y202119D01*
X947009D01*
G37*
G36*
G01Y206019D02*
X947679Y205669D01*
Y204799D01*
X947009Y204449D01*
X946834D01*
Y206019D01*
X947009D01*
G37*
G36*
G01X945136Y207807D02*
X945806Y208155D01*
X946519Y207656D01*
X946421Y206907D01*
X946321Y206764D01*
X945035Y207663D01*
X945136Y207807D01*
G37*
G36*
G01X910829Y195441D02*
X910539Y196226D01*
X911175Y196862D01*
X911960Y196572D01*
X912084Y196449D01*
X910952Y195317D01*
X910829Y195441D01*
G37*
G36*
G01X914586Y197285D02*
X914936Y198045D01*
X915836D01*
X916186Y197285D01*
Y197110D01*
X914586D01*
Y197285D01*
G37*
G36*
G01X918669Y198620D02*
X918379Y199405D01*
X919015Y200041D01*
X919800Y199751D01*
X919924Y199628D01*
X918792Y198496D01*
X918669Y198620D01*
G37*
G36*
G01X922275Y203070D02*
X922243Y203825D01*
X922996Y204260D01*
X923634Y203855D01*
X923722Y203703D01*
X922362Y202918D01*
X922275Y203070D01*
G37*
G36*
G01X925640Y205012D02*
X925608Y205767D01*
X926361Y206202D01*
X926999Y205797D01*
X927087Y205645D01*
X925727Y204861D01*
X925640Y205012D01*
G37*
G36*
G01X912737Y195795D02*
X913027Y195010D01*
X912391Y194374D01*
X911606Y194664D01*
X911482Y194787D01*
X912614Y195919D01*
X912737Y195795D01*
G37*
G36*
G01X916186Y196186D02*
X915836Y195426D01*
X914936D01*
X914586Y196186D01*
Y196361D01*
X916186D01*
Y196186D01*
G37*
G36*
G01X920576Y198975D02*
X920866Y198190D01*
X920230Y197554D01*
X919445Y197844D01*
X919321Y197967D01*
X920453Y199099D01*
X920576Y198975D01*
G37*
G36*
G01X926179Y203449D02*
X926211Y202694D01*
X925458Y202259D01*
X924820Y202664D01*
X924732Y202815D01*
X926092Y203601D01*
X926179Y203449D01*
G37*
G36*
G01X931871Y206353D02*
X931201Y206703D01*
Y207573D01*
X931871Y207923D01*
X932046D01*
Y206353D01*
X931871D01*
G37*
G36*
G01X931365Y188437D02*
X931075Y189222D01*
X931711Y189858D01*
X932496Y189568D01*
X932620Y189445D01*
X931488Y188313D01*
X931365Y188437D01*
G37*
G36*
G01X933583Y189816D02*
X933933Y190576D01*
X934833D01*
X935183Y189816D01*
Y189641D01*
X933583D01*
Y189816D01*
G37*
G36*
G01X936969Y191131D02*
X936679Y191915D01*
X937316Y192552D01*
X938100Y192262D01*
X938224Y192138D01*
X937093Y191007D01*
X936969Y191131D01*
G37*
G36*
G01X939727Y193889D02*
X939437Y194673D01*
X940074Y195310D01*
X940858Y195020D01*
X940982Y194896D01*
X939851Y193765D01*
X939727Y193889D01*
G37*
G36*
G01X942005Y200549D02*
X941335Y200899D01*
Y201769D01*
X942005Y202119D01*
X942180D01*
Y200549D01*
X942005D01*
G37*
G36*
G01X935183Y188716D02*
X934833Y187956D01*
X933933D01*
X933583Y188716D01*
Y188891D01*
X935183D01*
Y188716D01*
G37*
G36*
G01X938878Y191484D02*
X939168Y190699D01*
X938532Y190063D01*
X937747Y190353D01*
X937623Y190476D01*
X938755Y191608D01*
X938878Y191484D01*
G37*
G36*
G01X941636Y194242D02*
X941926Y193457D01*
X941290Y192821D01*
X940505Y193111D01*
X940381Y193234D01*
X941513Y194366D01*
X941636Y194242D01*
G37*
G36*
G01X943629Y200120D02*
X944299Y199770D01*
Y198900D01*
X943629Y198550D01*
X943454D01*
Y200120D01*
X943629D01*
G37*
G36*
G01Y204045D02*
X944299Y203695D01*
Y202825D01*
X943629Y202475D01*
X943454D01*
Y204045D01*
X943629D01*
G37*
G36*
G01X942714Y208239D02*
X943435Y208011D01*
X943586Y207154D01*
X942987Y206693D01*
X942814Y206663D01*
X942542Y208209D01*
X942714Y208239D01*
G37*
G36*
G01X935643Y196917D02*
X935933Y196133D01*
X935296Y195496D01*
X934512Y195786D01*
X934388Y195910D01*
X935519Y197041D01*
X935643Y196917D01*
G37*
G36*
G01X933008Y195276D02*
X932658Y194516D01*
X931758D01*
X931408Y195276D01*
Y195451D01*
X933008D01*
Y195276D01*
G37*
G36*
G01X922737Y191454D02*
X923027Y190669D01*
X922391Y190033D01*
X921606Y190323D01*
X921482Y190446D01*
X922614Y191578D01*
X922737Y191454D01*
G37*
G36*
G01X929108Y195276D02*
X928758Y194516D01*
X927858D01*
X927508Y195276D01*
Y195451D01*
X929108D01*
Y195276D01*
G37*
G36*
G01X925495Y194212D02*
X925785Y193427D01*
X925149Y192791D01*
X924364Y193081D01*
X924240Y193204D01*
X925372Y194336D01*
X925495Y194212D01*
G37*
G36*
G01X937794Y194668D02*
X938084Y193883D01*
X937448Y193247D01*
X936663Y193537D01*
X936539Y193660D01*
X937671Y194792D01*
X937794Y194668D01*
G37*
G36*
G01X933037Y192085D02*
X932687Y191325D01*
X931787D01*
X931437Y192085D01*
Y192260D01*
X933037D01*
Y192085D01*
G37*
G36*
G01X940249Y202119D02*
X940919Y201769D01*
Y200899D01*
X940249Y200549D01*
X940074D01*
Y202119D01*
X940249D01*
G37*
G36*
G01X927214Y189269D02*
X927504Y188484D01*
X926868Y187848D01*
X926083Y188138D01*
X925959Y188261D01*
X927091Y189393D01*
X927214Y189269D01*
G37*
G36*
G01X940249Y205970D02*
X940919Y205620D01*
Y204750D01*
X940249Y204400D01*
X940074D01*
Y205970D01*
X940249D01*
G37*
G36*
G01Y209869D02*
X940919Y209519D01*
Y208649D01*
X940249Y208299D01*
X940074D01*
Y209869D01*
X940249D01*
G37*
G36*
G01X931408Y196376D02*
X931758Y197136D01*
X932658D01*
X933008Y196376D01*
Y196201D01*
X931408D01*
Y196376D01*
G37*
G36*
G01X920828Y191101D02*
X920538Y191885D01*
X921175Y192522D01*
X921959Y192232D01*
X922083Y192108D01*
X920952Y190977D01*
X920828Y191101D01*
G37*
G36*
G01X927508Y196376D02*
X927858Y197136D01*
X928758D01*
X929108Y196376D01*
Y196201D01*
X927508D01*
Y196376D01*
G37*
G36*
G01X923586Y193859D02*
X923296Y194643D01*
X923933Y195280D01*
X924717Y194990D01*
X924841Y194866D01*
X923710Y193735D01*
X923586Y193859D01*
G37*
G36*
G01X931437Y193185D02*
X931787Y193945D01*
X932687D01*
X933037Y193185D01*
Y193010D01*
X931437D01*
Y193185D01*
G37*
G36*
G01X935885Y194315D02*
X935595Y195099D01*
X936232Y195736D01*
X937016Y195446D01*
X937140Y195322D01*
X936009Y194191D01*
X935885Y194315D01*
G37*
G36*
G01X938625Y202475D02*
X937955Y202825D01*
Y203695D01*
X938625Y204045D01*
X938800D01*
Y202475D01*
X938625D01*
G37*
G36*
G01X925305Y188916D02*
X925015Y189700D01*
X925652Y190337D01*
X926436Y190047D01*
X926560Y189923D01*
X925429Y188792D01*
X925305Y188916D01*
G37*
G36*
G01X938625Y206399D02*
X937955Y206749D01*
Y207619D01*
X938625Y207969D01*
X938800D01*
Y206399D01*
X938625D01*
G37*
G36*
G01X964601Y203257D02*
X965361Y202907D01*
Y202007D01*
X964601Y201657D01*
X964426D01*
Y203257D01*
X964601D01*
G37*
G36*
G01Y199357D02*
X965361Y199007D01*
Y198107D01*
X964601Y197757D01*
X964426D01*
Y199357D01*
X964601D01*
G37*
G36*
G01X963908Y211820D02*
X964578Y211470D01*
Y210600D01*
X963908Y210250D01*
X963733D01*
Y211820D01*
X963908D01*
G37*
G36*
G01Y215720D02*
X964578Y215370D01*
Y214500D01*
X963908Y214150D01*
X963733D01*
Y215720D01*
X963908D01*
G37*
G36*
G01X968991Y201972D02*
X969751Y201622D01*
Y200722D01*
X968991Y200372D01*
X968816D01*
Y201972D01*
X968991D01*
G37*
G36*
G01X967411Y217221D02*
X968171Y216871D01*
Y215971D01*
X967411Y215621D01*
X967236D01*
Y217221D01*
X967411D01*
G37*
G36*
G01Y209821D02*
X968171Y209471D01*
Y208571D01*
X967411Y208221D01*
X967236D01*
Y209821D01*
X967411D01*
G37*
G36*
G01Y213721D02*
X968171Y213371D01*
Y212471D01*
X967411Y212121D01*
X967236D01*
Y213721D01*
X967411D01*
G37*
G36*
G01X968991Y205872D02*
X969751Y205522D01*
Y204622D01*
X968991Y204272D01*
X968816D01*
Y205872D01*
X968991D01*
G37*
G36*
G01X963501Y201657D02*
X962741Y202007D01*
Y202907D01*
X963501Y203257D01*
X963676D01*
Y201657D01*
X963501D01*
G37*
G36*
G01Y197757D02*
X962741Y198107D01*
Y199007D01*
X963501Y199357D01*
X963676D01*
Y197757D01*
X963501D01*
G37*
G36*
G01X962284Y216149D02*
X961614Y216499D01*
Y217369D01*
X962284Y217719D01*
X962459D01*
Y216149D01*
X962284D01*
G37*
G36*
G01Y212249D02*
X961614Y212599D01*
Y213469D01*
X962284Y213819D01*
X962459D01*
Y212249D01*
X962284D01*
G37*
G36*
G01X967891Y199872D02*
X967131Y200222D01*
Y201122D01*
X967891Y201472D01*
X968066D01*
Y199872D01*
X967891D01*
G37*
G36*
G01Y203772D02*
X967131Y204122D01*
Y205022D01*
X967891Y205372D01*
X968066D01*
Y203772D01*
X967891D01*
G37*
G36*
G01X966311Y210221D02*
X965551Y210571D01*
Y211471D01*
X966311Y211821D01*
X966486D01*
Y210221D01*
X966311D01*
G37*
G36*
G01Y214121D02*
X965551Y214471D01*
Y215371D01*
X966311Y215721D01*
X966486D01*
Y214121D01*
X966311D01*
G37*
G36*
G01X959263Y203847D02*
X958503Y204197D01*
Y205097D01*
X959263Y205447D01*
X959438D01*
Y203847D01*
X959263D01*
G37*
G36*
G01X958904Y210250D02*
X958234Y210600D01*
Y211470D01*
X958904Y211820D01*
X959079D01*
Y210250D01*
X958904D01*
G37*
G36*
G01X959263Y207747D02*
X958503Y208097D01*
Y208997D01*
X959263Y209347D01*
X959438D01*
Y207747D01*
X959263D01*
G37*
G36*
G01X958904Y214150D02*
X958234Y214500D01*
Y215370D01*
X958904Y215720D01*
X959079D01*
Y214150D01*
X958904D01*
G37*
G36*
G01X960534Y201787D02*
X961294Y201437D01*
Y200537D01*
X960534Y200187D01*
X960359D01*
Y201787D01*
X960534D01*
G37*
G36*
G01X960363Y205447D02*
X961123Y205097D01*
Y204197D01*
X960363Y203847D01*
X960188D01*
Y205447D01*
X960363D01*
G37*
G36*
G01X960528Y217719D02*
X961198Y217369D01*
Y216499D01*
X960528Y216149D01*
X960353D01*
Y217719D01*
X960528D01*
G37*
G36*
G01Y213819D02*
X961198Y213469D01*
Y212599D01*
X960528Y212249D01*
X960353D01*
Y213819D01*
X960528D01*
G37*
G36*
G01X960363Y209347D02*
X961123Y208997D01*
Y208097D01*
X960363Y207747D01*
X960188D01*
Y209347D01*
X960363D01*
G37*
G36*
G01X953759Y198550D02*
X952999Y198900D01*
Y199800D01*
X953759Y200150D01*
X953934D01*
Y198550D01*
X953759D01*
G37*
G36*
G01X954388Y201914D02*
X954098Y202699D01*
X954734Y203336D01*
X955519Y203046D01*
X955643Y202922D01*
X954512Y201791D01*
X954388Y201914D01*
G37*
G36*
G01X955524Y216160D02*
X954854Y216510D01*
Y217380D01*
X955524Y217730D01*
X955699D01*
Y216160D01*
X955524D01*
G37*
G36*
G01X956047Y208414D02*
X955287Y208764D01*
Y209664D01*
X956047Y210014D01*
X956222D01*
Y208414D01*
X956047D01*
G37*
G36*
G01Y204514D02*
X955287Y204864D01*
Y205764D01*
X956047Y206114D01*
X956222D01*
Y204514D01*
X956047D01*
G37*
G36*
G01X955524Y212260D02*
X954854Y212610D01*
Y213480D01*
X955524Y213830D01*
X955699D01*
Y212260D01*
X955524D01*
G37*
G36*
G01X956318Y202287D02*
X956608Y201503D01*
X955971Y200866D01*
X955187Y201156D01*
X955063Y201280D01*
X956194Y202411D01*
X956318Y202287D01*
G37*
G36*
G01X954860Y200150D02*
X955620Y199800D01*
Y198900D01*
X954860Y198550D01*
X954685D01*
Y200150D01*
X954860D01*
G37*
G36*
G01X957149Y215709D02*
X957819Y215359D01*
Y214489D01*
X957149Y214139D01*
X956974D01*
Y215709D01*
X957149D01*
G37*
G36*
G01X957148Y206114D02*
X957908Y205764D01*
Y204864D01*
X957148Y204514D01*
X956973D01*
Y206114D01*
X957148D01*
G37*
G36*
G01Y210014D02*
X957908Y209664D01*
Y208764D01*
X957148Y208414D01*
X956973D01*
Y210014D01*
X957148D01*
G37*
G36*
G01X972856Y198548D02*
X972071Y198258D01*
X971434Y198894D01*
X971724Y199679D01*
X971848Y199803D01*
X972979Y198672D01*
X972856Y198548D01*
G37*
G36*
G01X969331Y210603D02*
X968571Y210953D01*
Y211853D01*
X969331Y212203D01*
X969506D01*
Y210603D01*
X969331D01*
G37*
G36*
G01X971155Y207008D02*
X970370Y206718D01*
X969733Y207354D01*
X970023Y208139D01*
X970147Y208263D01*
X971278Y207132D01*
X971155Y207008D01*
G37*
G36*
G01X971792Y204379D02*
X971032Y204729D01*
X971031Y205629D01*
X971792Y205979D01*
X971967D01*
Y204380D01*
X971792Y204379D01*
G37*
G36*
G01X969331Y214503D02*
X968571Y214853D01*
Y215753D01*
X969331Y216103D01*
X969506D01*
Y214503D01*
X969331D01*
G37*
G36*
G01X970431Y216103D02*
X971191Y215753D01*
Y214853D01*
X970431Y214503D01*
X970256D01*
Y216103D01*
X970431D01*
G37*
G36*
G01Y212203D02*
X971191Y211853D01*
Y210953D01*
X970431Y210603D01*
X970256D01*
Y212203D01*
X970431D01*
G37*
G36*
G01X970801Y208917D02*
X971586Y209207D01*
X972222Y208571D01*
X971932Y207786D01*
X971809Y207662D01*
X970677Y208793D01*
X970801Y208917D01*
G37*
G36*
G01X918886Y271315D02*
X918854Y272070D01*
X919607Y272505D01*
X920245Y272100D01*
X920333Y271949D01*
X918973Y271163D01*
X918886Y271315D01*
G37*
G36*
G01X922260Y273261D02*
X922228Y274016D01*
X922981Y274451D01*
X923619Y274046D01*
X923707Y273895D01*
X922347Y273109D01*
X922260Y273261D01*
G37*
G36*
G01X924835Y274046D02*
X925473Y274451D01*
X926226Y274016D01*
X926194Y273261D01*
X926107Y273109D01*
X924747Y273895D01*
X924835Y274046D01*
G37*
G36*
G01X928209Y272100D02*
X928847Y272505D01*
X929600Y272070D01*
X929568Y271315D01*
X929481Y271163D01*
X928121Y271949D01*
X928209Y272100D01*
G37*
G36*
G01X915357Y269181D02*
X915195Y269920D01*
X915861Y270479D01*
X916560Y270191D01*
X916672Y270057D01*
X915470Y269047D01*
X915357Y269181D01*
G37*
G36*
G01X928485Y235624D02*
X927815Y235974D01*
Y236844D01*
X928485Y237194D01*
X928660D01*
Y235624D01*
X928485D01*
G37*
G36*
G01Y231724D02*
X927815Y232074D01*
Y232944D01*
X928485Y233294D01*
X928660D01*
Y231724D01*
X928485D01*
G37*
G36*
G01Y227800D02*
X927815Y228150D01*
Y229020D01*
X928485Y229370D01*
X928660D01*
Y227800D01*
X928485D01*
G37*
G36*
G01Y223949D02*
X927815Y224299D01*
Y225169D01*
X928485Y225519D01*
X928660D01*
Y223949D01*
X928485D01*
G37*
G36*
G01Y220049D02*
X927815Y220399D01*
Y221269D01*
X928485Y221619D01*
X928660D01*
Y220049D01*
X928485D01*
G37*
G36*
G01X930109Y219620D02*
X930779Y219270D01*
Y218400D01*
X930109Y218050D01*
X929934D01*
Y219620D01*
X930109D01*
G37*
G36*
G01Y223520D02*
X930779Y223170D01*
Y222300D01*
X930109Y221950D01*
X929934D01*
Y223520D01*
X930109D01*
G37*
G36*
G01Y227445D02*
X930779Y227095D01*
Y226225D01*
X930109Y225875D01*
X929934D01*
Y227445D01*
X930109D01*
G37*
G36*
G01Y231369D02*
X930779Y231019D01*
Y230149D01*
X930109Y229799D01*
X929934D01*
Y231369D01*
X930109D01*
G37*
G36*
G01Y235220D02*
X930779Y234870D01*
Y234000D01*
X930109Y233650D01*
X929934D01*
Y235220D01*
X930109D01*
G37*
G36*
G01X918886Y251815D02*
X918854Y252570D01*
X919607Y253005D01*
X920245Y252600D01*
X920333Y252449D01*
X918973Y251663D01*
X918886Y251815D01*
G37*
G36*
G01X922260Y253761D02*
X922228Y254516D01*
X922981Y254951D01*
X923619Y254546D01*
X923707Y254395D01*
X922347Y253609D01*
X922260Y253761D01*
G37*
G36*
G01X915521Y249875D02*
X915489Y250630D01*
X916243Y251064D01*
X916880Y250659D01*
X916969Y250508D01*
X915608Y249723D01*
X915521Y249875D01*
G37*
G36*
G01X931172Y254061D02*
X931837Y254420D01*
X932558Y253934D01*
X932474Y253183D01*
X932376Y253038D01*
X931074Y253916D01*
X931172Y254061D01*
G37*
G36*
G01X911201Y241497D02*
X910441Y241847D01*
Y242747D01*
X911201Y243097D01*
X911376D01*
Y241497D01*
X911201D01*
G37*
G36*
G01Y245397D02*
X910441Y245747D01*
Y246647D01*
X911201Y246997D01*
X911376D01*
Y245397D01*
X911201D01*
G37*
G36*
G01X928209Y252600D02*
X928847Y253005D01*
X929600Y252570D01*
X929568Y251815D01*
X929481Y251663D01*
X928121Y252449D01*
X928209Y252600D01*
G37*
G36*
G01X931595Y250646D02*
X932233Y251051D01*
X932986Y250616D01*
X932954Y249861D01*
X932867Y249709D01*
X931507Y250495D01*
X931595Y250646D01*
G37*
G36*
G01X922814Y252208D02*
X922846Y251453D01*
X922093Y251018D01*
X921455Y251423D01*
X921367Y251575D01*
X922727Y252360D01*
X922814Y252208D01*
G37*
G36*
G01X919428Y250254D02*
X919460Y249499D01*
X918707Y249064D01*
X918069Y249469D01*
X917981Y249621D01*
X919341Y250406D01*
X919428Y250254D01*
G37*
G36*
G01X916054Y248308D02*
X916086Y247553D01*
X915333Y247118D01*
X914695Y247523D01*
X914607Y247675D01*
X915967Y248460D01*
X916054Y248308D01*
G37*
G36*
G01X912301Y244997D02*
X913061Y244647D01*
Y243747D01*
X912301Y243397D01*
X912126D01*
Y244997D01*
X912301D01*
G37*
G36*
G01X925105Y237574D02*
X924435Y237924D01*
Y238794D01*
X925105Y239144D01*
X925280D01*
Y237574D01*
X925105D01*
G37*
G36*
G01Y233674D02*
X924435Y234024D01*
Y234894D01*
X925105Y235244D01*
X925280D01*
Y233674D01*
X925105D01*
G37*
G36*
G01Y229774D02*
X924435Y230124D01*
Y230994D01*
X925105Y231344D01*
X925280D01*
Y229774D01*
X925105D01*
G37*
G36*
G01Y225874D02*
X924435Y226224D01*
Y227094D01*
X925105Y227444D01*
X925280D01*
Y225874D01*
X925105D01*
G37*
G36*
G01Y221974D02*
X924435Y222324D01*
Y223194D01*
X925105Y223544D01*
X925280D01*
Y221974D01*
X925105D01*
G37*
G36*
G01X926729Y237194D02*
X927399Y236844D01*
Y235974D01*
X926729Y235624D01*
X926554D01*
Y237194D01*
X926729D01*
G37*
G36*
G01Y221619D02*
X927399Y221269D01*
Y220399D01*
X926729Y220049D01*
X926554D01*
Y221619D01*
X926729D01*
G37*
G36*
G01Y225494D02*
X927399Y225144D01*
Y224274D01*
X926729Y223924D01*
X926554D01*
Y225494D01*
X926729D01*
G37*
G36*
G01Y229394D02*
X927399Y229044D01*
Y228174D01*
X926729Y227824D01*
X926554D01*
Y229394D01*
X926729D01*
G37*
G36*
G01Y233294D02*
X927399Y232944D01*
Y232074D01*
X926729Y231724D01*
X926554D01*
Y233294D01*
X926729D01*
G37*
G36*
G01X919428Y269754D02*
X919460Y268999D01*
X918707Y268564D01*
X918069Y268969D01*
X917981Y269120D01*
X919341Y269905D01*
X919428Y269754D01*
G37*
G36*
G01X922814Y271708D02*
X922846Y270953D01*
X922093Y270518D01*
X921455Y270923D01*
X921367Y271075D01*
X922727Y271860D01*
X922814Y271708D01*
G37*
G36*
G01X926999Y270923D02*
X926361Y270518D01*
X925608Y270953D01*
X925640Y271708D01*
X925727Y271860D01*
X927087Y271075D01*
X926999Y270923D01*
G37*
G36*
G01X915947Y267784D02*
X915979Y267029D01*
X915226Y266594D01*
X914588Y266999D01*
X914500Y267151D01*
X915860Y267936D01*
X915947Y267784D01*
G37*
G36*
G01X918886Y255715D02*
X918854Y256470D01*
X919607Y256905D01*
X920245Y256500D01*
X920333Y256349D01*
X918973Y255563D01*
X918886Y255715D01*
G37*
G36*
G01X922260Y257661D02*
X922228Y258416D01*
X922981Y258851D01*
X923619Y258446D01*
X923707Y258295D01*
X922347Y257509D01*
X922260Y257661D01*
G37*
G36*
G01X919428Y254154D02*
X919460Y253399D01*
X918707Y252964D01*
X918069Y253369D01*
X917981Y253521D01*
X919341Y254306D01*
X919428Y254154D01*
G37*
G36*
G01X922814Y256108D02*
X922846Y255353D01*
X922093Y254918D01*
X921455Y255323D01*
X921367Y255475D01*
X922727Y256260D01*
X922814Y256108D01*
G37*
G36*
G01X915947Y252184D02*
X915979Y251429D01*
X915226Y250994D01*
X914588Y251399D01*
X914500Y251551D01*
X915860Y252336D01*
X915947Y252184D01*
G37*
G36*
G01X918730Y275298D02*
X918673Y276053D01*
X919410Y276514D01*
X920062Y276131D01*
X920154Y275983D01*
X918824Y275150D01*
X918730Y275298D01*
G37*
G36*
G01X922296Y277183D02*
X922264Y277939D01*
X923018Y278374D01*
X923656Y277968D01*
X923743Y277817D01*
X922384Y277032D01*
X922296Y277183D01*
G37*
G36*
G01X924798Y277968D02*
X925436Y278374D01*
X926190Y277939D01*
X926158Y277183D01*
X926070Y277032D01*
X924711Y277817D01*
X924798Y277968D01*
G37*
G36*
G01X928209Y276000D02*
X928847Y276405D01*
X929600Y275970D01*
X929568Y275215D01*
X929481Y275063D01*
X928121Y275849D01*
X928209Y276000D01*
G37*
G36*
G01X931589Y274049D02*
X932227Y274454D01*
X932980Y274019D01*
X932948Y273264D01*
X932861Y273112D01*
X931501Y273898D01*
X931589Y274049D01*
G37*
G36*
G01X926999Y274823D02*
X926361Y274418D01*
X925608Y274853D01*
X925640Y275608D01*
X925727Y275760D01*
X927087Y274975D01*
X926999Y274823D01*
G37*
G36*
G01X930385Y272869D02*
X929747Y272464D01*
X928994Y272899D01*
X929026Y273654D01*
X929113Y273805D01*
X930473Y273020D01*
X930385Y272869D01*
G37*
G36*
G01X919215Y273729D02*
X919273Y272974D01*
X918535Y272513D01*
X917883Y272896D01*
X917791Y273044D01*
X919122Y273877D01*
X919215Y273729D01*
G37*
G36*
G01X922814Y275608D02*
X922846Y274853D01*
X922093Y274418D01*
X921455Y274823D01*
X921367Y274975D01*
X922727Y275760D01*
X922814Y275608D01*
G37*
G36*
G01X931984Y268819D02*
X931287Y269109D01*
X931211Y269976D01*
X931848Y270383D01*
X932022Y270398D01*
X932159Y268834D01*
X931984Y268819D01*
G37*
G36*
G01X922260Y261561D02*
X922228Y262316D01*
X922981Y262751D01*
X923619Y262346D01*
X923707Y262195D01*
X922347Y261409D01*
X922260Y261561D01*
G37*
G36*
G01X918886Y259615D02*
X918854Y260370D01*
X919607Y260805D01*
X920245Y260400D01*
X920333Y260249D01*
X918973Y259463D01*
X918886Y259615D01*
G37*
G36*
G01X915947Y256084D02*
X915979Y255329D01*
X915226Y254894D01*
X914588Y255299D01*
X914500Y255451D01*
X915860Y256236D01*
X915947Y256084D01*
G37*
G36*
G01X919428Y258054D02*
X919460Y257299D01*
X918707Y256864D01*
X918069Y257269D01*
X917981Y257420D01*
X919341Y258205D01*
X919428Y258054D01*
G37*
G36*
G01X922814Y260008D02*
X922846Y259253D01*
X922093Y258818D01*
X921455Y259223D01*
X921367Y259375D01*
X922727Y260160D01*
X922814Y260008D01*
G37*
G36*
G01X928209Y260400D02*
X928847Y260805D01*
X929600Y260370D01*
X929568Y259615D01*
X929481Y259463D01*
X928121Y260249D01*
X928209Y260400D01*
G37*
G36*
G01X925688Y250941D02*
X925629Y251694D01*
X926367Y252155D01*
X927018Y251773D01*
X927112Y251625D01*
X925780Y250792D01*
X925688Y250941D01*
G37*
G36*
G01X918886Y247915D02*
X918854Y248670D01*
X919607Y249105D01*
X920245Y248700D01*
X920333Y248549D01*
X918973Y247763D01*
X918886Y247915D01*
G37*
G36*
G01X922260Y249861D02*
X922228Y250616D01*
X922981Y251051D01*
X923619Y250646D01*
X923707Y250495D01*
X922347Y249709D01*
X922260Y249861D01*
G37*
G36*
G01X914965Y239549D02*
X914295Y239899D01*
Y240769D01*
X914965Y241119D01*
X915140D01*
Y239549D01*
X914965D01*
G37*
G36*
G01Y243407D02*
X914295Y243757D01*
X914296Y244626D01*
X914965Y244976D01*
X915141Y244977D01*
X915140Y243406D01*
X914965Y243407D01*
G37*
G36*
G01X915521Y245975D02*
X915489Y246730D01*
X916243Y247164D01*
X916880Y246759D01*
X916969Y246608D01*
X915608Y245823D01*
X915521Y245975D01*
G37*
G36*
G01X926976Y248311D02*
X926288Y247998D01*
X925603Y248534D01*
X925739Y249277D01*
X925847Y249415D01*
X927085Y248449D01*
X926976Y248311D01*
G37*
G36*
G01X932843Y246983D02*
X932835Y246228D01*
X932061Y245833D01*
X931445Y246270D01*
X931365Y246427D01*
X932764Y247140D01*
X932843Y246983D01*
G37*
G36*
G01X922814Y248308D02*
X922846Y247553D01*
X922093Y247118D01*
X921455Y247523D01*
X921367Y247675D01*
X922727Y248460D01*
X922814Y248308D01*
G37*
G36*
G01X919428Y246354D02*
X919460Y245599D01*
X918707Y245164D01*
X918069Y245569D01*
X917981Y245721D01*
X919341Y246506D01*
X919428Y246354D01*
G37*
G36*
G01X916589Y239120D02*
X917259Y238770D01*
Y237900D01*
X916589Y237550D01*
X916414D01*
Y239120D01*
X916589D01*
G37*
G36*
G01Y243020D02*
X917259Y242670D01*
Y241800D01*
X916589Y241450D01*
X916414D01*
Y243020D01*
X916589D01*
G37*
G36*
G01X915947Y259984D02*
X915979Y259229D01*
X915226Y258794D01*
X914588Y259199D01*
X914500Y259351D01*
X915860Y260136D01*
X915947Y259984D01*
G37*
G36*
G01X919398Y261937D02*
X919430Y261182D01*
X918677Y260747D01*
X918039Y261152D01*
X917951Y261303D01*
X919311Y262089D01*
X919398Y261937D01*
G37*
G36*
G01X922814Y263908D02*
X922846Y263153D01*
X922093Y262718D01*
X921455Y263123D01*
X921367Y263275D01*
X922727Y264060D01*
X922814Y263908D01*
G37*
G36*
G01X926999Y263123D02*
X926361Y262718D01*
X925608Y263153D01*
X925640Y263908D01*
X925727Y264060D01*
X927087Y263275D01*
X926999Y263123D01*
G37*
G36*
G01X930414Y261152D02*
X929776Y260747D01*
X929023Y261182D01*
X929055Y261937D01*
X929142Y262089D01*
X930502Y261303D01*
X930414Y261152D01*
G37*
G36*
G01X919969Y241095D02*
X920639Y240745D01*
Y239875D01*
X919969Y239525D01*
X919794D01*
Y241095D01*
X919969D01*
G37*
G36*
G01X922767Y244388D02*
X922799Y243633D01*
X922046Y243198D01*
X921408Y243603D01*
X921320Y243755D01*
X922680Y244540D01*
X922767Y244388D01*
G37*
G36*
G01X919969Y237195D02*
X920639Y236845D01*
Y235975D01*
X919969Y235625D01*
X919794D01*
Y237195D01*
X919969D01*
G37*
G36*
G01X917901Y232577D02*
X918191Y231792D01*
X917554Y231156D01*
X916769Y231446D01*
X916646Y231570D01*
X917777Y232701D01*
X917901Y232577D01*
G37*
G36*
G01X915143Y229819D02*
X915433Y229035D01*
X914796Y228398D01*
X914012Y228688D01*
X913888Y228812D01*
X915019Y229943D01*
X915143Y229819D01*
G37*
G36*
G01X926185Y242452D02*
X926217Y241697D01*
X925464Y241262D01*
X924826Y241667D01*
X924738Y241818D01*
X926098Y242603D01*
X926185Y242452D01*
G37*
G36*
G01X923348Y239144D02*
X924018Y238794D01*
Y237924D01*
X923348Y237574D01*
X923173D01*
Y239144D01*
X923348D01*
G37*
G36*
G01X930392Y241665D02*
X929754Y241260D01*
X929001Y241695D01*
X929033Y242450D01*
X929120Y242602D01*
X930480Y241816D01*
X930392Y241665D01*
G37*
G36*
G01X933765Y239720D02*
X933127Y239315D01*
X932374Y239750D01*
X932406Y240505D01*
X932493Y240656D01*
X933853Y239871D01*
X933765Y239720D01*
G37*
G36*
G01X922827Y235290D02*
X923587Y234940D01*
Y234040D01*
X922827Y233690D01*
X922652D01*
Y235290D01*
X922827D01*
G37*
G36*
G01X912325Y263160D02*
X911975Y262400D01*
X911075D01*
X910725Y263160D01*
Y263335D01*
X912325D01*
Y263160D01*
G37*
G36*
G01X919398Y265837D02*
X919430Y265082D01*
X918677Y264647D01*
X918039Y265052D01*
X917951Y265203D01*
X919311Y265989D01*
X919398Y265837D01*
G37*
G36*
G01X915947Y263884D02*
X915979Y263129D01*
X915226Y262694D01*
X914588Y263099D01*
X914500Y263251D01*
X915860Y264036D01*
X915947Y263884D01*
G37*
G36*
G01X922814Y267808D02*
X922846Y267053D01*
X922093Y266618D01*
X921455Y267023D01*
X921367Y267175D01*
X922727Y267960D01*
X922814Y267808D01*
G37*
G36*
G01X918893Y263519D02*
X918861Y264274D01*
X919614Y264709D01*
X920252Y264304D01*
X920340Y264153D01*
X918980Y263367D01*
X918893Y263519D01*
G37*
G36*
G01X922260Y265461D02*
X922228Y266216D01*
X922981Y266651D01*
X923619Y266246D01*
X923707Y266095D01*
X922347Y265309D01*
X922260Y265461D01*
G37*
G36*
G01X924835Y266246D02*
X925473Y266651D01*
X926226Y266216D01*
X926194Y265461D01*
X926107Y265309D01*
X924747Y266095D01*
X924835Y266246D01*
G37*
G36*
G01X928202Y264304D02*
X928840Y264709D01*
X929593Y264274D01*
X929561Y263519D01*
X929474Y263367D01*
X928114Y264153D01*
X928202Y264304D01*
G37*
G36*
G01X931582Y262353D02*
X932220Y262758D01*
X932973Y262323D01*
X932941Y261568D01*
X932854Y261416D01*
X931494Y262202D01*
X931582Y262353D01*
G37*
G36*
G01X918879Y244012D02*
X918847Y244767D01*
X919601Y245201D01*
X920238Y244796D01*
X920327Y244645D01*
X918966Y243860D01*
X918879Y244012D01*
G37*
G36*
G01X922260Y245961D02*
X922228Y246716D01*
X922981Y247151D01*
X923619Y246746D01*
X923707Y246595D01*
X922347Y245809D01*
X922260Y245961D01*
G37*
G36*
G01X918346Y241432D02*
X917676Y241782D01*
X917677Y242651D01*
X918346Y243001D01*
X918522Y243002D01*
X918521Y241431D01*
X918346Y241432D01*
G37*
G36*
G01X918345Y237574D02*
X917675Y237924D01*
Y238794D01*
X918345Y239144D01*
X918520D01*
Y237574D01*
X918345D01*
G37*
G36*
G01X915991Y232224D02*
X915701Y233009D01*
X916338Y233645D01*
X917123Y233355D01*
X917246Y233231D01*
X916115Y232100D01*
X915991Y232224D01*
G37*
G36*
G01X913234Y229466D02*
X912944Y230251D01*
X913580Y230887D01*
X914365Y230597D01*
X914489Y230474D01*
X913357Y229342D01*
X913234Y229466D01*
G37*
G36*
G01X928179Y244817D02*
X928817Y245222D01*
X929570Y244787D01*
X929538Y244032D01*
X929451Y243880D01*
X928091Y244665D01*
X928179Y244817D01*
G37*
G36*
G01X922260Y242061D02*
X922228Y242816D01*
X922981Y243251D01*
X923619Y242846D01*
X923707Y242695D01*
X922346Y241910D01*
X922260Y242061D01*
G37*
G36*
G01X921726Y239481D02*
X921056Y239831D01*
Y240701D01*
X921726Y241051D01*
X921901Y241052D01*
X921900Y239481D01*
X921726D01*
G37*
G36*
G01X931595Y242846D02*
X932233Y243251D01*
X932986Y242816D01*
X932954Y242061D01*
X932867Y241909D01*
X931507Y242695D01*
X931595Y242846D01*
G37*
G36*
G01X925675Y244032D02*
X925643Y244787D01*
X926396Y245222D01*
X927034Y244817D01*
X927122Y244666D01*
X925762Y243880D01*
X925675Y244032D01*
G37*
G36*
G01X921727Y233690D02*
X920967Y234040D01*
Y234940D01*
X921727Y235290D01*
X921902D01*
Y233690D01*
X921727D01*
G37*
G36*
G01X922266Y269364D02*
X922234Y270119D01*
X922987Y270554D01*
X923625Y270149D01*
X923713Y269997D01*
X922353Y269212D01*
X922266Y269364D01*
G37*
G36*
G01X924829Y270149D02*
X925467Y270554D01*
X926220Y270119D01*
X926188Y269364D01*
X926101Y269212D01*
X924741Y269997D01*
X924829Y270149D01*
G37*
G36*
G01X910725Y264260D02*
X911075Y265020D01*
X911975D01*
X912325Y264260D01*
Y264085D01*
X910725D01*
Y264260D01*
G37*
G36*
G01X918889Y267417D02*
X918857Y268172D01*
X919610Y268607D01*
X920248Y268202D01*
X920336Y268051D01*
X918976Y267265D01*
X918889Y267417D01*
G37*
G36*
G01X915512Y265470D02*
X915480Y266225D01*
X916233Y266660D01*
X916871Y266255D01*
X916959Y266104D01*
X915599Y265318D01*
X915512Y265470D01*
G37*
G36*
G01X963908Y246920D02*
X964578Y246570D01*
Y245700D01*
X963908Y245350D01*
X963733D01*
Y246920D01*
X963908D01*
G37*
G36*
G01Y250820D02*
X964578Y250470D01*
Y249600D01*
X963908Y249250D01*
X963733D01*
Y250820D01*
X963908D01*
G37*
G36*
G01Y254720D02*
X964578Y254370D01*
Y253500D01*
X963908Y253150D01*
X963733D01*
Y254720D01*
X963908D01*
G37*
G36*
G01Y258620D02*
X964578Y258270D01*
Y257400D01*
X963908Y257050D01*
X963733D01*
Y258620D01*
X963908D01*
G37*
G36*
G01Y223520D02*
X964578Y223170D01*
Y222300D01*
X963908Y221950D01*
X963733D01*
Y223520D01*
X963908D01*
G37*
G36*
G01Y227445D02*
X964578Y227095D01*
Y226225D01*
X963908Y225875D01*
X963733D01*
Y227445D01*
X963908D01*
G37*
G36*
G01Y231369D02*
X964578Y231019D01*
Y230149D01*
X963908Y229799D01*
X963733D01*
Y231369D01*
X963908D01*
G37*
G36*
G01Y219620D02*
X964578Y219270D01*
Y218400D01*
X963908Y218050D01*
X963733D01*
Y219620D01*
X963908D01*
G37*
G36*
G01Y235220D02*
X964578Y234870D01*
Y234000D01*
X963908Y233650D01*
X963733D01*
Y235220D01*
X963908D01*
G37*
G36*
G01Y239120D02*
X964578Y238770D01*
Y237900D01*
X963908Y237550D01*
X963733D01*
Y239120D01*
X963908D01*
G37*
G36*
G01Y243020D02*
X964578Y242670D01*
Y241800D01*
X963908Y241450D01*
X963733D01*
Y243020D01*
X963908D01*
G37*
G36*
G01X967288Y264494D02*
X967958Y264144D01*
Y263274D01*
X967288Y262924D01*
X967113D01*
Y264494D01*
X967288D01*
G37*
G36*
G01X967287Y260619D02*
X967957Y260269D01*
Y259399D01*
X967287Y259049D01*
X967112D01*
Y260619D01*
X967287D01*
G37*
G36*
G01X967288Y256719D02*
X967958Y256369D01*
Y255499D01*
X967288Y255149D01*
X967113D01*
Y256719D01*
X967288D01*
G37*
G36*
G01Y252819D02*
X967958Y252469D01*
Y251599D01*
X967288Y251249D01*
X967113D01*
Y252819D01*
X967288D01*
G37*
G36*
G01Y248919D02*
X967958Y248569D01*
Y247699D01*
X967288Y247349D01*
X967113D01*
Y248919D01*
X967288D01*
G37*
G36*
G01Y233294D02*
X967958Y232944D01*
Y232074D01*
X967288Y231724D01*
X967113D01*
Y233294D01*
X967288D01*
G37*
G36*
G01Y229370D02*
X967958Y229020D01*
Y228150D01*
X967288Y227800D01*
X967113D01*
Y229370D01*
X967288D01*
G37*
G36*
G01Y225519D02*
X967958Y225169D01*
Y224299D01*
X967288Y223949D01*
X967113D01*
Y225519D01*
X967288D01*
G37*
G36*
G01Y221619D02*
X967958Y221269D01*
Y220399D01*
X967288Y220049D01*
X967113D01*
Y221619D01*
X967288D01*
G37*
G36*
G01Y245019D02*
X967958Y244669D01*
Y243799D01*
X967288Y243449D01*
X967113D01*
Y245019D01*
X967288D01*
G37*
G36*
G01Y241119D02*
X967958Y240769D01*
Y239899D01*
X967288Y239549D01*
X967113D01*
Y241119D01*
X967288D01*
G37*
G36*
G01Y237219D02*
X967958Y236869D01*
Y235999D01*
X967288Y235649D01*
X967113D01*
Y237219D01*
X967288D01*
G37*
G36*
G01X962284Y255149D02*
X961614Y255499D01*
Y256369D01*
X962284Y256719D01*
X962459D01*
Y255149D01*
X962284D01*
G37*
G36*
G01Y251249D02*
X961614Y251599D01*
Y252469D01*
X962284Y252819D01*
X962459D01*
Y251249D01*
X962284D01*
G37*
G36*
G01Y247349D02*
X961614Y247699D01*
Y248569D01*
X962284Y248919D01*
X962459D01*
Y247349D01*
X962284D01*
G37*
G36*
G01Y259049D02*
X961614Y259399D01*
Y260269D01*
X962284Y260619D01*
X962459D01*
Y259049D01*
X962284D01*
G37*
G36*
G01Y231724D02*
X961614Y232074D01*
Y232944D01*
X962284Y233294D01*
X962459D01*
Y231724D01*
X962284D01*
G37*
G36*
G01Y227800D02*
X961614Y228150D01*
Y229020D01*
X962284Y229370D01*
X962459D01*
Y227800D01*
X962284D01*
G37*
G36*
G01Y223949D02*
X961614Y224299D01*
Y225169D01*
X962284Y225519D01*
X962459D01*
Y223949D01*
X962284D01*
G37*
G36*
G01Y220049D02*
X961614Y220399D01*
Y221269D01*
X962284Y221619D01*
X962459D01*
Y220049D01*
X962284D01*
G37*
G36*
G01Y243449D02*
X961614Y243799D01*
Y244669D01*
X962284Y245019D01*
X962459D01*
Y243449D01*
X962284D01*
G37*
G36*
G01Y239549D02*
X961614Y239899D01*
Y240769D01*
X962284Y241119D01*
X962459D01*
Y239549D01*
X962284D01*
G37*
G36*
G01Y235649D02*
X961614Y235999D01*
Y236869D01*
X962284Y237219D01*
X962459D01*
Y235649D01*
X962284D01*
G37*
G36*
G01X965664Y245350D02*
X964994Y245700D01*
Y246570D01*
X965664Y246920D01*
X965839D01*
Y245350D01*
X965664D01*
G37*
G36*
G01Y249250D02*
X964994Y249600D01*
Y250470D01*
X965664Y250820D01*
X965839D01*
Y249250D01*
X965664D01*
G37*
G36*
G01Y253150D02*
X964994Y253500D01*
Y254370D01*
X965664Y254720D01*
X965839D01*
Y253150D01*
X965664D01*
G37*
G36*
G01Y257050D02*
X964994Y257400D01*
Y258270D01*
X965664Y258620D01*
X965839D01*
Y257050D01*
X965664D01*
G37*
G36*
G01Y260974D02*
X964994Y261324D01*
Y262194D01*
X965664Y262544D01*
X965839D01*
Y260974D01*
X965664D01*
G37*
G36*
G01Y264850D02*
X964994Y265200D01*
Y266070D01*
X965664Y266420D01*
X965839D01*
Y264850D01*
X965664D01*
G37*
G36*
G01Y218050D02*
X964994Y218400D01*
Y219270D01*
X965664Y219620D01*
X965839D01*
Y218050D01*
X965664D01*
G37*
G36*
G01Y221950D02*
X964994Y222300D01*
Y223170D01*
X965664Y223520D01*
X965839D01*
Y221950D01*
X965664D01*
G37*
G36*
G01Y225875D02*
X964994Y226225D01*
Y227095D01*
X965664Y227445D01*
X965839D01*
Y225875D01*
X965664D01*
G37*
G36*
G01Y229799D02*
X964994Y230149D01*
Y231019D01*
X965664Y231369D01*
X965839D01*
Y229799D01*
X965664D01*
G37*
G36*
G01Y233650D02*
X964994Y234000D01*
Y234870D01*
X965664Y235220D01*
X965839D01*
Y233650D01*
X965664D01*
G37*
G36*
G01Y237550D02*
X964994Y237900D01*
Y238770D01*
X965664Y239120D01*
X965839D01*
Y237550D01*
X965664D01*
G37*
G36*
G01Y241450D02*
X964994Y241800D01*
Y242670D01*
X965664Y243020D01*
X965839D01*
Y241450D01*
X965664D01*
G37*
G36*
G01X958904Y260974D02*
X958234Y261324D01*
Y262194D01*
X958904Y262544D01*
X959079D01*
Y260974D01*
X958904D01*
G37*
G36*
G01Y257050D02*
X958234Y257400D01*
Y258270D01*
X958904Y258620D01*
X959079D01*
Y257050D01*
X958904D01*
G37*
G36*
G01Y253150D02*
X958234Y253500D01*
Y254370D01*
X958904Y254720D01*
X959079D01*
Y253150D01*
X958904D01*
G37*
G36*
G01Y249250D02*
X958234Y249600D01*
Y250470D01*
X958904Y250820D01*
X959079D01*
Y249250D01*
X958904D01*
G37*
G36*
G01Y245350D02*
X958234Y245700D01*
Y246570D01*
X958904Y246920D01*
X959079D01*
Y245350D01*
X958904D01*
G37*
G36*
G01Y229799D02*
X958234Y230149D01*
Y231019D01*
X958904Y231369D01*
X959079D01*
Y229799D01*
X958904D01*
G37*
G36*
G01Y225875D02*
X958234Y226225D01*
Y227095D01*
X958904Y227445D01*
X959079D01*
Y225875D01*
X958904D01*
G37*
G36*
G01Y221950D02*
X958234Y222300D01*
Y223170D01*
X958904Y223520D01*
X959079D01*
Y221950D01*
X958904D01*
G37*
G36*
G01Y218050D02*
X958234Y218400D01*
Y219270D01*
X958904Y219620D01*
X959079D01*
Y218050D01*
X958904D01*
G37*
G36*
G01Y233650D02*
X958234Y234000D01*
Y234870D01*
X958904Y235220D01*
X959079D01*
Y233650D01*
X958904D01*
G37*
G36*
G01Y241450D02*
X958234Y241800D01*
Y242670D01*
X958904Y243020D01*
X959079D01*
Y241450D01*
X958904D01*
G37*
G36*
G01Y237550D02*
X958234Y237900D01*
Y238770D01*
X958904Y239120D01*
X959079D01*
Y237550D01*
X958904D01*
G37*
G36*
G01X960527Y260619D02*
X961197Y260269D01*
Y259399D01*
X960527Y259049D01*
X960352D01*
Y260619D01*
X960527D01*
G37*
G36*
G01X960528Y256719D02*
X961198Y256369D01*
Y255499D01*
X960528Y255149D01*
X960353D01*
Y256719D01*
X960528D01*
G37*
G36*
G01Y252819D02*
X961198Y252469D01*
Y251599D01*
X960528Y251249D01*
X960353D01*
Y252819D01*
X960528D01*
G37*
G36*
G01Y248919D02*
X961198Y248569D01*
Y247699D01*
X960528Y247349D01*
X960353D01*
Y248919D01*
X960528D01*
G37*
G36*
G01Y233294D02*
X961198Y232944D01*
Y232074D01*
X960528Y231724D01*
X960353D01*
Y233294D01*
X960528D01*
G37*
G36*
G01Y229370D02*
X961198Y229020D01*
Y228150D01*
X960528Y227800D01*
X960353D01*
Y229370D01*
X960528D01*
G37*
G36*
G01Y225519D02*
X961198Y225169D01*
Y224299D01*
X960528Y223949D01*
X960353D01*
Y225519D01*
X960528D01*
G37*
G36*
G01Y221619D02*
X961198Y221269D01*
Y220399D01*
X960528Y220049D01*
X960353D01*
Y221619D01*
X960528D01*
G37*
G36*
G01Y245019D02*
X961198Y244669D01*
Y243799D01*
X960528Y243449D01*
X960353D01*
Y245019D01*
X960528D01*
G37*
G36*
G01Y241119D02*
X961198Y240769D01*
Y239899D01*
X960528Y239549D01*
X960353D01*
Y241119D01*
X960528D01*
G37*
G36*
G01Y237219D02*
X961198Y236869D01*
Y235999D01*
X960528Y235649D01*
X960353D01*
Y237219D01*
X960528D01*
G37*
G36*
G01X955524Y247360D02*
X954854Y247710D01*
Y248580D01*
X955524Y248930D01*
X955699D01*
Y247360D01*
X955524D01*
G37*
G36*
G01X955525Y259059D02*
X954855Y259409D01*
Y260279D01*
X955525Y260629D01*
X955700D01*
Y259059D01*
X955525D01*
G37*
G36*
G01X955524Y255160D02*
X954854Y255510D01*
Y256380D01*
X955524Y256730D01*
X955699D01*
Y255160D01*
X955524D01*
G37*
G36*
G01Y251260D02*
X954854Y251610D01*
Y252480D01*
X955524Y252830D01*
X955699D01*
Y251260D01*
X955524D01*
G37*
G36*
G01Y231749D02*
X954854Y232099D01*
Y232969D01*
X955524Y233319D01*
X955699D01*
Y231749D01*
X955524D01*
G37*
G36*
G01Y227800D02*
X954854Y228150D01*
Y229020D01*
X955524Y229370D01*
X955699D01*
Y227800D01*
X955524D01*
G37*
G36*
G01Y223960D02*
X954854Y224310D01*
Y225180D01*
X955524Y225530D01*
X955699D01*
Y223960D01*
X955524D01*
G37*
G36*
G01Y220060D02*
X954854Y220410D01*
Y221280D01*
X955524Y221630D01*
X955699D01*
Y220060D01*
X955524D01*
G37*
G36*
G01Y243460D02*
X954854Y243810D01*
Y244680D01*
X955524Y245030D01*
X955699D01*
Y243460D01*
X955524D01*
G37*
G36*
G01Y239560D02*
X954854Y239910D01*
Y240780D01*
X955524Y241130D01*
X955699D01*
Y239560D01*
X955524D01*
G37*
G36*
G01Y235660D02*
X954854Y236010D01*
Y236880D01*
X955524Y237230D01*
X955699D01*
Y235660D01*
X955524D01*
G37*
G36*
G01X957149Y262544D02*
X957819Y262194D01*
Y261324D01*
X957149Y260974D01*
X956974D01*
Y262544D01*
X957149D01*
G37*
G36*
G01Y258609D02*
X957819Y258259D01*
Y257389D01*
X957149Y257039D01*
X956974D01*
Y258609D01*
X957149D01*
G37*
G36*
G01Y254709D02*
X957819Y254359D01*
Y253489D01*
X957149Y253139D01*
X956974D01*
Y254709D01*
X957149D01*
G37*
G36*
G01Y250809D02*
X957819Y250459D01*
Y249589D01*
X957149Y249239D01*
X956974D01*
Y250809D01*
X957149D01*
G37*
G36*
G01Y246909D02*
X957819Y246559D01*
Y245689D01*
X957149Y245339D01*
X956974D01*
Y246909D01*
X957149D01*
G37*
G36*
G01Y219609D02*
X957819Y219259D01*
Y218389D01*
X957149Y218039D01*
X956974D01*
Y219609D01*
X957149D01*
G37*
G36*
G01Y231369D02*
X957819Y231019D01*
Y230149D01*
X957149Y229799D01*
X956974D01*
Y231369D01*
X957149D01*
G37*
G36*
G01Y227420D02*
X957819Y227070D01*
Y226200D01*
X957149Y225850D01*
X956974D01*
Y227420D01*
X957149D01*
G37*
G36*
G01Y223509D02*
X957819Y223159D01*
Y222289D01*
X957149Y221939D01*
X956974D01*
Y223509D01*
X957149D01*
G37*
G36*
G01Y235209D02*
X957819Y234859D01*
Y233989D01*
X957149Y233639D01*
X956974D01*
Y235209D01*
X957149D01*
G37*
G36*
G01Y243009D02*
X957819Y242659D01*
Y241789D01*
X957149Y241439D01*
X956974D01*
Y243009D01*
X957149D01*
G37*
G36*
G01Y239109D02*
X957819Y238759D01*
Y237889D01*
X957149Y237539D01*
X956974D01*
Y239109D01*
X957149D01*
G37*
G36*
G01X969044Y247349D02*
X968374Y247699D01*
Y248569D01*
X969044Y248919D01*
X969219D01*
Y247349D01*
X969044D01*
G37*
G36*
G01Y251249D02*
X968374Y251599D01*
Y252469D01*
X969044Y252819D01*
X969219D01*
Y251249D01*
X969044D01*
G37*
G36*
G01Y255149D02*
X968374Y255499D01*
Y256369D01*
X969044Y256719D01*
X969219D01*
Y255149D01*
X969044D01*
G37*
G36*
G01X969045Y259049D02*
X968375Y259399D01*
Y260269D01*
X969045Y260619D01*
X969220D01*
Y259049D01*
X969045D01*
G37*
G36*
G01X969056Y262987D02*
X968381Y263327D01*
X968368Y264197D01*
X969033Y264557D01*
X969209Y264559D01*
X969231Y262989D01*
X969056Y262987D01*
G37*
G36*
G01X969044Y220049D02*
X968374Y220399D01*
Y221269D01*
X969044Y221619D01*
X969219D01*
Y220049D01*
X969044D01*
G37*
G36*
G01Y223949D02*
X968374Y224299D01*
Y225169D01*
X969044Y225519D01*
X969219D01*
Y223949D01*
X969044D01*
G37*
G36*
G01Y227800D02*
X968374Y228150D01*
Y229020D01*
X969044Y229370D01*
X969219D01*
Y227800D01*
X969044D01*
G37*
G36*
G01Y231724D02*
X968374Y232074D01*
Y232944D01*
X969044Y233294D01*
X969219D01*
Y231724D01*
X969044D01*
G37*
G36*
G01Y235649D02*
X968374Y235999D01*
Y236869D01*
X969044Y237219D01*
X969219D01*
Y235649D01*
X969044D01*
G37*
G36*
G01Y239549D02*
X968374Y239899D01*
Y240769D01*
X969044Y241119D01*
X969219D01*
Y239549D01*
X969044D01*
G37*
G36*
G01Y243449D02*
X968374Y243799D01*
Y244669D01*
X969044Y245019D01*
X969219D01*
Y243449D01*
X969044D01*
G37*
G36*
G01X970668Y246920D02*
X971338Y246570D01*
Y245700D01*
X970668Y245350D01*
X970493D01*
Y246920D01*
X970668D01*
G37*
G36*
G01Y250820D02*
X971338Y250470D01*
Y249600D01*
X970668Y249250D01*
X970493D01*
Y250820D01*
X970668D01*
G37*
G36*
G01Y254720D02*
X971338Y254370D01*
Y253500D01*
X970668Y253150D01*
X970493D01*
Y254720D01*
X970668D01*
G37*
G36*
G01Y258620D02*
X971338Y258270D01*
Y257400D01*
X970668Y257050D01*
X970493D01*
Y258620D01*
X970668D01*
G37*
G36*
G01Y262544D02*
X971338Y262194D01*
Y261324D01*
X970668Y260974D01*
X970493D01*
Y262544D01*
X970668D01*
G37*
G36*
G01Y223520D02*
X971338Y223170D01*
Y222300D01*
X970668Y221950D01*
X970493D01*
Y223520D01*
X970668D01*
G37*
G36*
G01Y227445D02*
X971338Y227095D01*
Y226225D01*
X970668Y225875D01*
X970493D01*
Y227445D01*
X970668D01*
G37*
G36*
G01Y231369D02*
X971338Y231019D01*
Y230149D01*
X970668Y229799D01*
X970493D01*
Y231369D01*
X970668D01*
G37*
G36*
G01Y235220D02*
X971338Y234870D01*
Y234000D01*
X970668Y233650D01*
X970493D01*
Y235220D01*
X970668D01*
G37*
G36*
G01Y239120D02*
X971338Y238770D01*
Y237900D01*
X970668Y237550D01*
X970493D01*
Y239120D01*
X970668D01*
G37*
G36*
G01Y243020D02*
X971338Y242670D01*
Y241800D01*
X970668Y241450D01*
X970493D01*
Y243020D01*
X970668D01*
G37*
G36*
G01X932948Y328254D02*
X932980Y327499D01*
X932227Y327064D01*
X931589Y327469D01*
X931501Y327620D01*
X932861Y328405D01*
X932948Y328254D01*
G37*
G36*
G01X929574Y326308D02*
X929606Y325553D01*
X928853Y325118D01*
X928215Y325523D01*
X928127Y325675D01*
X929487Y326460D01*
X929574Y326308D01*
G37*
G36*
G01X926158Y324336D02*
X926190Y323580D01*
X925436Y323145D01*
X924798Y323551D01*
X924711Y323702D01*
X926070Y324487D01*
X926158Y324336D01*
G37*
G36*
G01X923656Y323551D02*
X923018Y323145D01*
X922264Y323580D01*
X922296Y324336D01*
X922384Y324487D01*
X923743Y323702D01*
X923656Y323551D01*
G37*
G36*
G01X920239Y325523D02*
X919601Y325118D01*
X918848Y325553D01*
X918880Y326308D01*
X918967Y326460D01*
X920327Y325675D01*
X920239Y325523D01*
G37*
G36*
G01X914699Y325524D02*
X914349Y324764D01*
X913449D01*
X913099Y325524D01*
Y325699D01*
X914699D01*
Y325524D01*
G37*
G36*
G01X936334Y330208D02*
X936366Y329453D01*
X935613Y329018D01*
X934975Y329423D01*
X934887Y329575D01*
X936247Y330360D01*
X936334Y330208D01*
G37*
G36*
G01X929574Y341908D02*
X929606Y341153D01*
X928853Y340718D01*
X928215Y341123D01*
X928127Y341275D01*
X929487Y342060D01*
X929574Y341908D01*
G37*
G36*
G01X926999Y341123D02*
X926361Y340718D01*
X925608Y341153D01*
X925640Y341908D01*
X925727Y342060D01*
X927087Y341275D01*
X926999Y341123D01*
G37*
G36*
G01X925640Y325912D02*
X925608Y326667D01*
X926361Y327102D01*
X926999Y326697D01*
X927087Y326545D01*
X925727Y325761D01*
X925640Y325912D01*
G37*
G36*
G01X921455Y326697D02*
X922093Y327102D01*
X922846Y326667D01*
X922814Y325912D01*
X922727Y325761D01*
X921367Y326545D01*
X921455Y326697D01*
G37*
G36*
G01X918075Y328647D02*
X918713Y329052D01*
X919466Y328617D01*
X919434Y327862D01*
X919347Y327711D01*
X917987Y328495D01*
X918075Y328647D01*
G37*
G36*
G01X915326Y327698D02*
X915164Y328437D01*
X915830Y328996D01*
X916529Y328708D01*
X916641Y328574D01*
X915439Y327564D01*
X915326Y327698D01*
G37*
G36*
G01X910984Y328718D02*
X911769Y329008D01*
X912405Y328372D01*
X912115Y327587D01*
X911992Y327463D01*
X910860Y328595D01*
X910984Y328718D01*
G37*
G36*
G01X929574Y338008D02*
X929606Y337253D01*
X928853Y336818D01*
X928215Y337223D01*
X928127Y337375D01*
X929487Y338160D01*
X929574Y338008D01*
G37*
G36*
G01X926999Y337223D02*
X926361Y336818D01*
X925608Y337253D01*
X925640Y338008D01*
X925727Y338160D01*
X927087Y337375D01*
X926999Y337223D01*
G37*
G36*
G01X923625Y339169D02*
X922987Y338764D01*
X922234Y339199D01*
X922266Y339954D01*
X922353Y340105D01*
X923713Y339320D01*
X923625Y339169D01*
G37*
G36*
G01X920239Y341123D02*
X919601Y340718D01*
X918848Y341153D01*
X918880Y341908D01*
X918967Y342060D01*
X920327Y341275D01*
X920239Y341123D01*
G37*
G36*
G01X932939Y324349D02*
X932971Y323594D01*
X932218Y323159D01*
X931580Y323564D01*
X931492Y323715D01*
X932852Y324501D01*
X932939Y324349D01*
G37*
G36*
G01X929574Y322408D02*
X929606Y321653D01*
X928853Y321218D01*
X928215Y321623D01*
X928127Y321775D01*
X929487Y322560D01*
X929574Y322408D01*
G37*
G36*
G01X920239Y321623D02*
X919601Y321218D01*
X918848Y321653D01*
X918880Y322408D01*
X918967Y322560D01*
X920327Y321775D01*
X920239Y321623D01*
G37*
G36*
G01X913171Y322506D02*
X912821Y321746D01*
X911921D01*
X911571Y322506D01*
Y322681D01*
X913171D01*
Y322506D01*
G37*
G36*
G01X936334Y326308D02*
X936366Y325553D01*
X935613Y325118D01*
X934975Y325523D01*
X934887Y325675D01*
X936247Y326460D01*
X936334Y326308D01*
G37*
G36*
G01X926188Y320454D02*
X926220Y319699D01*
X925467Y319264D01*
X924829Y319669D01*
X924741Y319820D01*
X926101Y320605D01*
X926188Y320454D01*
G37*
G36*
G01X923625Y319669D02*
X922987Y319264D01*
X922234Y319699D01*
X922266Y320454D01*
X922353Y320605D01*
X923713Y319820D01*
X923625Y319669D01*
G37*
G36*
G01X929035Y323970D02*
X929003Y324725D01*
X929756Y325160D01*
X930394Y324755D01*
X930482Y324603D01*
X929122Y323818D01*
X929035Y323970D01*
G37*
G36*
G01X925646Y322015D02*
X925614Y322770D01*
X926367Y323205D01*
X927005Y322800D01*
X927093Y322649D01*
X925733Y321863D01*
X925646Y322015D01*
G37*
G36*
G01X921449Y322800D02*
X922087Y323205D01*
X922840Y322770D01*
X922808Y322015D01*
X922721Y321863D01*
X921361Y322649D01*
X921449Y322800D01*
G37*
G36*
G01X918069Y324749D02*
X918707Y325154D01*
X919460Y324719D01*
X919428Y323964D01*
X919341Y323812D01*
X917981Y324597D01*
X918069Y324749D01*
G37*
G36*
G01X911571Y323604D02*
X911921Y324364D01*
X912821D01*
X913171Y323604D01*
Y323429D01*
X911571D01*
Y323604D01*
G37*
G36*
G01X932561Y336697D02*
X932593Y335942D01*
X931840Y335507D01*
X931202Y335912D01*
X931114Y336063D01*
X932474Y336849D01*
X932561Y336697D01*
G37*
G36*
G01X929020Y335661D02*
X928988Y336416D01*
X929741Y336851D01*
X930379Y336446D01*
X930467Y336295D01*
X929107Y335509D01*
X929020Y335661D01*
G37*
G36*
G01X923625Y335269D02*
X922987Y334864D01*
X922234Y335299D01*
X922266Y336054D01*
X922353Y336205D01*
X923713Y335420D01*
X923625Y335269D01*
G37*
G36*
G01X920239Y337223D02*
X919601Y336818D01*
X918848Y337253D01*
X918880Y338008D01*
X918967Y338160D01*
X920327Y337375D01*
X920239Y337223D01*
G37*
G36*
G01X916865Y339169D02*
X916227Y338764D01*
X915474Y339199D01*
X915506Y339954D01*
X915593Y340105D01*
X916953Y339320D01*
X916865Y339169D01*
G37*
G36*
G01X912206Y341566D02*
X911856Y340806D01*
X910956D01*
X910606Y341566D01*
Y341741D01*
X912206D01*
Y341566D01*
G37*
G36*
G01X921449Y338400D02*
X922087Y338805D01*
X922840Y338370D01*
X922808Y337615D01*
X922721Y337463D01*
X921361Y338249D01*
X921449Y338400D01*
G37*
G36*
G01X918075Y340346D02*
X918713Y340751D01*
X919466Y340316D01*
X919434Y339561D01*
X919347Y339409D01*
X917987Y340195D01*
X918075Y340346D01*
G37*
G36*
G01X916865Y335269D02*
X916227Y334864D01*
X915474Y335299D01*
X915506Y336054D01*
X915593Y336205D01*
X916953Y335420D01*
X916865Y335269D01*
G37*
G36*
G01X912828Y337260D02*
X912478Y336500D01*
X911578D01*
X911228Y337260D01*
Y337435D01*
X912828D01*
Y337260D01*
G37*
G36*
G01X923625Y331369D02*
X922987Y330964D01*
X922234Y331399D01*
X922266Y332154D01*
X922353Y332305D01*
X923713Y331520D01*
X923625Y331369D01*
G37*
G36*
G01X920239Y333323D02*
X919601Y332918D01*
X918848Y333353D01*
X918880Y334108D01*
X918967Y334260D01*
X920327Y333475D01*
X920239Y333323D01*
G37*
G36*
G01X914678Y334527D02*
X915351Y334872D01*
X916061Y334369D01*
X915960Y333619D01*
X915859Y333477D01*
X914577Y334384D01*
X914678Y334527D01*
G37*
G36*
G01X929020Y331761D02*
X928988Y332516D01*
X929741Y332951D01*
X930379Y332546D01*
X930467Y332395D01*
X929107Y331609D01*
X929020Y331761D01*
G37*
G36*
G01X925646Y329815D02*
X925614Y330570D01*
X926367Y331005D01*
X927005Y330600D01*
X927093Y330449D01*
X925733Y329663D01*
X925646Y329815D01*
G37*
G36*
G01X921449Y330600D02*
X922087Y331005D01*
X922840Y330570D01*
X922808Y329815D01*
X922721Y329663D01*
X921361Y330449D01*
X921449Y330600D01*
G37*
G36*
G01X918075Y332546D02*
X918713Y332951D01*
X919466Y332516D01*
X919434Y331761D01*
X919347Y331609D01*
X917987Y332395D01*
X918075Y332546D01*
G37*
G36*
G01X932406Y333715D02*
X932374Y334470D01*
X933127Y334905D01*
X933765Y334500D01*
X933853Y334349D01*
X932493Y333563D01*
X932406Y333715D01*
G37*
G36*
G01X921449Y334500D02*
X922087Y334905D01*
X922840Y334470D01*
X922808Y333715D01*
X922721Y333563D01*
X921361Y334349D01*
X921449Y334500D01*
G37*
G36*
G01X918075Y336446D02*
X918713Y336851D01*
X919466Y336416D01*
X919434Y335661D01*
X919347Y335509D01*
X917987Y336295D01*
X918075Y336446D01*
G37*
G36*
G01X914689Y338400D02*
X915327Y338805D01*
X916080Y338370D01*
X916048Y337615D01*
X915961Y337463D01*
X914601Y338249D01*
X914689Y338400D01*
G37*
G36*
G01X911228Y338360D02*
X911578Y339120D01*
X912478D01*
X912828Y338360D01*
Y338185D01*
X911228D01*
Y338360D01*
G37*
G36*
G01X926188Y328254D02*
X926220Y327499D01*
X925467Y327064D01*
X924829Y327469D01*
X924741Y327620D01*
X926101Y328405D01*
X926188Y328254D01*
G37*
G36*
G01X923625Y327469D02*
X922987Y327064D01*
X922234Y327499D01*
X922266Y328254D01*
X922353Y328405D01*
X923713Y327620D01*
X923625Y327469D01*
G37*
G36*
G01X932948Y332154D02*
X932980Y331399D01*
X932227Y330964D01*
X931589Y331369D01*
X931501Y331520D01*
X932861Y332305D01*
X932948Y332154D01*
G37*
G36*
G01X929574Y330208D02*
X929606Y329453D01*
X928853Y329018D01*
X928215Y329423D01*
X928127Y329575D01*
X929487Y330360D01*
X929574Y330208D01*
G37*
G36*
G01X920239Y329423D02*
X919601Y329018D01*
X918848Y329453D01*
X918880Y330208D01*
X918967Y330360D01*
X920327Y329575D01*
X920239Y329423D01*
G37*
G36*
G01X916550Y331310D02*
X915851Y331022D01*
X915185Y331581D01*
X915347Y332320D01*
X915460Y332454D01*
X916662Y331444D01*
X916550Y331310D01*
G37*
G36*
G01X936263Y334072D02*
X936295Y333317D01*
X935542Y332882D01*
X934904Y333288D01*
X934816Y333438D01*
X936176Y334224D01*
X936263Y334072D01*
G37*
G36*
G01X967288Y330819D02*
X967958Y330469D01*
Y329599D01*
X967288Y329249D01*
X967113D01*
Y330819D01*
X967288D01*
G37*
G36*
G01Y334719D02*
X967958Y334369D01*
Y333499D01*
X967288Y333149D01*
X967113D01*
Y334719D01*
X967288D01*
G37*
G36*
G01Y342519D02*
X967958Y342169D01*
Y341299D01*
X967288Y340949D01*
X967113D01*
Y342519D01*
X967288D01*
G37*
G36*
G01Y338619D02*
X967958Y338269D01*
Y337399D01*
X967288Y337049D01*
X967113D01*
Y338619D01*
X967288D01*
G37*
G36*
G01X969044Y340949D02*
X968374Y341299D01*
Y342169D01*
X969044Y342519D01*
X969219D01*
Y340949D01*
X969044D01*
G37*
G36*
G01X965664Y331150D02*
X964994Y331500D01*
Y332370D01*
X965664Y332720D01*
X965839D01*
Y331150D01*
X965664D01*
G37*
G36*
G01Y327250D02*
X964994Y327600D01*
Y328470D01*
X965664Y328820D01*
X965839D01*
Y327250D01*
X965664D01*
G37*
G36*
G01Y338950D02*
X964994Y339300D01*
Y340170D01*
X965664Y340520D01*
X965839D01*
Y338950D01*
X965664D01*
G37*
G36*
G01Y335050D02*
X964994Y335400D01*
Y336270D01*
X965664Y336620D01*
X965839D01*
Y335050D01*
X965664D01*
G37*
G36*
G01X970668Y340520D02*
X971338Y340170D01*
Y339300D01*
X970668Y338950D01*
X970493D01*
Y340520D01*
X970668D01*
G37*
G36*
G01X962284Y337049D02*
X961614Y337399D01*
Y338269D01*
X962284Y338619D01*
X962459D01*
Y337049D01*
X962284D01*
G37*
G36*
G01Y340949D02*
X961614Y341299D01*
Y342169D01*
X962284Y342519D01*
X962459D01*
Y340949D01*
X962284D01*
G37*
G36*
G01Y329249D02*
X961614Y329599D01*
Y330469D01*
X962284Y330819D01*
X962459D01*
Y329249D01*
X962284D01*
G37*
G36*
G01X963157Y332725D02*
X963827Y332375D01*
Y331505D01*
X963157Y331155D01*
X962982D01*
Y332725D01*
X963157D01*
G37*
G36*
G01X962284Y333149D02*
X961614Y333499D01*
Y334369D01*
X962284Y334719D01*
X962459D01*
Y333149D01*
X962284D01*
G37*
G36*
G01X963908Y340520D02*
X964578Y340170D01*
Y339300D01*
X963908Y338950D01*
X963733D01*
Y340520D01*
X963908D01*
G37*
G36*
G01X963478Y337342D02*
X964234Y337311D01*
X964606Y336525D01*
X964149Y335922D01*
X963991Y335847D01*
X963320Y337267D01*
X963478Y337342D01*
G37*
G36*
G01X958904Y331150D02*
X958234Y331500D01*
Y332370D01*
X958904Y332720D01*
X959079D01*
Y331150D01*
X958904D01*
G37*
G36*
G01Y338950D02*
X958234Y339300D01*
Y340170D01*
X958904Y340520D01*
X959079D01*
Y338950D01*
X958904D01*
G37*
G36*
G01Y335050D02*
X958234Y335400D01*
Y336270D01*
X958904Y336620D01*
X959079D01*
Y335050D01*
X958904D01*
G37*
G36*
G01X960044Y335531D02*
X960798Y335476D01*
X961144Y334678D01*
X960669Y334090D01*
X960508Y334021D01*
X959884Y335461D01*
X960044Y335531D01*
G37*
G36*
G01X960528Y342519D02*
X961198Y342169D01*
Y341299D01*
X960528Y340949D01*
X960353D01*
Y342519D01*
X960528D01*
G37*
G36*
G01Y338619D02*
X961198Y338269D01*
Y337399D01*
X960528Y337049D01*
X960353D01*
Y338619D01*
X960528D01*
G37*
G36*
G01X970402Y335249D02*
X970370Y336004D01*
X971124Y336439D01*
X971762Y336034D01*
X971850Y335883D01*
X970490Y335098D01*
X970402Y335249D01*
G37*
G36*
G01X970668Y332720D02*
X971338Y332370D01*
Y331500D01*
X970668Y331150D01*
X970493D01*
Y332720D01*
X970668D01*
G37*
G36*
G01X969795Y329244D02*
X969125Y329594D01*
Y330464D01*
X969795Y330814D01*
X969970D01*
Y329244D01*
X969795D01*
G37*
G36*
G01X932987Y359201D02*
X932566Y358573D01*
X931702Y358667D01*
X931426Y359371D01*
X931445Y359545D01*
X933006Y359374D01*
X932987Y359201D01*
G37*
G36*
G01X928485Y364349D02*
X927815Y364699D01*
Y365569D01*
X928485Y365919D01*
X928660D01*
Y364349D01*
X928485D01*
G37*
G36*
G01Y368200D02*
X927815Y368550D01*
Y369420D01*
X928485Y369770D01*
X928660D01*
Y368200D01*
X928485D01*
G37*
G36*
G01X927014Y372314D02*
X926376Y371909D01*
X925623Y372344D01*
X925655Y373099D01*
X925742Y373251D01*
X927102Y372465D01*
X927014Y372314D01*
G37*
G36*
G01X922950Y374309D02*
X922600Y373549D01*
X921700D01*
X921350Y374309D01*
Y374484D01*
X922950D01*
Y374309D01*
G37*
G36*
G01X917260Y376989D02*
X916476Y376699D01*
X915839Y377336D01*
X916129Y378120D01*
X916253Y378244D01*
X917384Y377113D01*
X917260Y376989D01*
G37*
G36*
G01X929407Y360363D02*
X928652Y360373D01*
X928259Y361149D01*
X928699Y361764D01*
X928855Y361843D01*
X929564Y360442D01*
X929407Y360363D01*
G37*
G36*
G01X930109Y367845D02*
X930779Y367495D01*
Y366625D01*
X930109Y366275D01*
X929934D01*
Y367845D01*
X930109D01*
G37*
G36*
G01X924835Y375446D02*
X925473Y375851D01*
X926226Y375416D01*
X926194Y374661D01*
X926107Y374509D01*
X924747Y375295D01*
X924835Y375446D01*
G37*
G36*
G01X930108Y371743D02*
X930778Y371394D01*
Y370524D01*
X930109Y370174D01*
X929933D01*
Y371744D01*
X930108Y371743D01*
G37*
G36*
G01X928179Y373517D02*
X928816Y373923D01*
X929569Y373488D01*
X929538Y372733D01*
X929450Y372581D01*
X928090Y373366D01*
X928179Y373517D01*
G37*
G36*
G01X921350Y375409D02*
X921700Y376169D01*
X922600D01*
X922950Y375409D01*
Y375234D01*
X921350D01*
Y375409D01*
G37*
G36*
G01X916906Y378897D02*
X917690Y379187D01*
X918327Y378550D01*
X918037Y377766D01*
X917913Y377642D01*
X916782Y378773D01*
X916906Y378897D01*
G37*
G36*
G01X930070Y363751D02*
X930825Y363714D01*
X931190Y362924D01*
X930729Y362326D01*
X930570Y362252D01*
X929911Y363677D01*
X930070Y363751D01*
G37*
G36*
G01X932948Y343854D02*
X932980Y343099D01*
X932227Y342664D01*
X931589Y343069D01*
X931501Y343220D01*
X932861Y344005D01*
X932948Y343854D01*
G37*
G36*
G01X923625Y343069D02*
X922987Y342664D01*
X922234Y343099D01*
X922266Y343854D01*
X922353Y344005D01*
X923713Y343220D01*
X923625Y343069D01*
G37*
G36*
G01X920239Y345023D02*
X919601Y344618D01*
X918848Y345053D01*
X918880Y345808D01*
X918967Y345960D01*
X920327Y345175D01*
X920239Y345023D01*
G37*
G36*
G01X916865Y346969D02*
X916227Y346564D01*
X915474Y346999D01*
X915506Y347754D01*
X915593Y347905D01*
X916953Y347120D01*
X916865Y346969D01*
G37*
G36*
G01X936334Y345808D02*
X936366Y345053D01*
X935613Y344618D01*
X934975Y345023D01*
X934887Y345175D01*
X936247Y345960D01*
X936334Y345808D01*
G37*
G36*
G01X910158Y354144D02*
X910943Y354434D01*
X911579Y353798D01*
X911289Y353013D01*
X911166Y352889D01*
X910034Y354021D01*
X910158Y354144D01*
G37*
G36*
G01X929020Y343461D02*
X928988Y344216D01*
X929741Y344651D01*
X930379Y344246D01*
X930467Y344095D01*
X929107Y343309D01*
X929020Y343461D01*
G37*
G36*
G01X924835Y344246D02*
X925473Y344651D01*
X926226Y344216D01*
X926194Y343461D01*
X926107Y343309D01*
X924747Y344095D01*
X924835Y344246D01*
G37*
G36*
G01X921449Y346200D02*
X922087Y346605D01*
X922840Y346170D01*
X922808Y345415D01*
X922721Y345263D01*
X921361Y346049D01*
X921449Y346200D01*
G37*
G36*
G01X918075Y348146D02*
X918713Y348551D01*
X919466Y348116D01*
X919434Y347361D01*
X919347Y347209D01*
X917987Y347995D01*
X918075Y348146D01*
G37*
G36*
G01X914681Y350019D02*
X915319Y350424D01*
X916072Y349989D01*
X916040Y349234D01*
X915953Y349082D01*
X914593Y349868D01*
X914681Y350019D01*
G37*
G36*
G01X925856Y358455D02*
X925186Y358805D01*
Y359675D01*
X925856Y360025D01*
X926031D01*
Y358455D01*
X925856D01*
G37*
G36*
G01X925105Y362350D02*
X924435Y362700D01*
Y363570D01*
X925105Y363920D01*
X925280D01*
Y362350D01*
X925105D01*
G37*
G36*
G01X921827Y367823D02*
X921042Y367533D01*
X920406Y368170D01*
X920696Y368954D01*
X920819Y369078D01*
X921951Y367947D01*
X921827Y367823D01*
G37*
G36*
G01X915127Y372523D02*
X914342Y372233D01*
X913706Y372870D01*
X913996Y373654D01*
X914119Y373778D01*
X915251Y372647D01*
X915127Y372523D01*
G37*
G36*
G01X912369Y375281D02*
X911584Y374991D01*
X910948Y375628D01*
X911238Y376412D01*
X911361Y376536D01*
X912493Y375405D01*
X912369Y375281D01*
G37*
G36*
G01X919069Y370581D02*
X918284Y370291D01*
X917648Y370928D01*
X917938Y371712D01*
X918061Y371836D01*
X919193Y370705D01*
X919069Y370581D01*
G37*
G36*
G01X926728Y365893D02*
X927398Y365544D01*
Y364674D01*
X926729Y364324D01*
X926554Y364323D01*
Y365894D01*
X926728Y365893D01*
G37*
G36*
G01X924799Y367667D02*
X925436Y368073D01*
X926189Y367638D01*
X926158Y366883D01*
X926071Y366731D01*
X924711Y367517D01*
X924799Y367667D01*
G37*
G36*
G01X914772Y374431D02*
X915557Y374721D01*
X916194Y374085D01*
X915904Y373300D01*
X915780Y373176D01*
X914649Y374307D01*
X914772Y374431D01*
G37*
G36*
G01X912014Y377189D02*
X912799Y377479D01*
X913436Y376843D01*
X913146Y376058D01*
X913022Y375934D01*
X911891Y377065D01*
X912014Y377189D01*
G37*
G36*
G01X918714Y372489D02*
X919499Y372779D01*
X920136Y372143D01*
X919846Y371358D01*
X919722Y371234D01*
X918591Y372365D01*
X918714Y372489D01*
G37*
G36*
G01X921172Y370031D02*
X921957Y370321D01*
X922594Y369685D01*
X922304Y368900D01*
X922180Y368776D01*
X921049Y369907D01*
X921172Y370031D01*
G37*
G36*
G01X931865Y389675D02*
X931195Y390025D01*
Y390895D01*
X931865Y391245D01*
X932040D01*
Y389675D01*
X931865D01*
G37*
G36*
G01X930379Y393772D02*
X929741Y393367D01*
X928988Y393802D01*
X929020Y394557D01*
X929107Y394709D01*
X930467Y393923D01*
X930379Y393772D01*
G37*
G36*
G01X927014Y395714D02*
X926376Y395309D01*
X925623Y395744D01*
X925655Y396499D01*
X925742Y396651D01*
X927102Y395865D01*
X927014Y395714D01*
G37*
G36*
G01X923625Y397669D02*
X922987Y397264D01*
X922234Y397699D01*
X922266Y398454D01*
X922353Y398605D01*
X923713Y397820D01*
X923625Y397669D01*
G37*
G36*
G01X920660Y400479D02*
X919876Y400189D01*
X919239Y400826D01*
X919529Y401610D01*
X919653Y401734D01*
X920784Y400603D01*
X920660Y400479D01*
G37*
G36*
G01X932687Y393169D02*
X933357Y392820D01*
Y391950D01*
X932687Y391600D01*
X932513Y391599D01*
X932512Y393170D01*
X932687Y393169D01*
G37*
G36*
G01X928200Y396905D02*
X928838Y397310D01*
X929591Y396875D01*
X929559Y396120D01*
X929472Y395968D01*
X928112Y396753D01*
X928200Y396905D01*
G37*
G36*
G01X924835Y398846D02*
X925473Y399251D01*
X926226Y398816D01*
X926194Y398061D01*
X926107Y397909D01*
X924747Y398695D01*
X924835Y398846D01*
G37*
G36*
G01X921406Y401287D02*
X922190Y401577D01*
X922827Y400940D01*
X922537Y400156D01*
X922413Y400032D01*
X921282Y401163D01*
X921406Y401287D01*
G37*
G36*
G01X945385Y397450D02*
X944715Y397800D01*
Y398670D01*
X945385Y399020D01*
X945560D01*
Y397450D01*
X945385D01*
G37*
G36*
G01X942547Y394167D02*
X942515Y394922D01*
X943268Y395356D01*
X943906Y394951D01*
X943994Y394800D01*
X942633Y394015D01*
X942547Y394167D01*
G37*
G36*
G01X942005Y391591D02*
X941336Y391941D01*
Y392810D01*
X942006Y393160D01*
X942181Y393161D01*
X942180Y391590D01*
X942005Y391591D01*
G37*
G36*
G01X946217Y401016D02*
X945458Y401365D01*
Y402266D01*
X946217Y402615D01*
X946393D01*
Y401016D01*
X946217D01*
G37*
G36*
G01X947009Y397094D02*
X947679Y396744D01*
Y395874D01*
X947009Y395524D01*
X946834D01*
Y397094D01*
X947009D01*
G37*
G36*
G01X947316Y402615D02*
X948076Y402265D01*
Y401366D01*
X947316Y401016D01*
X947141Y401015D01*
Y402616D01*
X947316Y402615D01*
G37*
G36*
G01X946274Y394432D02*
X946607Y393753D01*
X946092Y393052D01*
X945345Y393166D01*
X945203Y393270D01*
X946133Y394535D01*
X946274Y394432D01*
G37*
G36*
G01X927005Y391819D02*
X926367Y391414D01*
X925614Y391849D01*
X925646Y392604D01*
X925733Y392755D01*
X927093Y391970D01*
X927005Y391819D01*
G37*
G36*
G01X923619Y393772D02*
X922981Y393367D01*
X922228Y393802D01*
X922260Y394557D01*
X922347Y394709D01*
X923707Y393923D01*
X923619Y393772D01*
G37*
G36*
G01X919337Y395759D02*
X918987Y394999D01*
X918087D01*
X917737Y395759D01*
Y395934D01*
X919337D01*
Y395759D01*
G37*
G36*
G01X914704Y396884D02*
X913919Y396594D01*
X913283Y397231D01*
X913572Y398016D01*
X913696Y398139D01*
X914828Y397008D01*
X914704Y396884D01*
G37*
G36*
G01X924829Y394950D02*
X925467Y395355D01*
X926220Y394920D01*
X926188Y394165D01*
X926101Y394013D01*
X924741Y394799D01*
X924829Y394950D01*
G37*
G36*
G01X921440Y396905D02*
X922078Y397310D01*
X922831Y396875D01*
X922799Y396120D01*
X922712Y395968D01*
X921352Y396753D01*
X921440Y396905D01*
G37*
G36*
G01X917737Y396860D02*
X918087Y397620D01*
X918987D01*
X919337Y396860D01*
Y396685D01*
X917737D01*
Y396860D01*
G37*
G36*
G01X914351Y398794D02*
X915136Y399084D01*
X915772Y398448D01*
X915482Y397663D01*
X915359Y397539D01*
X914227Y398670D01*
X914351Y398794D01*
G37*
G36*
G01X939376Y389655D02*
X938706Y390005D01*
Y390875D01*
X939376Y391225D01*
X939551D01*
Y389655D01*
X939376D01*
G37*
G36*
G01X940249Y393170D02*
X940919Y392820D01*
Y391950D01*
X940249Y391600D01*
X940074D01*
Y393170D01*
X940249D01*
G37*
G36*
G01X941417Y400018D02*
X940633Y399728D01*
X939996Y400365D01*
X940286Y401149D01*
X940410Y401273D01*
X941541Y400142D01*
X941417Y400018D01*
G37*
G36*
G01X938549Y402369D02*
X938199Y401609D01*
X937299D01*
X936949Y402369D01*
Y402544D01*
X938549D01*
Y402369D01*
G37*
G36*
G01X943629Y399020D02*
X944299Y398670D01*
Y397800D01*
X943629Y397450D01*
X943454D01*
Y399020D01*
X943629D01*
G37*
G36*
G01X941063Y401926D02*
X941848Y402216D01*
X942484Y401580D01*
X942194Y400795D01*
X942071Y400671D01*
X940939Y401803D01*
X941063Y401926D01*
G37*
G36*
G01X916865Y343069D02*
X916227Y342664D01*
X915474Y343099D01*
X915506Y343854D01*
X915593Y344005D01*
X916953Y343220D01*
X916865Y343069D01*
G37*
G36*
G01X921449Y342300D02*
X922087Y342705D01*
X922840Y342270D01*
X922808Y341515D01*
X922721Y341363D01*
X921361Y342149D01*
X921449Y342300D01*
G37*
G36*
G01X918075Y344246D02*
X918713Y344651D01*
X919466Y344216D01*
X919434Y343461D01*
X919347Y343309D01*
X917987Y344095D01*
X918075Y344246D01*
G37*
G36*
G01X914689Y346200D02*
X915327Y346605D01*
X916080Y346170D01*
X916048Y345415D01*
X915961Y345263D01*
X914601Y346049D01*
X914689Y346200D01*
G37*
G36*
G01Y342300D02*
X915327Y342705D01*
X916080Y342270D01*
X916048Y341515D01*
X915961Y341363D01*
X914601Y342149D01*
X914689Y342300D01*
G37*
G36*
G01X910606Y342664D02*
X910956Y343424D01*
X911856D01*
X912206Y342664D01*
Y342489D01*
X910606D01*
Y342664D01*
G37*
G36*
G01X914095Y358041D02*
X913746Y357282D01*
X912845D01*
X912495Y358041D01*
Y358217D01*
X914095D01*
Y358041D01*
G37*
G36*
G01X929574Y345808D02*
X929606Y345053D01*
X928853Y344618D01*
X928215Y345023D01*
X928127Y345175D01*
X929487Y345960D01*
X929574Y345808D01*
G37*
G36*
G01X926999Y345023D02*
X926361Y344618D01*
X925608Y345053D01*
X925640Y345808D01*
X925727Y345960D01*
X927087Y345175D01*
X926999Y345023D01*
G37*
G36*
G01X923625Y346969D02*
X922987Y346564D01*
X922234Y346999D01*
X922266Y347754D01*
X922353Y347905D01*
X923713Y347120D01*
X923625Y346969D01*
G37*
G36*
G01X920239Y348923D02*
X919601Y348518D01*
X918848Y348953D01*
X918880Y349708D01*
X918967Y349860D01*
X920327Y349075D01*
X920239Y348923D01*
G37*
G36*
G01X932465Y348523D02*
X932870Y347885D01*
X932436Y347132D01*
X931681Y347164D01*
X931529Y347251D01*
X932314Y348610D01*
X932465Y348523D01*
G37*
G36*
G01X916632Y350883D02*
X915969Y350520D01*
X915244Y351002D01*
X915325Y351755D01*
X915423Y351900D01*
X916728Y351028D01*
X916632Y350883D01*
G37*
G36*
G01X935948Y350351D02*
X935980Y349596D01*
X935227Y349161D01*
X934589Y349566D01*
X934501Y349717D01*
X935861Y350503D01*
X935948Y350351D01*
G37*
G36*
G01X916655Y357002D02*
X917415Y356652D01*
Y355751D01*
X916655Y355402D01*
X916480D01*
Y357002D01*
X916655D01*
G37*
G36*
G01X921449Y350100D02*
X922087Y350505D01*
X922840Y350070D01*
X922808Y349315D01*
X922721Y349163D01*
X921361Y349949D01*
X921449Y350100D01*
G37*
G36*
G01X918075Y352046D02*
X918713Y352451D01*
X919466Y352016D01*
X919434Y351261D01*
X919347Y351109D01*
X917987Y351895D01*
X918075Y352046D01*
G37*
G36*
G01X924835Y348146D02*
X925473Y348551D01*
X926226Y348116D01*
X926194Y347361D01*
X926107Y347209D01*
X924747Y347995D01*
X924835Y348146D01*
G37*
G36*
G01X910359Y361144D02*
X911143Y361434D01*
X911780Y360797D01*
X911490Y360013D01*
X911366Y359889D01*
X910235Y361020D01*
X910359Y361144D01*
G37*
G36*
G01X912995Y359140D02*
X913345Y359900D01*
X914246D01*
X914595Y359140D01*
Y358965D01*
X912995D01*
Y359140D01*
G37*
G36*
G01X921449Y354000D02*
X922087Y354405D01*
X922840Y353970D01*
X922808Y353215D01*
X922721Y353063D01*
X921361Y353849D01*
X921449Y354000D01*
G37*
G36*
G01X919967Y359741D02*
X920727Y359391D01*
Y358491D01*
X919967Y358141D01*
X919792D01*
Y359741D01*
X919967D01*
G37*
G36*
G01X932406Y353215D02*
X932374Y353970D01*
X933127Y354405D01*
X933765Y354000D01*
X933853Y353849D01*
X932493Y353063D01*
X932406Y353215D01*
G37*
G36*
G01X924835Y352046D02*
X925473Y352451D01*
X926226Y352016D01*
X926194Y351261D01*
X926107Y351109D01*
X924747Y351895D01*
X924835Y352046D01*
G37*
G36*
G01X914866Y364016D02*
X915216Y364776D01*
X916116D01*
X916466Y364016D01*
Y363841D01*
X914866D01*
Y364016D01*
G37*
G36*
G01X918331Y363948D02*
X919116Y364238D01*
X919753Y363601D01*
X919463Y362816D01*
X919339Y362692D01*
X918207Y363824D01*
X918331Y363948D01*
G37*
G36*
G01X936869Y391245D02*
X937539Y390895D01*
Y390025D01*
X936869Y389675D01*
X936694D01*
Y391245D01*
X936869D01*
G37*
G36*
G01X931595Y398846D02*
X932233Y399251D01*
X932986Y398816D01*
X932954Y398061D01*
X932867Y397909D01*
X931507Y398695D01*
X931595Y398846D01*
G37*
G36*
G01X927229Y402353D02*
X928014Y402643D01*
X928650Y402007D01*
X928360Y401222D01*
X928237Y401098D01*
X927105Y402230D01*
X927229Y402353D01*
G37*
G36*
G01X936868Y395143D02*
X937538Y394794D01*
Y393924D01*
X936869Y393574D01*
X936694Y393573D01*
Y395144D01*
X936868Y395143D01*
G37*
G36*
G01X934939Y396917D02*
X935576Y397323D01*
X936329Y396888D01*
X936298Y396133D01*
X936211Y395981D01*
X934851Y396767D01*
X934939Y396917D01*
G37*
G36*
G01X923625Y354769D02*
X922987Y354364D01*
X922234Y354799D01*
X922266Y355554D01*
X922353Y355705D01*
X923713Y354920D01*
X923625Y354769D01*
G37*
G36*
G01X926999Y352823D02*
X926361Y352418D01*
X925608Y352853D01*
X925640Y353608D01*
X925727Y353760D01*
X927087Y352975D01*
X926999Y352823D01*
G37*
G36*
G01X914796Y366501D02*
X914012Y366211D01*
X913375Y366848D01*
X913665Y367632D01*
X913789Y367756D01*
X914920Y366625D01*
X914796Y366501D01*
G37*
G36*
G01X918478Y365575D02*
X918129Y364816D01*
X917228D01*
X916879Y365575D01*
Y365751D01*
X918478D01*
Y365575D01*
G37*
G36*
G01X921115Y363935D02*
X920330Y363645D01*
X919694Y364281D01*
X919984Y365066D01*
X920107Y365190D01*
X921239Y364058D01*
X921115Y363935D01*
G37*
G36*
G01X921727Y359467D02*
X920967Y359817D01*
Y360717D01*
X921727Y361067D01*
X921902D01*
Y359467D01*
X921727D01*
G37*
G36*
G01X912038Y369259D02*
X911254Y368969D01*
X910617Y369606D01*
X910907Y370390D01*
X911031Y370514D01*
X912162Y369383D01*
X912038Y369259D01*
G37*
G36*
G01X930960Y402527D02*
X930175Y402237D01*
X929539Y402873D01*
X929829Y403658D01*
X929952Y403782D01*
X931084Y402650D01*
X930960Y402527D01*
G37*
G36*
G01X937208Y397611D02*
X936537Y397263D01*
X935824Y397762D01*
X935922Y398512D01*
X936022Y398655D01*
X937308Y397755D01*
X937208Y397611D01*
G37*
G36*
G01X933809Y399638D02*
X933171Y399233D01*
X932418Y399668D01*
X932450Y400423D01*
X932537Y400575D01*
X933897Y399790D01*
X933809Y399638D01*
G37*
G36*
G01X918867Y358141D02*
X918107Y358491D01*
Y359391D01*
X918867Y359741D01*
X919042D01*
Y358141D01*
X918867D01*
G37*
G36*
G01X932948Y351654D02*
X932980Y350899D01*
X932227Y350464D01*
X931589Y350869D01*
X931501Y351020D01*
X932861Y351805D01*
X932948Y351654D01*
G37*
G36*
G01X929574Y349708D02*
X929606Y348953D01*
X928853Y348518D01*
X928215Y348923D01*
X928127Y349075D01*
X929487Y349860D01*
X929574Y349708D01*
G37*
G36*
G01X926999Y348923D02*
X926361Y348518D01*
X925608Y348953D01*
X925640Y349708D01*
X925727Y349860D01*
X927087Y349075D01*
X926999Y348923D01*
G37*
G36*
G01X923625Y350869D02*
X922987Y350464D01*
X922234Y350899D01*
X922266Y351654D01*
X922353Y351805D01*
X923713Y351020D01*
X923625Y350869D01*
G37*
G36*
G01X920239Y352823D02*
X919601Y352418D01*
X918848Y352853D01*
X918880Y353608D01*
X918967Y353760D01*
X920327Y352975D01*
X920239Y352823D01*
G37*
G36*
G01X936277Y353597D02*
X936309Y352842D01*
X935556Y352407D01*
X934918Y352813D01*
X934830Y352963D01*
X936190Y353749D01*
X936277Y353597D01*
G37*
G36*
G01X916466Y362916D02*
X916116Y362156D01*
X915216D01*
X914866Y362916D01*
Y363091D01*
X916466D01*
Y362916D01*
G37*
G36*
G01X935245Y387700D02*
X934575Y388050D01*
Y388920D01*
X935245Y389270D01*
X935420D01*
Y387700D01*
X935245D01*
G37*
G36*
G01X937130Y385960D02*
X936459Y385612D01*
X935746Y386111D01*
X935844Y386860D01*
X935944Y387003D01*
X937230Y386104D01*
X937130Y385960D01*
G37*
G36*
G01X930385Y397669D02*
X929747Y397264D01*
X928994Y397699D01*
X929026Y398454D01*
X929113Y398605D01*
X930473Y397820D01*
X930385Y397669D01*
G37*
G36*
G01X927582Y400444D02*
X926798Y400154D01*
X926161Y400791D01*
X926451Y401575D01*
X926575Y401699D01*
X927706Y400568D01*
X927582Y400444D01*
G37*
G36*
G01X935245Y391600D02*
X934575Y391950D01*
Y392820D01*
X935245Y393170D01*
X935420D01*
Y391600D01*
X935245D01*
G37*
G36*
G01X933774Y395714D02*
X933136Y395309D01*
X932383Y395744D01*
X932415Y396499D01*
X932502Y396651D01*
X933862Y395865D01*
X933774Y395714D01*
G37*
G36*
G01X924835Y355946D02*
X925473Y356351D01*
X926226Y355916D01*
X926194Y355161D01*
X926107Y355009D01*
X924747Y355795D01*
X924835Y355946D01*
G37*
G36*
G01X922827Y360067D02*
X923587Y359717D01*
Y358817D01*
X922827Y358467D01*
X922652D01*
Y360067D01*
X922827D01*
G37*
G36*
G01X928151Y354029D02*
X928789Y354434D01*
X929542Y353999D01*
X929510Y353244D01*
X929423Y353092D01*
X928063Y353878D01*
X928151Y354029D01*
G37*
G36*
G01X914443Y368410D02*
X915228Y368700D01*
X915864Y368064D01*
X915574Y367279D01*
X915451Y367155D01*
X914319Y368287D01*
X914443Y368410D01*
G37*
G36*
G01X916879Y366676D02*
X917229Y367436D01*
X918128D01*
X918478Y366676D01*
X918479Y366501D01*
X916878D01*
X916879Y366676D01*
G37*
G36*
G01X911685Y371168D02*
X912470Y371458D01*
X913106Y370822D01*
X912816Y370037D01*
X912693Y369913D01*
X911561Y371045D01*
X911685Y371168D01*
G37*
G36*
G01X920762Y365844D02*
X921546Y366134D01*
X922183Y365497D01*
X921893Y364713D01*
X921769Y364589D01*
X920638Y365720D01*
X920762Y365844D01*
G37*
G36*
G01X934947Y400807D02*
X935585Y401212D01*
X936338Y400777D01*
X936306Y400022D01*
X936219Y399871D01*
X934859Y400655D01*
X934947Y400807D01*
G37*
G36*
G01X938870Y397866D02*
X939625Y397898D01*
X940060Y397145D01*
X939655Y396506D01*
X939503Y396419D01*
X938718Y397779D01*
X938870Y397866D01*
G37*
G36*
G01X967287Y393179D02*
X967957Y392829D01*
Y391959D01*
X967287Y391609D01*
X967112D01*
Y393179D01*
X967287D01*
G37*
G36*
G01X965863Y400123D02*
X966623Y399773D01*
Y398873D01*
X965863Y398523D01*
X965688D01*
Y400123D01*
X965863D01*
G37*
G36*
G01X967288Y385419D02*
X967958Y385069D01*
Y384199D01*
X967288Y383849D01*
X967113D01*
Y385419D01*
X967288D01*
G37*
G36*
G01Y381519D02*
X967958Y381169D01*
Y380299D01*
X967288Y379949D01*
X967113D01*
Y381519D01*
X967288D01*
G37*
G36*
G01Y377619D02*
X967958Y377269D01*
Y376399D01*
X967288Y376049D01*
X967113D01*
Y377619D01*
X967288D01*
G37*
G36*
G01Y373694D02*
X967958Y373344D01*
Y372474D01*
X967288Y372124D01*
X967113D01*
Y373694D01*
X967288D01*
G37*
G36*
G01Y369770D02*
X967958Y369420D01*
Y368550D01*
X967288Y368200D01*
X967113D01*
Y369770D01*
X967288D01*
G37*
G36*
G01Y365919D02*
X967958Y365569D01*
Y364699D01*
X967288Y364349D01*
X967113D01*
Y365919D01*
X967288D01*
G37*
G36*
G01Y362019D02*
X967958Y361669D01*
Y360799D01*
X967288Y360449D01*
X967113D01*
Y362019D01*
X967288D01*
G37*
G36*
G01Y389319D02*
X967958Y388969D01*
Y388099D01*
X967288Y387749D01*
X967113D01*
Y389319D01*
X967288D01*
G37*
G36*
G01Y346419D02*
X967958Y346069D01*
Y345199D01*
X967288Y344849D01*
X967113D01*
Y346419D01*
X967288D01*
G37*
G36*
G01Y354219D02*
X967958Y353869D01*
Y352999D01*
X967288Y352649D01*
X967113D01*
Y354219D01*
X967288D01*
G37*
G36*
G01Y350319D02*
X967958Y349969D01*
Y349099D01*
X967288Y348749D01*
X967113D01*
Y350319D01*
X967288D01*
G37*
G36*
G01Y358119D02*
X967958Y357769D01*
Y356899D01*
X967288Y356549D01*
X967113D01*
Y358119D01*
X967288D01*
G37*
G36*
G01X969044Y372124D02*
X968374Y372474D01*
Y373344D01*
X969044Y373694D01*
X969219D01*
Y372124D01*
X969044D01*
G37*
G36*
G01X967916Y399021D02*
X967156Y399371D01*
Y400271D01*
X967916Y400621D01*
X968091D01*
Y399021D01*
X967916D01*
G37*
G36*
G01X969581Y391821D02*
X968821Y392171D01*
Y393071D01*
X969581Y393421D01*
X969756D01*
Y391821D01*
X969581D01*
G37*
G36*
G01Y384021D02*
X968821Y384371D01*
Y385271D01*
X969581Y385621D01*
X969756D01*
Y384021D01*
X969581D01*
G37*
G36*
G01X969044Y379949D02*
X968374Y380299D01*
Y381169D01*
X969044Y381519D01*
X969219D01*
Y379949D01*
X969044D01*
G37*
G36*
G01Y376049D02*
X968374Y376399D01*
Y377269D01*
X969044Y377619D01*
X969219D01*
Y376049D01*
X969044D01*
G37*
G36*
G01X969581Y387921D02*
X968821Y388271D01*
Y389171D01*
X969581Y389521D01*
X969756D01*
Y387921D01*
X969581D01*
G37*
G36*
G01X969044Y368200D02*
X968374Y368550D01*
Y369420D01*
X969044Y369770D01*
X969219D01*
Y368200D01*
X969044D01*
G37*
G36*
G01Y364349D02*
X968374Y364699D01*
Y365569D01*
X969044Y365919D01*
X969219D01*
Y364349D01*
X969044D01*
G37*
G36*
G01Y360449D02*
X968374Y360799D01*
Y361669D01*
X969044Y362019D01*
X969219D01*
Y360449D01*
X969044D01*
G37*
G36*
G01Y352649D02*
X968374Y352999D01*
Y353869D01*
X969044Y354219D01*
X969219D01*
Y352649D01*
X969044D01*
G37*
G36*
G01Y348749D02*
X968374Y349099D01*
Y349969D01*
X969044Y350319D01*
X969219D01*
Y348749D01*
X969044D01*
G37*
G36*
G01Y344849D02*
X968374Y345199D01*
Y346069D01*
X969044Y346419D01*
X969219D01*
Y344849D01*
X969044D01*
G37*
G36*
G01Y356549D02*
X968374Y356899D01*
Y357769D01*
X969044Y358119D01*
X969219D01*
Y356549D01*
X969044D01*
G37*
G36*
G01X964763Y398523D02*
X964003Y398873D01*
Y399773D01*
X964763Y400123D01*
X964938D01*
Y398523D01*
X964763D01*
G37*
G36*
G01X965664Y385750D02*
X964994Y386100D01*
Y386970D01*
X965664Y387320D01*
X965839D01*
Y385750D01*
X965664D01*
G37*
G36*
G01Y381850D02*
X964994Y382200D01*
Y383070D01*
X965664Y383420D01*
X965839D01*
Y381850D01*
X965664D01*
G37*
G36*
G01Y377950D02*
X964994Y378300D01*
Y379170D01*
X965664Y379520D01*
X965839D01*
Y377950D01*
X965664D01*
G37*
G36*
G01Y374050D02*
X964994Y374400D01*
Y375270D01*
X965664Y375620D01*
X965839D01*
Y374050D01*
X965664D01*
G37*
G36*
G01Y370199D02*
X964994Y370549D01*
Y371419D01*
X965664Y371769D01*
X965839D01*
Y370199D01*
X965664D01*
G37*
G36*
G01Y366275D02*
X964994Y366625D01*
Y367495D01*
X965664Y367845D01*
X965839D01*
Y366275D01*
X965664D01*
G37*
G36*
G01Y362350D02*
X964994Y362700D01*
Y363570D01*
X965664Y363920D01*
X965839D01*
Y362350D01*
X965664D01*
G37*
G36*
G01Y389675D02*
X964994Y390025D01*
Y390895D01*
X965664Y391245D01*
X965839D01*
Y389675D01*
X965664D01*
G37*
G36*
G01Y350650D02*
X964994Y351000D01*
Y351870D01*
X965664Y352220D01*
X965839D01*
Y350650D01*
X965664D01*
G37*
G36*
G01Y346750D02*
X964994Y347100D01*
Y347970D01*
X965664Y348320D01*
X965839D01*
Y346750D01*
X965664D01*
G37*
G36*
G01Y342850D02*
X964994Y343200D01*
Y344070D01*
X965664Y344420D01*
X965839D01*
Y342850D01*
X965664D01*
G37*
G36*
G01Y358450D02*
X964994Y358800D01*
Y359670D01*
X965664Y360020D01*
X965839D01*
Y358450D01*
X965664D01*
G37*
G36*
G01Y354550D02*
X964994Y354900D01*
Y355770D01*
X965664Y356120D01*
X965839D01*
Y354550D01*
X965664D01*
G37*
G36*
G01X970681Y393421D02*
X971441Y393071D01*
Y392171D01*
X970681Y391821D01*
X970506D01*
Y393421D01*
X970681D01*
G37*
G36*
G01Y385621D02*
X971441Y385271D01*
Y384371D01*
X970681Y384021D01*
X970506D01*
Y385621D01*
X970681D01*
G37*
G36*
G01X970668Y379520D02*
X971338Y379170D01*
Y378300D01*
X970668Y377950D01*
X970493D01*
Y379520D01*
X970668D01*
G37*
G36*
G01Y375620D02*
X971338Y375270D01*
Y374400D01*
X970668Y374050D01*
X970493D01*
Y375620D01*
X970668D01*
G37*
G36*
G01X970681Y389521D02*
X971441Y389171D01*
Y388271D01*
X970681Y387921D01*
X970506D01*
Y389521D01*
X970681D01*
G37*
G36*
G01X969016Y400621D02*
X969776Y400271D01*
Y399371D01*
X969016Y399021D01*
X968841D01*
Y400621D01*
X969016D01*
G37*
G36*
G01X970668Y371769D02*
X971338Y371419D01*
Y370549D01*
X970668Y370199D01*
X970493D01*
Y371769D01*
X970668D01*
G37*
G36*
G01Y367845D02*
X971338Y367495D01*
Y366625D01*
X970668Y366275D01*
X970493D01*
Y367845D01*
X970668D01*
G37*
G36*
G01Y363920D02*
X971338Y363570D01*
Y362700D01*
X970668Y362350D01*
X970493D01*
Y363920D01*
X970668D01*
G37*
G36*
G01Y352220D02*
X971338Y351870D01*
Y351000D01*
X970668Y350650D01*
X970493D01*
Y352220D01*
X970668D01*
G37*
G36*
G01Y348320D02*
X971338Y347970D01*
Y347100D01*
X970668Y346750D01*
X970493D01*
Y348320D01*
X970668D01*
G37*
G36*
G01Y344420D02*
X971338Y344070D01*
Y343200D01*
X970668Y342850D01*
X970493D01*
Y344420D01*
X970668D01*
G37*
G36*
G01Y360020D02*
X971338Y359670D01*
Y358800D01*
X970668Y358450D01*
X970493D01*
Y360020D01*
X970668D01*
G37*
G36*
G01Y356120D02*
X971338Y355770D01*
Y354900D01*
X970668Y354550D01*
X970493D01*
Y356120D01*
X970668D01*
G37*
G36*
G01X962284Y356549D02*
X961614Y356899D01*
Y357769D01*
X962284Y358119D01*
X962459D01*
Y356549D01*
X962284D01*
G37*
G36*
G01Y344849D02*
X961614Y345199D01*
Y346069D01*
X962284Y346419D01*
X962459D01*
Y344849D01*
X962284D01*
G37*
G36*
G01Y348749D02*
X961614Y349099D01*
Y349969D01*
X962284Y350319D01*
X962459D01*
Y348749D01*
X962284D01*
G37*
G36*
G01Y352649D02*
X961614Y352999D01*
Y353869D01*
X962284Y354219D01*
X962459D01*
Y352649D01*
X962284D01*
G37*
G36*
G01Y360449D02*
X961614Y360799D01*
Y361669D01*
X962284Y362019D01*
X962459D01*
Y360449D01*
X962284D01*
G37*
G36*
G01Y364349D02*
X961614Y364699D01*
Y365569D01*
X962284Y365919D01*
X962459D01*
Y364349D01*
X962284D01*
G37*
G36*
G01Y368200D02*
X961614Y368550D01*
Y369420D01*
X962284Y369770D01*
X962459D01*
Y368200D01*
X962284D01*
G37*
G36*
G01Y372124D02*
X961614Y372474D01*
Y373344D01*
X962284Y373694D01*
X962459D01*
Y372124D01*
X962284D01*
G37*
G36*
G01Y376049D02*
X961614Y376399D01*
Y377269D01*
X962284Y377619D01*
X962459D01*
Y376049D01*
X962284D01*
G37*
G36*
G01Y383849D02*
X961614Y384199D01*
Y385069D01*
X962284Y385419D01*
X962459D01*
Y383849D01*
X962284D01*
G37*
G36*
G01Y379949D02*
X961614Y380299D01*
Y381169D01*
X962284Y381519D01*
X962459D01*
Y379949D01*
X962284D01*
G37*
G36*
G01X961849Y390781D02*
X961089Y391131D01*
Y392031D01*
X961849Y392381D01*
X962024D01*
Y390781D01*
X961849D01*
G37*
G36*
G01X961793Y393945D02*
X961009Y393655D01*
X960372Y394292D01*
X960662Y395076D01*
X960786Y395200D01*
X961917Y394069D01*
X961793Y393945D01*
G37*
G36*
G01X961247Y399081D02*
X962007Y398731D01*
Y397831D01*
X961247Y397481D01*
X961072D01*
Y399081D01*
X961247D01*
G37*
G36*
G01X961439Y395853D02*
X962223Y396143D01*
X962860Y395506D01*
X962570Y394721D01*
X962446Y394598D01*
X961315Y395729D01*
X961439Y395853D01*
G37*
G36*
G01X962947Y391381D02*
X963707Y391031D01*
Y390131D01*
X962947Y389781D01*
X962772D01*
Y391381D01*
X962947D01*
G37*
G36*
G01X963908Y387320D02*
X964578Y386970D01*
Y386100D01*
X963908Y385750D01*
X963733D01*
Y387320D01*
X963908D01*
G37*
G36*
G01Y383420D02*
X964578Y383070D01*
Y382200D01*
X963908Y381850D01*
X963733D01*
Y383420D01*
X963908D01*
G37*
G36*
G01Y379520D02*
X964578Y379170D01*
Y378300D01*
X963908Y377950D01*
X963733D01*
Y379520D01*
X963908D01*
G37*
G36*
G01Y375620D02*
X964578Y375270D01*
Y374400D01*
X963908Y374050D01*
X963733D01*
Y375620D01*
X963908D01*
G37*
G36*
G01Y371769D02*
X964578Y371419D01*
Y370549D01*
X963908Y370199D01*
X963733D01*
Y371769D01*
X963908D01*
G37*
G36*
G01Y367845D02*
X964578Y367495D01*
Y366625D01*
X963908Y366275D01*
X963733D01*
Y367845D01*
X963908D01*
G37*
G36*
G01Y363920D02*
X964578Y363570D01*
Y362700D01*
X963908Y362350D01*
X963733D01*
Y363920D01*
X963908D01*
G37*
G36*
G01Y352220D02*
X964578Y351870D01*
Y351000D01*
X963908Y350650D01*
X963733D01*
Y352220D01*
X963908D01*
G37*
G36*
G01Y348320D02*
X964578Y347970D01*
Y347100D01*
X963908Y346750D01*
X963733D01*
Y348320D01*
X963908D01*
G37*
G36*
G01Y344420D02*
X964578Y344070D01*
Y343200D01*
X963908Y342850D01*
X963733D01*
Y344420D01*
X963908D01*
G37*
G36*
G01Y360020D02*
X964578Y359670D01*
Y358800D01*
X963908Y358450D01*
X963733D01*
Y360020D01*
X963908D01*
G37*
G36*
G01Y356120D02*
X964578Y355770D01*
Y354900D01*
X963908Y354550D01*
X963733D01*
Y356120D01*
X963908D01*
G37*
G36*
G01X958420Y390358D02*
X957635Y390068D01*
X956999Y390704D01*
X957289Y391489D01*
X957412Y391613D01*
X958544Y390481D01*
X958420Y390358D01*
G37*
G36*
G01X954781Y397190D02*
X954021Y397540D01*
Y398440D01*
X954781Y398790D01*
X954956D01*
Y397190D01*
X954781D01*
G37*
G36*
G01X958904Y377950D02*
X958234Y378300D01*
Y379170D01*
X958904Y379520D01*
X959079D01*
Y377950D01*
X958904D01*
G37*
G36*
G01Y381850D02*
X958234Y382200D01*
Y383070D01*
X958904Y383420D01*
X959079D01*
Y381850D01*
X958904D01*
G37*
G36*
G01Y385750D02*
X958234Y386100D01*
Y386970D01*
X958904Y387320D01*
X959079D01*
Y385750D01*
X958904D01*
G37*
G36*
G01Y370199D02*
X958234Y370549D01*
Y371419D01*
X958904Y371769D01*
X959079D01*
Y370199D01*
X958904D01*
G37*
G36*
G01Y374050D02*
X958234Y374400D01*
Y375270D01*
X958904Y375620D01*
X959079D01*
Y374050D01*
X958904D01*
G37*
G36*
G01Y362350D02*
X958234Y362700D01*
Y363570D01*
X958904Y363920D01*
X959079D01*
Y362350D01*
X958904D01*
G37*
G36*
G01Y366275D02*
X958234Y366625D01*
Y367495D01*
X958904Y367845D01*
X959079D01*
Y366275D01*
X958904D01*
G37*
G36*
G01Y346750D02*
X958234Y347100D01*
Y347970D01*
X958904Y348320D01*
X959079D01*
Y346750D01*
X958904D01*
G37*
G36*
G01Y350650D02*
X958234Y351000D01*
Y351870D01*
X958904Y352220D01*
X959079D01*
Y350650D01*
X958904D01*
G37*
G36*
G01Y342850D02*
X958234Y343200D01*
Y344070D01*
X958904Y344420D01*
X959079D01*
Y342850D01*
X958904D01*
G37*
G36*
G01Y354550D02*
X958234Y354900D01*
Y355770D01*
X958904Y356120D01*
X959079D01*
Y354550D01*
X958904D01*
G37*
G36*
G01Y358450D02*
X958234Y358800D01*
Y359670D01*
X958904Y360020D01*
X959079D01*
Y358450D01*
X958904D01*
G37*
G36*
G01X958065Y392265D02*
X958850Y392555D01*
X959486Y391919D01*
X959196Y391134D01*
X959073Y391010D01*
X957941Y392142D01*
X958065Y392265D01*
G37*
G36*
G01X955879Y398790D02*
X956639Y398440D01*
Y397540D01*
X955879Y397190D01*
X955704D01*
Y398790D01*
X955879D01*
G37*
G36*
G01X960528Y385419D02*
X961198Y385069D01*
Y384199D01*
X960528Y383849D01*
X960353D01*
Y385419D01*
X960528D01*
G37*
G36*
G01Y381519D02*
X961198Y381169D01*
Y380299D01*
X960528Y379949D01*
X960353D01*
Y381519D01*
X960528D01*
G37*
G36*
G01Y377619D02*
X961198Y377269D01*
Y376399D01*
X960528Y376049D01*
X960353D01*
Y377619D01*
X960528D01*
G37*
G36*
G01Y373694D02*
X961198Y373344D01*
Y372474D01*
X960528Y372124D01*
X960353D01*
Y373694D01*
X960528D01*
G37*
G36*
G01Y369770D02*
X961198Y369420D01*
Y368550D01*
X960528Y368200D01*
X960353D01*
Y369770D01*
X960528D01*
G37*
G36*
G01Y365919D02*
X961198Y365569D01*
Y364699D01*
X960528Y364349D01*
X960353D01*
Y365919D01*
X960528D01*
G37*
G36*
G01Y362019D02*
X961198Y361669D01*
Y360799D01*
X960528Y360449D01*
X960353D01*
Y362019D01*
X960528D01*
G37*
G36*
G01Y354219D02*
X961198Y353869D01*
Y352999D01*
X960528Y352649D01*
X960353D01*
Y354219D01*
X960528D01*
G37*
G36*
G01Y350319D02*
X961198Y349969D01*
Y349099D01*
X960528Y348749D01*
X960353D01*
Y350319D01*
X960528D01*
G37*
G36*
G01Y346419D02*
X961198Y346069D01*
Y345199D01*
X960528Y344849D01*
X960353D01*
Y346419D01*
X960528D01*
G37*
G36*
G01Y358119D02*
X961198Y357769D01*
Y356899D01*
X960528Y356549D01*
X960353D01*
Y358119D01*
X960528D01*
G37*
G36*
G01X971381Y397501D02*
X970621Y397851D01*
Y398751D01*
X971381Y399101D01*
X971556D01*
Y397501D01*
X971381D01*
G37*
G36*
G01X918648Y404045D02*
X919432Y404335D01*
X920069Y403698D01*
X919779Y402914D01*
X919655Y402790D01*
X918524Y403921D01*
X918648Y404045D01*
G37*
G36*
G01X945617Y403918D02*
X944833Y403628D01*
X944196Y404265D01*
X944486Y405049D01*
X944610Y405173D01*
X945741Y404042D01*
X945617Y403918D01*
G37*
G36*
G01X945263Y405826D02*
X946048Y406116D01*
X946684Y405480D01*
X946394Y404695D01*
X946271Y404571D01*
X945139Y405703D01*
X945263Y405826D01*
G37*
G36*
G01X934424Y404023D02*
X933640Y403733D01*
X933003Y404370D01*
X933293Y405154D01*
X933417Y405278D01*
X934548Y404147D01*
X934424Y404023D01*
G37*
G36*
G01X934070Y405931D02*
X934855Y406221D01*
X935491Y405585D01*
X935201Y404800D01*
X935078Y404676D01*
X933946Y405808D01*
X934070Y405931D01*
G37*
G36*
G01X937449Y403466D02*
X937799Y404226D01*
X938699D01*
X939049Y403466D01*
Y403291D01*
X937449D01*
Y403466D01*
G37*
G36*
G01X926560Y405827D02*
X925775Y405537D01*
X925139Y406173D01*
X925429Y406958D01*
X925552Y407082D01*
X926684Y405950D01*
X926560Y405827D01*
G37*
G36*
G01X926207Y407736D02*
X926991Y408026D01*
X927628Y407389D01*
X927338Y406605D01*
X927214Y406481D01*
X926083Y407612D01*
X926207Y407736D01*
G37*
G36*
G01X930607Y404436D02*
X931391Y404726D01*
X932028Y404089D01*
X931738Y403305D01*
X931614Y403181D01*
X930483Y404312D01*
X930607Y404436D01*
G37*
G36*
G01X968801Y404521D02*
X968041Y404871D01*
Y405771D01*
X968801Y406121D01*
X968976D01*
Y404521D01*
X968801D01*
G37*
G36*
G01X969901Y406121D02*
X970661Y405771D01*
Y404871D01*
X969901Y404521D01*
X969726D01*
Y406121D01*
X969901D01*
G37*
G36*
G01X972351Y216016D02*
X971591Y216366D01*
Y217266D01*
X972351Y217616D01*
X972526D01*
Y216016D01*
X972351D01*
G37*
G36*
G01Y212116D02*
X971591Y212466D01*
Y213366D01*
X972351Y213716D01*
X972526D01*
Y212116D01*
X972351D01*
G37*
G36*
G01X977856Y198794D02*
X977071Y198504D01*
X976435Y199140D01*
X976725Y199925D01*
X976848Y200049D01*
X977980Y198917D01*
X977856Y198794D01*
G37*
G36*
G01X976027Y203123D02*
X975267Y203473D01*
Y204373D01*
X976027Y204723D01*
X976202D01*
Y203123D01*
X976027D01*
G37*
G36*
G01X975086Y207316D02*
X974301Y207026D01*
X973665Y207662D01*
X973955Y208447D01*
X974078Y208571D01*
X975210Y207439D01*
X975086Y207316D01*
G37*
G36*
G01X977502Y200703D02*
X978287Y200993D01*
X978924Y200356D01*
X978634Y199571D01*
X978510Y199448D01*
X977379Y200579D01*
X977502Y200703D01*
G37*
G36*
G01X977127Y204723D02*
X977887Y204373D01*
Y203473D01*
X977127Y203123D01*
X976952D01*
Y204723D01*
X977127D01*
G37*
G36*
G01X973452Y217616D02*
X974212Y217266D01*
Y216366D01*
X973452Y216016D01*
X973277D01*
Y217616D01*
X973452D01*
G37*
G36*
G01Y214116D02*
X974212Y213766D01*
Y212866D01*
X973452Y212516D01*
X973277D01*
Y214116D01*
X973452D01*
G37*
G36*
G01X974732Y209225D02*
X975517Y209515D01*
X976154Y208878D01*
X975864Y208093D01*
X975740Y207970D01*
X974609Y209101D01*
X974732Y209225D01*
G37*
G36*
G01X972892Y205979D02*
X973652Y205629D01*
Y204730D01*
X972892Y204380D01*
X972717Y204379D01*
Y205979D01*
X972892D01*
G37*
G36*
G01X972424Y245350D02*
X971754Y245700D01*
Y246570D01*
X972424Y246920D01*
X972599D01*
Y245350D01*
X972424D01*
G37*
G36*
G01Y249250D02*
X971754Y249600D01*
Y250470D01*
X972424Y250820D01*
X972599D01*
Y249250D01*
X972424D01*
G37*
G36*
G01Y253150D02*
X971754Y253500D01*
Y254370D01*
X972424Y254720D01*
X972599D01*
Y253150D01*
X972424D01*
G37*
G36*
G01Y257050D02*
X971754Y257400D01*
Y258270D01*
X972424Y258620D01*
X972599D01*
Y257050D01*
X972424D01*
G37*
G36*
G01Y260950D02*
X971754Y261300D01*
Y262170D01*
X972424Y262520D01*
X972599D01*
Y260950D01*
X972424D01*
G37*
G36*
G01Y221950D02*
X971754Y222300D01*
Y223170D01*
X972424Y223520D01*
X972599D01*
Y221950D01*
X972424D01*
G37*
G36*
G01Y225875D02*
X971754Y226225D01*
Y227095D01*
X972424Y227445D01*
X972599D01*
Y225875D01*
X972424D01*
G37*
G36*
G01Y229799D02*
X971754Y230149D01*
Y231019D01*
X972424Y231369D01*
X972599D01*
Y229799D01*
X972424D01*
G37*
G36*
G01Y233650D02*
X971754Y234000D01*
Y234870D01*
X972424Y235220D01*
X972599D01*
Y233650D01*
X972424D01*
G37*
G36*
G01Y237550D02*
X971754Y237900D01*
Y238770D01*
X972424Y239120D01*
X972599D01*
Y237550D01*
X972424D01*
G37*
G36*
G01Y241450D02*
X971754Y241800D01*
Y242670D01*
X972424Y243020D01*
X972599D01*
Y241450D01*
X972424D01*
G37*
G36*
G01X974048Y264519D02*
X974718Y264169D01*
Y263299D01*
X974048Y262949D01*
X973873D01*
Y264519D01*
X974048D01*
G37*
G36*
G01Y256719D02*
X974718Y256369D01*
Y255499D01*
X974048Y255149D01*
X973873D01*
Y256719D01*
X974048D01*
G37*
G36*
G01Y252819D02*
X974718Y252469D01*
Y251599D01*
X974048Y251249D01*
X973873D01*
Y252819D01*
X974048D01*
G37*
G36*
G01Y248919D02*
X974718Y248569D01*
Y247699D01*
X974048Y247349D01*
X973873D01*
Y248919D01*
X974048D01*
G37*
G36*
G01Y260619D02*
X974718Y260269D01*
Y259399D01*
X974048Y259049D01*
X973873D01*
Y260619D01*
X974048D01*
G37*
G36*
G01Y233294D02*
X974718Y232944D01*
Y232074D01*
X974048Y231724D01*
X973873D01*
Y233294D01*
X974048D01*
G37*
G36*
G01Y229370D02*
X974718Y229020D01*
Y228150D01*
X974048Y227800D01*
X973873D01*
Y229370D01*
X974048D01*
G37*
G36*
G01Y225519D02*
X974718Y225169D01*
Y224299D01*
X974048Y223949D01*
X973873D01*
Y225519D01*
X974048D01*
G37*
G36*
G01Y245019D02*
X974718Y244669D01*
Y243799D01*
X974048Y243449D01*
X973873D01*
Y245019D01*
X974048D01*
G37*
G36*
G01Y241119D02*
X974718Y240769D01*
Y239899D01*
X974048Y239549D01*
X973873D01*
Y241119D01*
X974048D01*
G37*
G36*
G01Y237219D02*
X974718Y236869D01*
Y235999D01*
X974048Y235649D01*
X973873D01*
Y237219D01*
X974048D01*
G37*
G36*
G01X1017700Y230400D02*
X1017100Y231000D01*
X1016822D01*
X1016770Y231120D01*
G03X1014200I-1285J-561D01*
G01X1014148Y231000D01*
X1010062D01*
X1010010Y231120D01*
G03X1007440I-1285J-561D01*
G01X1007388Y231000D01*
X1003302D01*
X1003250Y231120D01*
G03X1000680I-1285J-561D01*
G01X1000628Y231000D01*
X996543D01*
X996491Y231120D01*
G03X993921I-1285J-561D01*
G01X993869Y231000D01*
X990100D01*
X988500Y232600D01*
Y233049D01*
X988668Y233076D01*
G03Y235844I-222J1384D01*
G01X988500Y235871D01*
Y236949D01*
X988668Y236976D01*
G03Y239744I-222J1384D01*
G01X988500Y239771D01*
Y240849D01*
X988668Y240876D01*
G03Y243644I-222J1384D01*
G01X988500Y243671D01*
Y244749D01*
X988668Y244776D01*
G03X989793Y246547I-222J1384D01*
G01X989761Y246661D01*
X990000Y246900D01*
X991114D01*
X991159Y246876D01*
G03X992493I667J1233D01*
G01X992538Y246900D01*
X993436D01*
G02X993829Y246425I0J-400D01*
G03X996583I1377J-265D01*
G02X996976Y246900I393J75D01*
G01X997874D01*
X997919Y246876D01*
G03X999253I667J1233D01*
G01X999298Y246900D01*
X1000195D01*
G02X1000588Y246425I0J-400D01*
G03X1003342I1377J-265D01*
G02X1003735Y246900I393J75D01*
G01X1004633D01*
X1004678Y246876D01*
G03X1006012I667J1233D01*
G01X1006057Y246900D01*
X1006955D01*
G02X1007348Y246425I0J-400D01*
G03X1010102I1377J-265D01*
G02X1010495Y246900I393J75D01*
G01X1011393D01*
X1011438Y246876D01*
G03X1012772I667J1233D01*
G01X1012817Y246900D01*
X1013715D01*
G02X1014108Y246425I0J-400D01*
G03X1016862I1377J-265D01*
G02X1017255Y246900I393J75D01*
G01X1018153D01*
X1018198Y246876D01*
G03X1020251Y247896I667J1233D01*
G01X1020261Y247961D01*
X1021306Y249006D01*
X1021443Y248910D01*
G03X1023395Y250862I802J1150D01*
G01X1023299Y250999D01*
X1023749Y251449D01*
G02X1024386Y251353I283J-283D01*
G03X1026281Y253248I1239J656D01*
G02X1026185Y253885I187J354D01*
G01X1038600Y266300D01*
X1076468D01*
X1076926Y265842D01*
Y262069D01*
X1073110Y258253D01*
X1070040D01*
X1069300Y257513D01*
Y255337D01*
G02X1068632Y255040I-400J0D01*
G03Y252960I-940J-1040D01*
G02X1069300Y252663I268J-297D01*
G01Y251147D01*
G02X1068883Y250748I-400J0D01*
G03Y247946I-61J-1401D01*
G02X1069300Y247547I17J-399D01*
G01Y247247D01*
G02X1068883Y246848I-400J0D01*
G03Y244046I-61J-1401D01*
G02X1069300Y243647I17J-399D01*
G01Y243347D01*
G02X1068883Y242948I-400J0D01*
G03X1067724Y240675I-61J-1401D01*
G01X1067835Y240535D01*
X1067221Y239921D01*
G02X1066562Y240069I-283J283D01*
G03X1064769Y238276I-1320J-473D01*
G02X1064917Y237617I-135J-376D01*
G01X1057700Y230400D01*
X1050691D01*
X1050686Y230595D01*
G03X1047882I-1402J-36D01*
G01X1047877Y230400D01*
X1043931D01*
X1043926Y230595D01*
G03X1041122I-1402J-36D01*
G01X1041117Y230400D01*
X1037172D01*
X1037167Y230595D01*
G03X1034363I-1402J-36D01*
G01X1034358Y230400D01*
X1030412D01*
X1030407Y230595D01*
G03X1027603I-1402J-36D01*
G01X1027598Y230400D01*
X1023652D01*
X1023647Y230595D01*
G03X1020843I-1402J-36D01*
G01X1020838Y230400D01*
X1017700D01*
G37*
G36*
G01X975804Y337049D02*
X975134Y337399D01*
Y338269D01*
X975804Y338619D01*
X975979D01*
Y337049D01*
X975804D01*
G37*
G36*
G01Y340949D02*
X975134Y341299D01*
Y342169D01*
X975804Y342519D01*
X975979D01*
Y340949D01*
X975804D01*
G37*
G36*
G01X977428Y340520D02*
X978098Y340170D01*
Y339300D01*
X977428Y338950D01*
X977253D01*
Y340520D01*
X977428D01*
G37*
G36*
G01Y336620D02*
X978098Y336270D01*
Y335400D01*
X977428Y335050D01*
X977253D01*
Y336620D01*
X977428D01*
G37*
G36*
G01X972424Y338950D02*
X971754Y339300D01*
Y340170D01*
X972424Y340520D01*
X972599D01*
Y338950D01*
X972424D01*
G37*
G36*
G01X974048Y342519D02*
X974718Y342169D01*
Y341299D01*
X974048Y340949D01*
X973873D01*
Y342519D01*
X974048D01*
G37*
G36*
G01Y338619D02*
X974718Y338269D01*
Y337399D01*
X974048Y337049D01*
X973873D01*
Y338619D01*
X974048D01*
G37*
G36*
G01X973392Y335792D02*
X973709Y335106D01*
X973178Y334417D01*
X972434Y334549D01*
X972294Y334655D01*
X973253Y335899D01*
X973392Y335792D01*
G37*
G36*
G01X978681Y389045D02*
X977921Y389395D01*
Y390295D01*
X978681Y390645D01*
X978856D01*
Y389045D01*
X978681D01*
G37*
G36*
G01Y385145D02*
X977921Y385495D01*
Y386395D01*
X978681Y386745D01*
X978856D01*
Y385145D01*
X978681D01*
G37*
G36*
G01Y392945D02*
X977921Y393295D01*
Y394195D01*
X978681Y394545D01*
X978856D01*
Y392945D01*
X978681D01*
G37*
G36*
G01Y396845D02*
X977921Y397195D01*
Y398095D01*
X978681Y398445D01*
X978856D01*
Y396845D01*
X978681D01*
G37*
G36*
G01Y400745D02*
X977921Y401095D01*
Y401995D01*
X978681Y402345D01*
X978856D01*
Y400745D01*
X978681D01*
G37*
G36*
G01X975804Y372124D02*
X975134Y372474D01*
Y373344D01*
X975804Y373694D01*
X975979D01*
Y372124D01*
X975804D01*
G37*
G36*
G01X977022Y379587D02*
X976539Y380270D01*
X976989Y381049D01*
X977822Y380972D01*
X977974Y380885D01*
X977173Y379499D01*
X977022Y379587D01*
G37*
G36*
G01X975804Y376049D02*
X975134Y376399D01*
Y377269D01*
X975804Y377619D01*
X975979D01*
Y376049D01*
X975804D01*
G37*
G36*
G01Y368200D02*
X975134Y368550D01*
Y369420D01*
X975804Y369770D01*
X975979D01*
Y368200D01*
X975804D01*
G37*
G36*
G01Y364349D02*
X975134Y364699D01*
Y365569D01*
X975804Y365919D01*
X975979D01*
Y364349D01*
X975804D01*
G37*
G36*
G01Y360449D02*
X975134Y360799D01*
Y361669D01*
X975804Y362019D01*
X975979D01*
Y360449D01*
X975804D01*
G37*
G36*
G01Y352649D02*
X975134Y352999D01*
Y353869D01*
X975804Y354219D01*
X975979D01*
Y352649D01*
X975804D01*
G37*
G36*
G01Y348749D02*
X975134Y349099D01*
Y349969D01*
X975804Y350319D01*
X975979D01*
Y348749D01*
X975804D01*
G37*
G36*
G01Y344849D02*
X975134Y345199D01*
Y346069D01*
X975804Y346419D01*
X975979D01*
Y344849D01*
X975804D01*
G37*
G36*
G01Y356549D02*
X975134Y356899D01*
Y357769D01*
X975804Y358119D01*
X975979D01*
Y356549D01*
X975804D01*
G37*
G36*
G01X979779Y390645D02*
X980539Y390295D01*
Y389395D01*
X979779Y389045D01*
X979604D01*
Y390645D01*
X979779D01*
G37*
G36*
G01Y386745D02*
X980539Y386395D01*
Y385495D01*
X979779Y385145D01*
X979604D01*
Y386745D01*
X979779D01*
G37*
G36*
G01Y394545D02*
X980539Y394195D01*
Y393295D01*
X979779Y392945D01*
X979604D01*
Y394545D01*
X979779D01*
G37*
G36*
G01Y398445D02*
X980539Y398095D01*
Y397195D01*
X979779Y396845D01*
X979604D01*
Y398445D01*
X979779D01*
G37*
G36*
G01Y402345D02*
X980539Y401995D01*
Y401095D01*
X979779Y400745D01*
X979604D01*
Y402345D01*
X979779D01*
G37*
G36*
G01X978774Y380422D02*
X979257Y379739D01*
X978806Y378960D01*
X977973Y379037D01*
X977822Y379125D01*
X978622Y380510D01*
X978774Y380422D01*
G37*
G36*
G01X977428Y375620D02*
X978098Y375270D01*
Y374400D01*
X977428Y374050D01*
X977253D01*
Y375620D01*
X977428D01*
G37*
G36*
G01Y371769D02*
X978098Y371419D01*
Y370549D01*
X977428Y370199D01*
X977253D01*
Y371769D01*
X977428D01*
G37*
G36*
G01Y367845D02*
X978098Y367495D01*
Y366625D01*
X977428Y366275D01*
X977253D01*
Y367845D01*
X977428D01*
G37*
G36*
G01Y363920D02*
X978098Y363570D01*
Y362700D01*
X977428Y362350D01*
X977253D01*
Y363920D01*
X977428D01*
G37*
G36*
G01Y352220D02*
X978098Y351870D01*
Y351000D01*
X977428Y350650D01*
X977253D01*
Y352220D01*
X977428D01*
G37*
G36*
G01Y348320D02*
X978098Y347970D01*
Y347100D01*
X977428Y346750D01*
X977253D01*
Y348320D01*
X977428D01*
G37*
G36*
G01Y344420D02*
X978098Y344070D01*
Y343200D01*
X977428Y342850D01*
X977253D01*
Y344420D01*
X977428D01*
G37*
G36*
G01Y360020D02*
X978098Y359670D01*
Y358800D01*
X977428Y358450D01*
X977253D01*
Y360020D01*
X977428D01*
G37*
G36*
G01Y356120D02*
X978098Y355770D01*
Y354900D01*
X977428Y354550D01*
X977253D01*
Y356120D01*
X977428D01*
G37*
G36*
G01X972381Y393201D02*
X971621Y393551D01*
Y394451D01*
X972381Y394801D01*
X972556D01*
Y393201D01*
X972381D01*
G37*
G36*
G01X972424Y377950D02*
X971754Y378300D01*
Y379170D01*
X972424Y379520D01*
X972599D01*
Y377950D01*
X972424D01*
G37*
G36*
G01X973126Y381913D02*
X972366Y382263D01*
Y383163D01*
X973126Y383513D01*
X973301D01*
Y381913D01*
X973126D01*
G37*
G36*
G01X972424Y374050D02*
X971754Y374400D01*
Y375270D01*
X972424Y375620D01*
X972599D01*
Y374050D01*
X972424D01*
G37*
G36*
G01Y370199D02*
X971754Y370549D01*
Y371419D01*
X972424Y371769D01*
X972599D01*
Y370199D01*
X972424D01*
G37*
G36*
G01Y366275D02*
X971754Y366625D01*
Y367495D01*
X972424Y367845D01*
X972599D01*
Y366275D01*
X972424D01*
G37*
G36*
G01Y362350D02*
X971754Y362700D01*
Y363570D01*
X972424Y363920D01*
X972599D01*
Y362350D01*
X972424D01*
G37*
G36*
G01X972381Y389301D02*
X971621Y389651D01*
Y390551D01*
X972381Y390901D01*
X972556D01*
Y389301D01*
X972381D01*
G37*
G36*
G01X972424Y350650D02*
X971754Y351000D01*
Y351870D01*
X972424Y352220D01*
X972599D01*
Y350650D01*
X972424D01*
G37*
G36*
G01Y346750D02*
X971754Y347100D01*
Y347970D01*
X972424Y348320D01*
X972599D01*
Y346750D01*
X972424D01*
G37*
G36*
G01Y342850D02*
X971754Y343200D01*
Y344070D01*
X972424Y344420D01*
X972599D01*
Y342850D01*
X972424D01*
G37*
G36*
G01Y358450D02*
X971754Y358800D01*
Y359670D01*
X972424Y360020D01*
X972599D01*
Y358450D01*
X972424D01*
G37*
G36*
G01Y354550D02*
X971754Y354900D01*
Y355770D01*
X972424Y356120D01*
X972599D01*
Y354550D01*
X972424D01*
G37*
G36*
G01X972479Y399101D02*
X973239Y398751D01*
Y397851D01*
X972479Y397501D01*
X972304D01*
Y399101D01*
X972479D01*
G37*
G36*
G01X973479Y394801D02*
X974239Y394451D01*
Y393551D01*
X973479Y393201D01*
X973304D01*
Y394801D01*
X973479D01*
G37*
G36*
G01X974224Y383513D02*
X974984Y383163D01*
Y382263D01*
X974224Y381913D01*
X974049D01*
Y383513D01*
X974224D01*
G37*
G36*
G01X974048Y377619D02*
X974718Y377269D01*
Y376399D01*
X974048Y376049D01*
X973873D01*
Y377619D01*
X974048D01*
G37*
G36*
G01Y373694D02*
X974718Y373344D01*
Y372474D01*
X974048Y372124D01*
X973873D01*
Y373694D01*
X974048D01*
G37*
G36*
G01Y369770D02*
X974718Y369420D01*
Y368550D01*
X974048Y368200D01*
X973873D01*
Y369770D01*
X974048D01*
G37*
G36*
G01Y365919D02*
X974718Y365569D01*
Y364699D01*
X974048Y364349D01*
X973873D01*
Y365919D01*
X974048D01*
G37*
G36*
G01Y362019D02*
X974718Y361669D01*
Y360799D01*
X974048Y360449D01*
X973873D01*
Y362019D01*
X974048D01*
G37*
G36*
G01X973479Y390901D02*
X974239Y390551D01*
Y389651D01*
X973479Y389301D01*
X973304D01*
Y390901D01*
X973479D01*
G37*
G36*
G01X974048Y354219D02*
X974718Y353869D01*
Y352999D01*
X974048Y352649D01*
X973873D01*
Y354219D01*
X974048D01*
G37*
G36*
G01Y350319D02*
X974718Y349969D01*
Y349099D01*
X974048Y348749D01*
X973873D01*
Y350319D01*
X974048D01*
G37*
G36*
G01Y346419D02*
X974718Y346069D01*
Y345199D01*
X974048Y344849D01*
X973873D01*
Y346419D01*
X974048D01*
G37*
G36*
G01Y358119D02*
X974718Y357769D01*
Y356899D01*
X974048Y356549D01*
X973873D01*
Y358119D01*
X974048D01*
G37*
G36*
G01X1064525Y213658D02*
X1063858Y213303D01*
X1063141Y213795D01*
X1063231Y214545D01*
X1063329Y214690D01*
X1064624Y213801D01*
X1064525Y213658D01*
G37*
G36*
G01X1066642Y201877D02*
X1065882Y202227D01*
Y203127D01*
X1066642Y203477D01*
X1066817D01*
Y201877D01*
X1066642D01*
G37*
G36*
G01X1070749Y189202D02*
X1069989Y189552D01*
Y190452D01*
X1070749Y190802D01*
X1070924D01*
Y189202D01*
X1070749D01*
G37*
G36*
G01X1068970Y198098D02*
X1068186Y197808D01*
X1067549Y198445D01*
X1067839Y199229D01*
X1067963Y199353D01*
X1069094Y198222D01*
X1068970Y198098D01*
G37*
G36*
G01X1069630Y194453D02*
X1068870Y194803D01*
Y195703D01*
X1069630Y196053D01*
X1069805D01*
Y194453D01*
X1069630D01*
G37*
G36*
G01X1066205Y209537D02*
X1065535Y209887D01*
Y210757D01*
X1066205Y211107D01*
X1066380D01*
Y209537D01*
X1066205D01*
G37*
G36*
G01X1066642Y205777D02*
X1065882Y206127D01*
Y207027D01*
X1066642Y207377D01*
X1066817D01*
Y205777D01*
X1066642D01*
G37*
G36*
G01X1070749Y185302D02*
X1069989Y185652D01*
Y186552D01*
X1070749Y186902D01*
X1070924D01*
Y185302D01*
X1070749D01*
G37*
G36*
G01X1068110Y200515D02*
X1068895Y200805D01*
X1069532Y200169D01*
X1069242Y199384D01*
X1069118Y199260D01*
X1067987Y200391D01*
X1068110Y200515D01*
G37*
G36*
G01X1071847Y190802D02*
X1072607Y190452D01*
Y189552D01*
X1071847Y189202D01*
X1071672D01*
Y190802D01*
X1071847D01*
G37*
G36*
G01X1070729Y196053D02*
X1071489Y195703D01*
Y194803D01*
X1070729Y194453D01*
X1070554D01*
Y196053D01*
X1070729D01*
G37*
G36*
G01X1067740Y203477D02*
X1068500Y203127D01*
Y202227D01*
X1067740Y201877D01*
X1067565D01*
Y203477D01*
X1067740D01*
G37*
G36*
G01X1067809Y213023D02*
X1068479Y212673D01*
Y211803D01*
X1067808Y211453D01*
X1067633D01*
X1067634Y213023D01*
X1067809D01*
G37*
G36*
G01X1067740Y207377D02*
X1068500Y207027D01*
Y206127D01*
X1067740Y205777D01*
X1067565D01*
Y207377D01*
X1067740D01*
G37*
G36*
G01X1071847Y186902D02*
X1072607Y186552D01*
Y185652D01*
X1071847Y185302D01*
X1071672D01*
Y186902D01*
X1071847D01*
G37*
G36*
G01X1081761Y201347D02*
X1081001Y201697D01*
Y202597D01*
X1081761Y202947D01*
X1081936D01*
Y201347D01*
X1081761D01*
G37*
G36*
G01Y196547D02*
X1081001Y196897D01*
Y197797D01*
X1081761Y198147D01*
X1081936D01*
Y196547D01*
X1081761D01*
G37*
G36*
G01X1080362Y208704D02*
X1079602Y209054D01*
Y209954D01*
X1080362Y210304D01*
X1080537D01*
Y208704D01*
X1080362D01*
G37*
G36*
G01X1079839Y217326D02*
X1079169Y217676D01*
Y218546D01*
X1079839Y218896D01*
X1080014D01*
Y217326D01*
X1079839D01*
G37*
G36*
G01Y213419D02*
X1079169Y213769D01*
Y214639D01*
X1079839Y214989D01*
X1080014D01*
Y213419D01*
X1079839D01*
G37*
G36*
G01X1087558Y185656D02*
X1086773Y185366D01*
X1086137Y186002D01*
X1086427Y186787D01*
X1086550Y186911D01*
X1087682Y185779D01*
X1087558Y185656D01*
G37*
G36*
G01X1084800Y188413D02*
X1084015Y188123D01*
X1083379Y188760D01*
X1083669Y189545D01*
X1083793Y189668D01*
X1084924Y188537D01*
X1084800Y188413D01*
G37*
G36*
G01X1090316Y182898D02*
X1089531Y182608D01*
X1088894Y183244D01*
X1089184Y184029D01*
X1089308Y184153D01*
X1090439Y183022D01*
X1090316Y182898D01*
G37*
G36*
G01X1082861Y202947D02*
X1083621Y202597D01*
Y201697D01*
X1082861Y201347D01*
X1082686D01*
Y202947D01*
X1082861D01*
G37*
G36*
G01X1084445Y190321D02*
X1085230Y190611D01*
X1085867Y189975D01*
X1085577Y189190D01*
X1085453Y189066D01*
X1084322Y190197D01*
X1084445Y190321D01*
G37*
G36*
G01X1082861Y198147D02*
X1083621Y197797D01*
Y196897D01*
X1082861Y196547D01*
X1082686D01*
Y198147D01*
X1082861D01*
G37*
G36*
G01X1081460Y210304D02*
X1082220Y209954D01*
Y209054D01*
X1081460Y208704D01*
X1081285D01*
Y210304D01*
X1081460D01*
G37*
G36*
G01X1081464Y217017D02*
X1082134Y216667D01*
Y215797D01*
X1081464Y215447D01*
X1081289D01*
Y217017D01*
X1081464D01*
G37*
G36*
G01X1089961Y184806D02*
X1090746Y185096D01*
X1091382Y184459D01*
X1091092Y183674D01*
X1090968Y183551D01*
X1089837Y184682D01*
X1089961Y184806D01*
G37*
G36*
G01X1087203Y187563D02*
X1087988Y187853D01*
X1088624Y187217D01*
X1088334Y186432D01*
X1088211Y186308D01*
X1087079Y187440D01*
X1087203Y187563D01*
G37*
G36*
G01X1063624Y200048D02*
X1062864Y200398D01*
Y201298D01*
X1063624Y201648D01*
X1063799D01*
Y200048D01*
X1063624D01*
G37*
G36*
G01X1060631Y207850D02*
X1059871Y208200D01*
Y209100D01*
X1060631Y209450D01*
X1060806D01*
Y207850D01*
X1060631D01*
G37*
G36*
G01Y211750D02*
X1059871Y212100D01*
Y213000D01*
X1060631Y213350D01*
X1060806D01*
Y211750D01*
X1060631D01*
G37*
G36*
G01Y217250D02*
X1059871Y217600D01*
Y218500D01*
X1060631Y218850D01*
X1060806D01*
Y217250D01*
X1060631D01*
G37*
G36*
G01X1066611Y193322D02*
X1065851Y193672D01*
Y194572D01*
X1066611Y194922D01*
X1066786D01*
Y193322D01*
X1066611D01*
G37*
G36*
G01X1067731Y183722D02*
X1066971Y184072D01*
Y184972D01*
X1067731Y185322D01*
X1067906D01*
Y183722D01*
X1067731D01*
G37*
G36*
G01Y187622D02*
X1066971Y187972D01*
Y188872D01*
X1067731Y189222D01*
X1067906D01*
Y187622D01*
X1067731D01*
G37*
G36*
G01X1061731Y218850D02*
X1062491Y218500D01*
Y217600D01*
X1061731Y217250D01*
X1061556D01*
Y218850D01*
X1061731D01*
G37*
G36*
G01Y209450D02*
X1062491Y209100D01*
Y208200D01*
X1061731Y207850D01*
X1061556D01*
Y209450D01*
X1061731D01*
G37*
G36*
G01Y213350D02*
X1062491Y213000D01*
Y212100D01*
X1061731Y211750D01*
X1061556D01*
Y213350D01*
X1061731D01*
G37*
G36*
G01X1064722Y201648D02*
X1065482Y201298D01*
Y200398D01*
X1064722Y200048D01*
X1064547D01*
Y201648D01*
X1064722D01*
G37*
G36*
G01X1067710Y194922D02*
X1068470Y194572D01*
Y193672D01*
X1067710Y193322D01*
X1067535D01*
Y194922D01*
X1067710D01*
G37*
G36*
G01X1068829Y185322D02*
X1069589Y184972D01*
Y184072D01*
X1068829Y183722D01*
X1068654D01*
Y185322D01*
X1068829D01*
G37*
G36*
G01Y189222D02*
X1069589Y188872D01*
Y187972D01*
X1068829Y187622D01*
X1068654D01*
Y189222D01*
X1068829D01*
G37*
G36*
G01X1078741Y200647D02*
X1077981Y200997D01*
Y201897D01*
X1078741Y202247D01*
X1078916D01*
Y200647D01*
X1078741D01*
G37*
G36*
G01Y196747D02*
X1077981Y197097D01*
Y197997D01*
X1078741Y198347D01*
X1078916D01*
Y196747D01*
X1078741D01*
G37*
G36*
G01X1076460Y211509D02*
X1075790Y211859D01*
Y212729D01*
X1076460Y213079D01*
X1076635D01*
Y211509D01*
X1076460D01*
G37*
G36*
G01Y215411D02*
X1075790Y215761D01*
Y216631D01*
X1076460Y216981D01*
X1076635D01*
Y215411D01*
X1076460D01*
G37*
G36*
G01X1077352Y207154D02*
X1076592Y207504D01*
Y208404D01*
X1077352Y208754D01*
X1077527D01*
Y207154D01*
X1077352D01*
G37*
G36*
G01X1082189Y186757D02*
X1081404Y186467D01*
X1080768Y187103D01*
X1081058Y187888D01*
X1081181Y188012D01*
X1082313Y186880D01*
X1082189Y186757D01*
G37*
G36*
G01X1084947Y183999D02*
X1084162Y183709D01*
X1083526Y184345D01*
X1083816Y185130D01*
X1083939Y185254D01*
X1085071Y184122D01*
X1084947Y183999D01*
G37*
G36*
G01X1079841Y202247D02*
X1080601Y201897D01*
Y200997D01*
X1079841Y200647D01*
X1079666D01*
Y202247D01*
X1079841D01*
G37*
G36*
G01Y198347D02*
X1080601Y197997D01*
Y197097D01*
X1079841Y196747D01*
X1079666D01*
Y198347D01*
X1079841D01*
G37*
G36*
G01X1078084Y218930D02*
X1078754Y218580D01*
Y217710D01*
X1078084Y217360D01*
X1077909D01*
Y218930D01*
X1078084D01*
G37*
G36*
G01Y215030D02*
X1078754Y214680D01*
Y213810D01*
X1078084Y213460D01*
X1077909D01*
Y215030D01*
X1078084D01*
G37*
G36*
G01X1078452Y208754D02*
X1079212Y208404D01*
Y207504D01*
X1078452Y207154D01*
X1078277D01*
Y208754D01*
X1078452D01*
G37*
G36*
G01X1081834Y188664D02*
X1082619Y188954D01*
X1083255Y188318D01*
X1082965Y187533D01*
X1082842Y187409D01*
X1081710Y188541D01*
X1081834Y188664D01*
G37*
G36*
G01X1084592Y185906D02*
X1085377Y186196D01*
X1086013Y185560D01*
X1085723Y184775D01*
X1085600Y184651D01*
X1084468Y185783D01*
X1084592Y185906D01*
G37*
G36*
G01X1071628Y203634D02*
X1072413Y203924D01*
X1073049Y203288D01*
X1072759Y202503D01*
X1072636Y202379D01*
X1071504Y203511D01*
X1071628Y203634D01*
G37*
G36*
G01X1073801Y200837D02*
X1074561Y200487D01*
Y199587D01*
X1073801Y199237D01*
X1073626D01*
Y200837D01*
X1073801D01*
G37*
G36*
G01X1074917Y190548D02*
X1075677Y190198D01*
Y189298D01*
X1074917Y188948D01*
X1074742D01*
Y190548D01*
X1074917D01*
G37*
G36*
G01X1073801Y196937D02*
X1074561Y196587D01*
Y195687D01*
X1073801Y195337D01*
X1073626D01*
Y196937D01*
X1073801D01*
G37*
G36*
G01X1069429Y216785D02*
X1070067Y217190D01*
X1070820Y216755D01*
X1070788Y216000D01*
X1070701Y215849D01*
X1069341Y216633D01*
X1069429Y216785D01*
G37*
G36*
G01X1071322Y212798D02*
X1072082Y212448D01*
Y211548D01*
X1071322Y211198D01*
X1071147D01*
Y212798D01*
X1071322D01*
G37*
G36*
G01X1070839Y207295D02*
X1071599Y206945D01*
Y206045D01*
X1070839Y205695D01*
X1070664D01*
Y207295D01*
X1070839D01*
G37*
G36*
G01X1076045Y185867D02*
X1076830Y186157D01*
X1077466Y185521D01*
X1077176Y184736D01*
X1077053Y184612D01*
X1075921Y185744D01*
X1076045Y185867D01*
G37*
G36*
G01X1078409Y182452D02*
X1079169Y182102D01*
Y181202D01*
X1078409Y180852D01*
X1078234D01*
Y182452D01*
X1078409D01*
G37*
G36*
G01X1075721Y199368D02*
X1074961Y199718D01*
Y200618D01*
X1075721Y200968D01*
X1075896D01*
Y199368D01*
X1075721D01*
G37*
G36*
G01X1075001Y202976D02*
X1074217Y202686D01*
X1073580Y203323D01*
X1073870Y204107D01*
X1073994Y204231D01*
X1075125Y203100D01*
X1075001Y202976D01*
G37*
G36*
G01X1075721Y195468D02*
X1074961Y195818D01*
Y196718D01*
X1075721Y197068D01*
X1075896D01*
Y195468D01*
X1075721D01*
G37*
G36*
G01X1071593Y217560D02*
X1070956Y217155D01*
X1070202Y217589D01*
X1070234Y218344D01*
X1070322Y218497D01*
X1071681Y217711D01*
X1071593Y217560D01*
G37*
G36*
G01X1073602Y209603D02*
X1072842Y209953D01*
Y210853D01*
X1073602Y211203D01*
X1073777D01*
Y209603D01*
X1073602D01*
G37*
G36*
G01Y213503D02*
X1072842Y213853D01*
Y214753D01*
X1073602Y215103D01*
X1073777D01*
Y213503D01*
X1073602D01*
G37*
G36*
G01X1078377Y186297D02*
X1077593Y186007D01*
X1076956Y186644D01*
X1077246Y187428D01*
X1077370Y187552D01*
X1078501Y186421D01*
X1078377Y186297D01*
G37*
G36*
G01X1081135Y183539D02*
X1080351Y183249D01*
X1079714Y183886D01*
X1080004Y184670D01*
X1080128Y184794D01*
X1081259Y183663D01*
X1081135Y183539D01*
G37*
G36*
G01X1071581Y202125D02*
X1070797Y201835D01*
X1070160Y202472D01*
X1070450Y203256D01*
X1070574Y203380D01*
X1071705Y202249D01*
X1071581Y202125D01*
G37*
G36*
G01X1073817Y188948D02*
X1073057Y189298D01*
Y190198D01*
X1073817Y190548D01*
X1073992D01*
Y188948D01*
X1073817D01*
G37*
G36*
G01X1072701Y193237D02*
X1071941Y193587D01*
Y194487D01*
X1072701Y194837D01*
X1072876D01*
Y193237D01*
X1072701D01*
G37*
G36*
G01Y197137D02*
X1071941Y197487D01*
Y198387D01*
X1072701Y198737D01*
X1072876D01*
Y197137D01*
X1072701D01*
G37*
G36*
G01X1068225Y215585D02*
X1067575Y215199D01*
X1066834Y215655D01*
X1066887Y216409D01*
X1066979Y216558D01*
X1068316Y215734D01*
X1068225Y215585D01*
G37*
G36*
G01X1070222Y211198D02*
X1069462Y211548D01*
Y212448D01*
X1070222Y212798D01*
X1070397D01*
Y211198D01*
X1070222D01*
G37*
G36*
G01X1069739Y205695D02*
X1068979Y206045D01*
Y206945D01*
X1069739Y207295D01*
X1069914D01*
Y205695D01*
X1069739D01*
G37*
G36*
G01X1076398Y183958D02*
X1075614Y183668D01*
X1074977Y184305D01*
X1075267Y185089D01*
X1075391Y185213D01*
X1076522Y184082D01*
X1076398Y183958D01*
G37*
G36*
G01X1077309Y180852D02*
X1076549Y181202D01*
Y182102D01*
X1077309Y182452D01*
X1077484D01*
Y180852D01*
X1077309D01*
G37*
G36*
G01X1076821Y200968D02*
X1077581Y200618D01*
Y199718D01*
X1076821Y199368D01*
X1076646D01*
Y200968D01*
X1076821D01*
G37*
G36*
G01X1074948Y204585D02*
X1075733Y204875D01*
X1076369Y204239D01*
X1076079Y203454D01*
X1075956Y203330D01*
X1074824Y204462D01*
X1074948Y204585D01*
G37*
G36*
G01X1076821Y197068D02*
X1077581Y196718D01*
Y195818D01*
X1076821Y195468D01*
X1076646D01*
Y197068D01*
X1076821D01*
G37*
G36*
G01X1074702Y215503D02*
X1075462Y215153D01*
Y214253D01*
X1074702Y213903D01*
X1074527D01*
Y215503D01*
X1074702D01*
G37*
G36*
G01Y211603D02*
X1075462Y211253D01*
Y210353D01*
X1074702Y210003D01*
X1074527D01*
Y211603D01*
X1074702D01*
G37*
G36*
G01X1080782Y185448D02*
X1081567Y185738D01*
X1082203Y185102D01*
X1081913Y184317D01*
X1081790Y184193D01*
X1080658Y185325D01*
X1080782Y185448D01*
G37*
G36*
G01X1078024Y188206D02*
X1078809Y188496D01*
X1079445Y187860D01*
X1079155Y187075D01*
X1079032Y186951D01*
X1077900Y188083D01*
X1078024Y188206D01*
G37*
G36*
G01X1093126Y207323D02*
X1092366Y207673D01*
Y208573D01*
X1093126Y208923D01*
X1093301D01*
Y207323D01*
X1093126D01*
G37*
G36*
G01X1093359Y217337D02*
X1092689Y217687D01*
Y218557D01*
X1093359Y218907D01*
X1093534D01*
Y217337D01*
X1093359D01*
G37*
G36*
G01Y213437D02*
X1092689Y213787D01*
Y214657D01*
X1093359Y215007D01*
X1093534D01*
Y213437D01*
X1093359D01*
G37*
G36*
G01X1094983Y217006D02*
X1095653Y216656D01*
Y215786D01*
X1094983Y215436D01*
X1094808D01*
Y217006D01*
X1094983D01*
G37*
G36*
G01Y213106D02*
X1095653Y212756D01*
Y211886D01*
X1094983Y211536D01*
X1094808D01*
Y213106D01*
X1094983D01*
G37*
G36*
G01X1094226Y208923D02*
X1094986Y208573D01*
Y207673D01*
X1094226Y207323D01*
X1094051D01*
Y208923D01*
X1094226D01*
G37*
G36*
G01X1092324Y201968D02*
X1091539Y201678D01*
X1090903Y202315D01*
X1091193Y203100D01*
X1091317Y203223D01*
X1092448Y202092D01*
X1092324Y201968D01*
G37*
G36*
G01X1089979Y215436D02*
X1089309Y215786D01*
Y216656D01*
X1089979Y217006D01*
X1090154D01*
Y215436D01*
X1089979D01*
G37*
G36*
G01Y211536D02*
X1089309Y211886D01*
Y212756D01*
X1089979Y213106D01*
X1090154D01*
Y211536D01*
X1089979D01*
G37*
G36*
G01X1095082Y199211D02*
X1094297Y198921D01*
X1093661Y199557D01*
X1093951Y200342D01*
X1094074Y200466D01*
X1095206Y199334D01*
X1095082Y199211D01*
G37*
G36*
G01X1091971Y203878D02*
X1092756Y204168D01*
X1093392Y203531D01*
X1093102Y202746D01*
X1092978Y202623D01*
X1091847Y203754D01*
X1091971Y203878D01*
G37*
G36*
G01X1091603Y218907D02*
X1092273Y218557D01*
Y217687D01*
X1091603Y217337D01*
X1091428D01*
Y218907D01*
X1091603D01*
G37*
G36*
G01Y215007D02*
X1092273Y214657D01*
Y213787D01*
X1091603Y213437D01*
X1091428D01*
Y215007D01*
X1091603D01*
G37*
G36*
G01Y211107D02*
X1092273Y210757D01*
Y209887D01*
X1091603Y209537D01*
X1091428D01*
Y211107D01*
X1091603D01*
G37*
G36*
G01X1094729Y201120D02*
X1095513Y201410D01*
X1096150Y200773D01*
X1095860Y199989D01*
X1095736Y199865D01*
X1094605Y200996D01*
X1094729Y201120D01*
G37*
G36*
G01X1078360Y221456D02*
X1077722Y221051D01*
X1076969Y221486D01*
X1077001Y222241D01*
X1077088Y222393D01*
X1078448Y221607D01*
X1078360Y221456D01*
G37*
G36*
G01X1081464Y220917D02*
X1082134Y220567D01*
Y219697D01*
X1081464Y219347D01*
X1081289D01*
Y220917D01*
X1081464D01*
G37*
G36*
G01X1079545Y222648D02*
X1080183Y223054D01*
X1080936Y222619D01*
X1080904Y221864D01*
X1080817Y221712D01*
X1079458Y222498D01*
X1079545Y222648D01*
G37*
G36*
G01X1062299Y225201D02*
X1062009Y225986D01*
X1062646Y226622D01*
X1063431Y226332D01*
X1063554Y226208D01*
X1062423Y225077D01*
X1062299Y225201D01*
G37*
G36*
G01X1060631Y221150D02*
X1059871Y221500D01*
Y222400D01*
X1060631Y222750D01*
X1060806D01*
Y221150D01*
X1060631D01*
G37*
G36*
G01X1061731Y222750D02*
X1062491Y222400D01*
Y221500D01*
X1061731Y221150D01*
X1061556D01*
Y222750D01*
X1061731D01*
G37*
G36*
G01X1063504Y224844D02*
X1063794Y224059D01*
X1063158Y223423D01*
X1062373Y223713D01*
X1062249Y223836D01*
X1063381Y224968D01*
X1063504Y224844D01*
G37*
G36*
G01X1074974Y219510D02*
X1074336Y219105D01*
X1073583Y219540D01*
X1073615Y220295D01*
X1073702Y220447D01*
X1075062Y219661D01*
X1074974Y219510D01*
G37*
G36*
G01X1076183Y220688D02*
X1076821Y221093D01*
X1077574Y220659D01*
X1077542Y219904D01*
X1077455Y219751D01*
X1076096Y220537D01*
X1076183Y220688D01*
G37*
G36*
G01X1073695Y221770D02*
X1073139Y222281D01*
X1073364Y223121D01*
X1074101Y223286D01*
X1074270Y223241D01*
X1073864Y221724D01*
X1073695Y221770D01*
G37*
G36*
G01X1072753Y218716D02*
X1073390Y219121D01*
X1074144Y218686D01*
X1074112Y217931D01*
X1074024Y217779D01*
X1072665Y218564D01*
X1072753Y218716D01*
G37*
G36*
G01X1071324Y226732D02*
X1071994Y226382D01*
Y225512D01*
X1071324Y225162D01*
X1071149D01*
Y226732D01*
X1071324D01*
G37*
G36*
G01X1093359Y221237D02*
X1092689Y221587D01*
Y222457D01*
X1093359Y222807D01*
X1093534D01*
Y221237D01*
X1093359D01*
G37*
G36*
G01Y225137D02*
X1092689Y225487D01*
Y226357D01*
X1093359Y226707D01*
X1093534D01*
Y225137D01*
X1093359D01*
G37*
G36*
G01Y229062D02*
X1092689Y229412D01*
Y230282D01*
X1093359Y230632D01*
X1093534D01*
Y229062D01*
X1093359D01*
G37*
G36*
G01X1094983Y228706D02*
X1095653Y228356D01*
Y227486D01*
X1094983Y227136D01*
X1094808D01*
Y228706D01*
X1094983D01*
G37*
G36*
G01Y220906D02*
X1095653Y220556D01*
Y219686D01*
X1094983Y219336D01*
X1094808D01*
Y220906D01*
X1094983D01*
G37*
G36*
G01Y224806D02*
X1095653Y224456D01*
Y223586D01*
X1094983Y223236D01*
X1094808D01*
Y224806D01*
X1094983D01*
G37*
G36*
G01X1089979Y219336D02*
X1089309Y219686D01*
Y220556D01*
X1089979Y220906D01*
X1090154D01*
Y219336D01*
X1089979D01*
G37*
G36*
G01Y223236D02*
X1089309Y223586D01*
Y224456D01*
X1089979Y224806D01*
X1090154D01*
Y223236D01*
X1089979D01*
G37*
G36*
G01Y227136D02*
X1089309Y227486D01*
Y228356D01*
X1089979Y228706D01*
X1090154D01*
Y227136D01*
X1089979D01*
G37*
G36*
G01Y230987D02*
X1089309Y231337D01*
Y232207D01*
X1089979Y232557D01*
X1090154D01*
Y230987D01*
X1089979D01*
G37*
G36*
G01X1091603Y222807D02*
X1092273Y222457D01*
Y221587D01*
X1091603Y221237D01*
X1091428D01*
Y222807D01*
X1091603D01*
G37*
G36*
G01Y226707D02*
X1092273Y226357D01*
Y225487D01*
X1091603Y225137D01*
X1091428D01*
Y226707D01*
X1091603D01*
G37*
G36*
G01Y230632D02*
X1092273Y230282D01*
Y229412D01*
X1091603Y229062D01*
X1091428D01*
Y230632D01*
X1091603D01*
G37*
G36*
G01X1159232Y220130D02*
X1159207Y220301D01*
G03X1156561Y220712I-1387J-205D01*
G02X1155919Y220605I-359J176D01*
G01X1155457Y221067D01*
X1155561Y221205D01*
G03X1153135Y222558I-1120J842D01*
G02X1152479Y222421I-373J146D01*
G01X1151980Y222921D01*
X1152106Y223062D01*
G03X1150057Y224975I-1046J933D01*
G02X1149488Y224972I-286J280D01*
G01X1149000Y225460D01*
X1149031Y225572D01*
G03X1147305Y227298I-1351J375D01*
G01X1147193Y227267D01*
X1146978Y227483D01*
Y228071D01*
G02X1147445Y228465I400J0D01*
G03Y231229I235J1382D01*
G02X1146978Y231623I-67J394D01*
G01Y231970D01*
G02X1147445Y232364I400J0D01*
G03Y235128I235J1382D01*
G02X1146978Y235522I-67J394D01*
G01Y235871D01*
G02X1147445Y236265I400J0D01*
G03Y239029I235J1382D01*
G02X1146978Y239423I-67J394D01*
G01Y239771D01*
G02X1147445Y240165I400J0D01*
G03Y242929I235J1382D01*
G02X1146978Y243323I-67J394D01*
G01Y246468D01*
X1147700Y247190D01*
Y247934D01*
X1147873Y247958D01*
G03Y250736I-193J1389D01*
G01X1147700Y250760D01*
Y250930D01*
X1147500Y251130D01*
X1147440D01*
X1146978Y251592D01*
Y251926D01*
X1147210D01*
X1147240Y251916D01*
G03X1147445Y254629I440J1331D01*
G02X1146978Y255023I-67J394D01*
G01Y255371D01*
G02X1147445Y255765I400J0D01*
G03Y258529I235J1382D01*
G02X1146978Y258923I-67J394D01*
G01Y259271D01*
G02X1147445Y259665I400J0D01*
G03Y262429I235J1382D01*
G02X1146978Y262823I-67J394D01*
G01Y263171D01*
G02X1147445Y263565I400J0D01*
G03Y266329I235J1382D01*
G02X1146978Y266723I-67J394D01*
G01Y267071D01*
G02X1147445Y267465I400J0D01*
G03Y270229I235J1382D01*
G02X1146978Y270623I-67J394D01*
G01Y270971D01*
G02X1147445Y271365I400J0D01*
G03X1146867Y273889I235J1382D01*
G01X1146729Y273791D01*
X1145698Y274822D01*
X1145689Y274888D01*
G03X1144108Y273307I-1389J-192D01*
G01X1144174Y273298D01*
X1144822Y272650D01*
Y272165D01*
X1144602D01*
X1144582Y272169D01*
G03X1144395Y269397I-282J-1373D01*
G02X1144822Y268998I27J-399D01*
G01Y268694D01*
G02X1144395Y268295I-400J0D01*
G03Y265497I-95J-1399D01*
G02X1144822Y265098I27J-399D01*
G01Y264794D01*
G02X1144395Y264395I-400J0D01*
G03Y261597I-95J-1399D01*
G02X1144822Y261198I27J-399D01*
G01Y260894D01*
G02X1144395Y260495I-400J0D01*
G03Y257697I-95J-1399D01*
G02X1144822Y257298I27J-399D01*
G01Y256994D01*
G02X1144395Y256595I-400J0D01*
G03X1143178Y256037I-95J-1399D01*
G02X1142576Y255994I-320J240D01*
G01X1137798Y260772D01*
X1137811Y260869D01*
G03X1136242Y262438I-1391J178D01*
G01X1136145Y262425D01*
X1136000Y262570D01*
X1134842D01*
G02X1134442Y262976I0J400D01*
G03X1131638I-1402J20D01*
G02X1131238Y262570I-400J-6D01*
G01X1128082D01*
G02X1127682Y262976I0J400D01*
G03X1125166Y263847I-1402J20D01*
G02X1124890Y263807I-159J122D01*
G03X1124297Y264150I-1992J-2759D01*
G02X1124195Y264409I82J182D01*
G03X1121605I-1295J538D01*
G02X1121503Y264150I-184J-77D01*
G03X1120910Y263807I1399J-3102D01*
G02X1120635Y263848I-116J162D01*
G03X1118649Y261898I-1113J-852D01*
G02X1118683Y261302I-249J-313D01*
G01X1118003Y260622D01*
Y250202D01*
X1117899Y250098D01*
G02X1117289Y250152I-282J283D01*
G03X1116319Y247956I-1148J-805D01*
G02X1116770Y247560I51J-397D01*
G01Y247341D01*
X1114174D01*
X1114157Y247523D01*
G03X1111365I-1396J-127D01*
G01X1111348Y247341D01*
X1107414D01*
X1107397Y247523D01*
G03X1104605I-1396J-127D01*
G01X1104588Y247341D01*
X1100654D01*
X1100637Y247523D01*
G03X1097873Y247089I-1396J-126D01*
G01X1097897Y246982D01*
X1097385Y246470D01*
G02X1096827Y246463I-283J283D01*
G03X1094571Y244898I-966J-1016D01*
G02X1094203Y244341I-368J-157D01*
G01X1093600D01*
G03X1091362I-1119J-845D01*
G01X1086904D01*
X1083785Y247460D01*
Y247461D01*
X1083756Y247490D01*
Y252231D01*
X1089397Y255673D01*
X1090654Y256930D01*
Y257823D01*
G02X1091120Y258217I400J0D01*
G03Y260983I231J1383D01*
G02X1090654Y261377I-66J394D01*
G01Y262366D01*
X1091510Y263222D01*
X1091629Y263179D01*
G03X1093101Y265482I471J1321D01*
G02X1093145Y266081I285J280D01*
G03X1092284Y268602I-845J1119D01*
G02X1091880Y269002I-4J400D01*
G01Y291152D01*
G02X1092374Y291541I400J0D01*
G03X1093775Y292002I328J1363D01*
G02X1094416Y291963I306J-258D01*
G03X1096956Y291780I1340J878D01*
G02X1097556I300J-265D01*
G03X1099748Y291583I1200J1061D01*
G02X1100320Y291505I249J-314D01*
G03X1102408Y291055I1296J942D01*
G02X1102936Y290934I198J-348D01*
G03X1103463Y293233I1320J907D01*
G02X1102935Y293354I-198J348D01*
G03X1102434Y293824I-1321J-906D01*
G02X1102424Y294506I204J344D01*
G03X1102555Y294598I-854J1355D01*
G02X1103086Y294566I248J-314D01*
G03X1103233Y296957I1135J1130D01*
G02X1102702Y296989I-248J314D01*
G03X1100360Y296913I-1136J-1130D01*
G02X1099761Y296909I-301J263D01*
G03X1097367Y296902I-1194J-1068D01*
G02X1096767I-300J265D01*
G03X1094373Y296909I-1200J-1061D01*
G02X1093774Y296913I-298J267D01*
G03X1092337Y297444I-1206J-1054D01*
G02X1091880Y297840I-57J396D01*
G01Y308103D01*
G02X1092386Y308489I400J0D01*
G03Y311193I370J1352D01*
G02X1091880Y311579I-106J386D01*
G01Y322582D01*
X1093146Y323848D01*
G02X1093823Y323633I283J-283D01*
G03X1096642Y322890I1579J271D01*
G02X1097242Y322913I310J-253D01*
G03X1099520Y322869I1161J1104D01*
G02X1100079I280J-286D01*
G03X1100082Y325161I1121J1145D01*
G02X1099523I-279J286D01*
G03X1097162Y325031I-1121J-1144D01*
G02X1096562Y325008I-310J253D01*
G03X1095673Y325483I-1161J-1104D01*
G02X1095458Y326160I68J394D01*
G01X1104568Y335270D01*
X1104908D01*
Y334993D01*
X1104857Y334936D01*
G03X1107128Y334677I1044J-936D01*
G02X1107478Y335270I350J193D01*
G01X1125225D01*
X1127223Y333272D01*
G02X1127042Y332603I-283J-282D01*
G03X1128791Y331075I358J-1356D01*
G02X1129471Y331309I397J-49D01*
G01X1129860Y330920D01*
G02X1129844Y330340I-283J-282D01*
G03X1131824Y328360I936J-1044D01*
G02X1132404Y328376I298J-267D01*
G01X1132870Y327910D01*
X1132831Y327793D01*
G03X1134606Y326018I1329J-446D01*
G01X1134723Y326057D01*
X1137282Y323498D01*
G02X1137119Y322833I-283J-283D01*
G03X1138877Y321075I421J-1337D01*
G02X1139542Y321238I382J-120D01*
G01X1140085Y320695D01*
X1139943Y320552D01*
X1139942Y320551D01*
G03X1141924Y318569I978J-1004D01*
G01X1141925Y318570D01*
X1142068Y318712D01*
X1142920Y317860D01*
X1142908Y317764D01*
G03X1144468Y316204I1392J-168D01*
G01X1144564Y316216D01*
X1147145Y313635D01*
G02X1147043Y312996I-283J-282D01*
G03X1148929Y311110I637J-1249D01*
G02X1149568Y311212I357J-181D01*
G01X1150024Y310756D01*
X1149924Y310618D01*
G03X1152012Y308768I1137J-820D01*
G01X1153040Y307740D01*
X1153049Y307672D01*
G03X1154265Y306456I1391J175D01*
G01X1154333Y306447D01*
X1154748Y306032D01*
G02X1154460Y305349I-282J-283D01*
G03X1155776Y304373I-20J-1402D01*
G02X1156157Y304895I381J122D01*
G01X1156838D01*
G03X1158802I982J1001D01*
G01X1159483D01*
G02X1159864Y304373I0J-400D01*
G03X1161184Y302545I1336J-426D01*
G02X1161580Y302128I-4J-400D01*
G03X1161579Y301866I3000J-142D01*
G02X1161184Y301449I-399J-17D01*
G03X1162406Y299332I16J-1402D01*
G02X1162965Y299465I344J-204D01*
G03X1163193Y299333I1617J2530D01*
G02X1163357Y298782I-184J-355D01*
G03X1164564Y296694I1223J-686D01*
G02X1164959Y296277I-4J-400D01*
G03X1164960Y296015I3001J-120D01*
G02X1164564Y295598I-400J-17D01*
G03X1163624Y295222I16J-1402D01*
G02X1163069Y295231I-273J292D01*
G01X1162549Y295751D01*
X1162572Y295857D01*
G03X1159799Y296090I-1372J289D01*
G01X1159803Y296003D01*
X1158905Y295105D01*
X1158764Y295233D01*
G03X1157277Y292903I-943J-1037D01*
G01X1157400Y292852D01*
Y291640D01*
X1157277Y291589D01*
G03Y289003I543J-1293D01*
G01X1157400Y288952D01*
Y287740D01*
X1157277Y287689D01*
G03X1158621Y285246I543J-1293D01*
G01X1158759Y285341D01*
X1159300Y284800D01*
Y283938D01*
G02X1158660Y283618I-400J0D01*
G03Y281374I-840J-1122D01*
G02X1159300Y281054I240J-320D01*
G01Y280038D01*
G02X1158660Y279718I-400J0D01*
G03Y277474I-840J-1122D01*
G02X1159300Y277154I240J-320D01*
G01Y276138D01*
G02X1158660Y275818I-400J0D01*
G03Y273574I-840J-1122D01*
G02X1159300Y273254I240J-320D01*
G01Y272238D01*
G02X1158660Y271918I-400J0D01*
G03Y269674I-840J-1122D01*
G02X1159300Y269354I240J-320D01*
G01Y268338D01*
G02X1158660Y268018I-400J0D01*
G03X1157786Y265494I-840J-1122D01*
G02X1158176Y265100I-10J-400D01*
G03X1158563Y264150I1402J17D01*
G02X1158521Y263560I-290J-276D01*
G03X1160405Y263427I869J-1100D01*
G02X1160447Y264017I290J276D01*
G03X1160580Y264136I-866J1102D01*
G02X1161184Y264098I286J-280D01*
G03X1162183Y263550I1116J849D01*
G02X1162550Y263151I-33J-399D01*
G01Y254778D01*
G02X1161939Y254438I-400J0D01*
G03Y252056I-739J-1191D01*
G02X1162550Y251716I211J-340D01*
G01Y250878D01*
G02X1161939Y250538I-400J0D01*
G03Y248156I-739J-1191D01*
G02X1162550Y247816I211J-340D01*
G01Y246978D01*
G02X1161939Y246638I-400J0D01*
G03Y244256I-739J-1191D01*
G02X1162550Y243916I211J-340D01*
G01Y243078D01*
G02X1161939Y242738I-400J0D01*
G03Y240356I-739J-1191D01*
G02X1162550Y240016I211J-340D01*
G01Y239178D01*
G02X1161939Y238838I-400J0D01*
G03Y236456I-739J-1191D01*
G02X1162550Y236116I211J-340D01*
G01Y235277D01*
G02X1161939Y234937I-400J0D01*
G03Y232555I-739J-1191D01*
G02X1162550Y232215I211J-340D01*
G01Y231378D01*
G02X1161939Y231038I-400J0D01*
G03Y228656I-739J-1191D01*
G02X1162550Y228316I211J-340D01*
G01Y227478D01*
G02X1161939Y227138I-400J0D01*
G03Y224756I-739J-1191D01*
G02X1162550Y224416I211J-340D01*
G01Y221050D01*
X1161630Y220130D01*
X1159232D01*
G37*
G36*
G01X1070824Y398698D02*
X1070064Y399048D01*
Y399948D01*
X1070824Y400298D01*
X1070999D01*
Y398698D01*
X1070824D01*
G37*
G36*
G01Y394798D02*
X1070064Y395148D01*
Y396048D01*
X1070824Y396398D01*
X1070999D01*
Y394798D01*
X1070824D01*
G37*
G36*
G01Y390898D02*
X1070064Y391248D01*
Y392148D01*
X1070824Y392498D01*
X1070999D01*
Y390898D01*
X1070824D01*
G37*
G36*
G01X1071922Y396398D02*
X1072682Y396048D01*
Y395148D01*
X1071922Y394798D01*
X1071747D01*
Y396398D01*
X1071922D01*
G37*
G36*
G01Y400298D02*
X1072682Y399948D01*
Y399048D01*
X1071922Y398698D01*
X1071747D01*
Y400298D01*
X1071922D01*
G37*
G36*
G01X1081731Y387014D02*
X1081061Y387364D01*
Y388234D01*
X1081731Y388584D01*
X1081906D01*
Y387014D01*
X1081731D01*
G37*
G36*
G01X1082584Y386634D02*
X1083254Y386284D01*
Y385414D01*
X1082584Y385064D01*
X1082409D01*
Y386634D01*
X1082584D01*
G37*
G36*
G01X1087723Y400708D02*
X1086963Y401058D01*
Y401958D01*
X1087723Y402308D01*
X1087898D01*
Y400708D01*
X1087723D01*
G37*
G36*
G01Y396808D02*
X1086963Y397158D01*
Y398058D01*
X1087723Y398408D01*
X1087898D01*
Y396808D01*
X1087723D01*
G37*
G36*
G01X1084880Y391502D02*
X1084848Y392257D01*
X1085601Y392692D01*
X1086239Y392287D01*
X1086327Y392135D01*
X1084967Y391351D01*
X1084880Y391502D01*
G37*
G36*
G01X1088821Y402308D02*
X1089581Y401958D01*
Y401058D01*
X1088821Y400708D01*
X1088646D01*
Y402308D01*
X1088821D01*
G37*
G36*
G01Y398408D02*
X1089581Y398058D01*
Y397158D01*
X1088821Y396808D01*
X1088646D01*
Y398408D01*
X1088821D01*
G37*
G36*
G01X1089343Y394449D02*
X1090013Y394099D01*
X1090012Y393230D01*
X1089343Y392880D01*
X1089167Y392879D01*
X1089168Y394450D01*
X1089343Y394449D01*
G37*
G36*
G01X1088787Y391881D02*
X1088819Y391126D01*
X1088065Y390692D01*
X1087428Y391097D01*
X1087339Y391248D01*
X1088700Y392033D01*
X1088787Y391881D01*
G37*
G36*
G01X1085407Y389931D02*
X1085439Y389176D01*
X1084685Y388742D01*
X1084048Y389147D01*
X1083959Y389298D01*
X1085320Y390083D01*
X1085407Y389931D01*
G37*
G36*
G01X1070824Y383156D02*
X1070064Y383506D01*
Y384406D01*
X1070824Y384756D01*
X1070999D01*
Y383156D01*
X1070824D01*
G37*
G36*
G01X1070015Y386254D02*
X1069231Y385964D01*
X1068594Y386601D01*
X1068884Y387385D01*
X1069008Y387509D01*
X1070139Y386378D01*
X1070015Y386254D01*
G37*
G36*
G01X1070824Y379256D02*
X1070064Y379606D01*
Y380506D01*
X1070824Y380856D01*
X1070999D01*
Y379256D01*
X1070824D01*
G37*
G36*
G01X1067972Y396677D02*
X1067212Y397027D01*
Y397927D01*
X1067972Y398277D01*
X1068147D01*
Y396677D01*
X1067972D01*
G37*
G36*
G01Y400577D02*
X1067212Y400927D01*
Y401827D01*
X1067972Y402177D01*
X1068147D01*
Y400577D01*
X1067972D01*
G37*
G36*
G01Y392777D02*
X1067212Y393127D01*
Y394027D01*
X1067972Y394377D01*
X1068147D01*
Y392777D01*
X1067972D01*
G37*
G36*
G01X1069661Y388162D02*
X1070445Y388452D01*
X1071082Y387815D01*
X1070792Y387031D01*
X1070668Y386907D01*
X1069537Y388038D01*
X1069661Y388162D01*
G37*
G36*
G01X1071922Y384756D02*
X1072682Y384406D01*
Y383506D01*
X1071922Y383156D01*
X1071747D01*
Y384756D01*
X1071922D01*
G37*
G36*
G01X1069072Y398277D02*
X1069832Y397927D01*
Y397027D01*
X1069072Y396677D01*
X1068897D01*
Y398277D01*
X1069072D01*
G37*
G36*
G01Y402177D02*
X1069832Y401827D01*
Y400927D01*
X1069072Y400577D01*
X1068897D01*
Y402177D01*
X1069072D01*
G37*
G36*
G01Y394377D02*
X1069832Y394027D01*
Y393127D01*
X1069072Y392777D01*
X1068897D01*
Y394377D01*
X1069072D01*
G37*
G36*
G01X1079204Y388606D02*
X1079874Y388256D01*
Y387386D01*
X1079204Y387036D01*
X1079029D01*
Y388606D01*
X1079204D01*
G37*
G36*
G01X1078331Y385042D02*
X1077661Y385392D01*
Y386262D01*
X1078331Y386612D01*
X1078506D01*
Y385042D01*
X1078331D01*
G37*
G36*
G01X1084705Y395259D02*
X1083945Y395609D01*
Y396509D01*
X1084705Y396859D01*
X1084880D01*
Y395259D01*
X1084705D01*
G37*
G36*
G01Y399159D02*
X1083945Y399509D01*
Y400409D01*
X1084705Y400759D01*
X1084880D01*
Y399159D01*
X1084705D01*
G37*
G36*
G01X1081495Y393448D02*
X1081463Y394203D01*
X1082216Y394638D01*
X1082854Y394233D01*
X1082942Y394081D01*
X1081582Y393297D01*
X1081495Y393448D01*
G37*
G36*
G01X1085803Y396859D02*
X1086563Y396509D01*
Y395609D01*
X1085803Y395259D01*
X1085628D01*
Y396859D01*
X1085803D01*
G37*
G36*
G01Y400759D02*
X1086563Y400409D01*
Y399509D01*
X1085803Y399159D01*
X1085628D01*
Y400759D01*
X1085803D01*
G37*
G36*
G01X1082043Y391891D02*
X1082075Y391136D01*
X1081322Y390701D01*
X1080684Y391106D01*
X1080596Y391257D01*
X1081956Y392043D01*
X1082043Y391891D01*
G37*
G36*
G01X1085423Y393841D02*
X1085455Y393086D01*
X1084702Y392651D01*
X1084064Y393056D01*
X1083976Y393207D01*
X1085336Y393993D01*
X1085423Y393841D01*
G37*
G36*
G01X1075823Y396325D02*
X1076583Y395975D01*
Y395075D01*
X1075823Y394725D01*
X1075648D01*
Y396325D01*
X1075823D01*
G37*
G36*
G01Y400225D02*
X1076583Y399875D01*
Y398975D01*
X1075823Y398625D01*
X1075648D01*
Y400225D01*
X1075823D01*
G37*
G36*
G01X1078387Y403844D02*
X1078677Y403060D01*
X1078040Y402423D01*
X1077256Y402713D01*
X1077132Y402837D01*
X1078263Y403968D01*
X1078387Y403844D01*
G37*
G36*
G01X1075824Y386634D02*
X1076494Y386284D01*
Y385414D01*
X1075824Y385064D01*
X1075649D01*
Y386634D01*
X1075824D01*
G37*
G36*
G01Y390534D02*
X1076494Y390184D01*
Y389314D01*
X1075824Y388964D01*
X1075649D01*
Y390534D01*
X1075824D01*
G37*
G36*
G01X1079308Y396469D02*
X1079018Y397254D01*
X1079654Y397890D01*
X1080439Y397600D01*
X1080563Y397477D01*
X1079432Y396345D01*
X1079308Y396469D01*
G37*
G36*
G01X1081685Y399067D02*
X1080925Y399417D01*
Y400317D01*
X1081685Y400667D01*
X1081860D01*
Y399067D01*
X1081685D01*
G37*
G36*
G01X1074723Y398625D02*
X1073963Y398975D01*
Y399875D01*
X1074723Y400225D01*
X1074898D01*
Y398625D01*
X1074723D01*
G37*
G36*
G01X1074200Y390914D02*
X1073530Y391264D01*
Y392134D01*
X1074200Y392484D01*
X1074375D01*
Y390914D01*
X1074200D01*
G37*
G36*
G01X1074723Y394725D02*
X1073963Y395075D01*
Y395975D01*
X1074723Y396325D01*
X1074898D01*
Y394725D01*
X1074723D01*
G37*
G36*
G01X1074200Y383114D02*
X1073530Y383464D01*
Y384334D01*
X1074200Y384684D01*
X1074375D01*
Y383114D01*
X1074200D01*
G37*
G36*
G01Y387014D02*
X1073530Y387364D01*
Y388234D01*
X1074200Y388584D01*
X1074375D01*
Y387014D01*
X1074200D01*
G37*
G36*
G01X1082785Y400667D02*
X1083545Y400317D01*
Y399417D01*
X1082785Y399067D01*
X1082610D01*
Y400667D01*
X1082785D01*
G37*
G36*
G01X1081217Y396823D02*
X1081507Y396038D01*
X1080871Y395401D01*
X1080086Y395691D01*
X1079962Y395815D01*
X1081094Y396946D01*
X1081217Y396823D01*
G37*
G36*
G01X1074544Y411149D02*
X1073784Y411499D01*
Y412399D01*
X1074544Y412749D01*
X1074719D01*
Y411149D01*
X1074544D01*
G37*
G36*
G01Y407249D02*
X1073784Y407599D01*
Y408499D01*
X1074544Y408849D01*
X1074719D01*
Y407249D01*
X1074544D01*
G37*
G36*
G01Y415049D02*
X1073784Y415399D01*
Y416299D01*
X1074544Y416649D01*
X1074719D01*
Y415049D01*
X1074544D01*
G37*
G36*
G01X1072169Y404753D02*
X1071879Y405538D01*
X1072515Y406174D01*
X1073300Y405884D01*
X1073424Y405761D01*
X1072292Y404629D01*
X1072169Y404753D01*
G37*
G36*
G01X1075642Y412749D02*
X1076402Y412399D01*
Y411499D01*
X1075642Y411149D01*
X1075467D01*
Y412749D01*
X1075642D01*
G37*
G36*
G01Y408849D02*
X1076402Y408499D01*
Y407599D01*
X1075642Y407249D01*
X1075467D01*
Y408849D01*
X1075642D01*
G37*
G36*
G01Y416649D02*
X1076402Y416299D01*
Y415399D01*
X1075642Y415049D01*
X1075467D01*
Y416649D01*
X1075642D01*
G37*
G36*
G01X1074076Y405108D02*
X1074366Y404323D01*
X1073730Y403687D01*
X1072945Y403977D01*
X1072821Y404100D01*
X1073953Y405232D01*
X1074076Y405108D01*
G37*
G36*
G01X1089341Y405446D02*
X1089051Y406230D01*
X1089688Y406867D01*
X1090472Y406577D01*
X1090596Y406453D01*
X1089465Y405322D01*
X1089341Y405446D01*
G37*
G36*
G01X1091467Y406020D02*
X1091757Y405236D01*
X1091120Y404599D01*
X1090336Y404889D01*
X1090212Y405013D01*
X1091343Y406144D01*
X1091467Y406020D01*
G37*
G36*
G01X1069574Y406795D02*
X1068814Y407145D01*
Y408045D01*
X1069574Y408395D01*
X1069749D01*
Y406795D01*
X1069574D01*
G37*
G36*
G01Y410695D02*
X1068814Y411045D01*
Y411945D01*
X1069574Y412295D01*
X1069749D01*
Y410695D01*
X1069574D01*
G37*
G36*
G01X1070674Y408395D02*
X1071434Y408045D01*
Y407145D01*
X1070674Y406795D01*
X1070499D01*
Y408395D01*
X1070674D01*
G37*
G36*
G01Y412295D02*
X1071434Y411945D01*
Y411045D01*
X1070674Y410695D01*
X1070499D01*
Y412295D01*
X1070674D01*
G37*
G36*
G01X1086868Y407835D02*
X1086108Y408185D01*
Y409085D01*
X1086868Y409435D01*
X1087043D01*
Y407835D01*
X1086868D01*
G37*
G36*
G01X1084705Y403059D02*
X1083945Y403409D01*
Y404309D01*
X1084705Y404659D01*
X1084880D01*
Y403059D01*
X1084705D01*
G37*
G36*
G01X1087966Y409435D02*
X1088726Y409085D01*
Y408185D01*
X1087966Y407835D01*
X1087791D01*
Y409435D01*
X1087966D01*
G37*
G36*
G01X1085803Y404659D02*
X1086563Y404309D01*
Y403409D01*
X1085803Y403059D01*
X1085628D01*
Y404659D01*
X1085803D01*
G37*
G36*
G01X1080361Y414526D02*
X1081121Y414176D01*
Y413276D01*
X1080361Y412926D01*
X1080186D01*
Y414526D01*
X1080361D01*
G37*
G36*
G01Y410626D02*
X1081121Y410276D01*
Y409376D01*
X1080361Y409026D01*
X1080186D01*
Y410626D01*
X1080361D01*
G37*
G36*
G01X1082711Y410952D02*
X1081951Y411302D01*
Y412202D01*
X1082711Y412552D01*
X1082886D01*
Y410952D01*
X1082711D01*
G37*
G36*
G01X1081685Y402967D02*
X1080925Y403317D01*
Y404217D01*
X1081685Y404567D01*
X1081860D01*
Y402967D01*
X1081685D01*
G37*
G36*
G01X1082711Y407052D02*
X1081951Y407402D01*
Y408302D01*
X1082711Y408652D01*
X1082886D01*
Y407052D01*
X1082711D01*
G37*
G36*
G01Y414852D02*
X1081951Y415202D01*
Y416102D01*
X1082711Y416452D01*
X1082886D01*
Y414852D01*
X1082711D01*
G37*
G36*
G01X1079261Y409026D02*
X1078501Y409376D01*
Y410276D01*
X1079261Y410626D01*
X1079436D01*
Y409026D01*
X1079261D01*
G37*
G36*
G01Y412926D02*
X1078501Y413276D01*
Y414176D01*
X1079261Y414526D01*
X1079436D01*
Y412926D01*
X1079261D01*
G37*
G36*
G01X1076478Y403491D02*
X1076188Y404276D01*
X1076824Y404912D01*
X1077609Y404622D01*
X1077733Y404499D01*
X1076601Y403367D01*
X1076478Y403491D01*
G37*
G36*
G01X1083811Y408652D02*
X1084571Y408302D01*
Y407402D01*
X1083811Y407052D01*
X1083636D01*
Y408652D01*
X1083811D01*
G37*
G36*
G01Y412552D02*
X1084571Y412202D01*
Y411302D01*
X1083811Y410952D01*
X1083636D01*
Y412552D01*
X1083811D01*
G37*
G36*
G01X1082785Y404567D02*
X1083545Y404217D01*
Y403317D01*
X1082785Y402967D01*
X1082610D01*
Y404567D01*
X1082785D01*
G37*
G36*
G01X1083811Y416452D02*
X1084571Y416102D01*
Y415202D01*
X1083811Y414852D01*
X1083636D01*
Y416452D01*
X1083811D01*
G37*
G36*
G01X1121117Y204532D02*
X1120362Y204500D01*
X1119927Y205253D01*
X1120332Y205891D01*
X1120484Y205979D01*
X1121268Y204619D01*
X1121117Y204532D01*
G37*
G36*
G01X1120398Y217326D02*
X1119728Y217676D01*
Y218546D01*
X1120398Y218896D01*
X1120573D01*
Y217326D01*
X1120398D01*
G37*
G36*
G01Y213437D02*
X1119728Y213787D01*
Y214657D01*
X1120398Y215007D01*
X1120573D01*
Y213437D01*
X1120398D01*
G37*
G36*
G01Y209537D02*
X1119728Y209887D01*
Y210757D01*
X1120398Y211107D01*
X1120573D01*
Y209537D01*
X1120398D01*
G37*
G36*
G01X1129258Y199847D02*
X1128473Y199557D01*
X1127837Y200193D01*
X1128127Y200978D01*
X1128250Y201102D01*
X1129382Y199970D01*
X1129258Y199847D01*
G37*
G36*
G01X1123189Y205172D02*
X1123789Y205632D01*
X1124577Y205264D01*
X1124611Y204509D01*
X1124537Y204350D01*
X1123115Y205014D01*
X1123189Y205172D01*
G37*
G36*
G01X1122022Y209206D02*
X1122692Y208856D01*
Y207986D01*
X1122022Y207636D01*
X1121847D01*
Y209206D01*
X1122022D01*
G37*
G36*
G01X1122023Y217017D02*
X1122693Y216667D01*
Y215797D01*
X1122023Y215447D01*
X1121848D01*
Y217017D01*
X1122023D01*
G37*
G36*
G01X1122022Y213106D02*
X1122692Y212756D01*
Y211886D01*
X1122022Y211536D01*
X1121847D01*
Y213106D01*
X1122022D01*
G37*
G36*
G01X1128903Y201754D02*
X1129688Y202044D01*
X1130324Y201408D01*
X1130034Y200623D01*
X1129911Y200499D01*
X1128779Y201631D01*
X1128903Y201754D01*
G37*
G36*
G01X1133918Y217337D02*
X1133248Y217687D01*
Y218557D01*
X1133918Y218907D01*
X1134093D01*
Y217337D01*
X1133918D01*
G37*
G36*
G01Y213437D02*
X1133248Y213787D01*
Y214657D01*
X1133918Y215007D01*
X1134093D01*
Y213437D01*
X1133918D01*
G37*
G36*
G01X1135542Y217006D02*
X1136212Y216656D01*
Y215786D01*
X1135542Y215436D01*
X1135367D01*
Y217006D01*
X1135542D01*
G37*
G36*
G01X1117018Y207636D02*
X1116348Y207986D01*
Y208856D01*
X1117018Y209206D01*
X1117193D01*
Y207636D01*
X1117018D01*
G37*
G36*
G01X1117019Y215436D02*
X1116349Y215786D01*
Y216656D01*
X1117019Y217006D01*
X1117194D01*
Y215436D01*
X1117019D01*
G37*
G36*
G01X1117018Y211547D02*
X1116348Y211897D01*
Y212767D01*
X1117018Y213117D01*
X1117193D01*
Y211547D01*
X1117018D01*
G37*
G36*
G01X1117725Y202603D02*
X1116970Y202571D01*
X1116535Y203324D01*
X1116940Y203962D01*
X1117092Y204050D01*
X1117876Y202690D01*
X1117725Y202603D01*
G37*
G36*
G01X1118643Y207231D02*
X1119313Y206881D01*
Y206011D01*
X1118643Y205661D01*
X1118468D01*
Y207231D01*
X1118643D01*
G37*
G36*
G01Y218907D02*
X1119313Y218557D01*
Y217687D01*
X1118643Y217337D01*
X1118468D01*
Y218907D01*
X1118643D01*
G37*
G36*
G01Y214996D02*
X1119313Y214646D01*
Y213776D01*
X1118643Y213426D01*
X1118468D01*
Y214996D01*
X1118643D01*
G37*
G36*
G01Y211096D02*
X1119313Y210746D01*
Y209876D01*
X1118643Y209526D01*
X1118468D01*
Y211096D01*
X1118643D01*
G37*
G36*
G01X1135812Y207809D02*
X1135174Y207404D01*
X1134421Y207839D01*
X1134453Y208594D01*
X1134540Y208746D01*
X1135900Y207960D01*
X1135812Y207809D01*
G37*
G36*
G01X1130538Y215436D02*
X1129868Y215786D01*
Y216656D01*
X1130538Y217006D01*
X1130713D01*
Y215436D01*
X1130538D01*
G37*
G36*
G01Y211536D02*
X1129868Y211886D01*
Y212756D01*
X1130538Y213106D01*
X1130713D01*
Y211536D01*
X1130538D01*
G37*
G36*
G01X1141087Y206216D02*
X1140302Y205926D01*
X1139666Y206562D01*
X1139956Y207347D01*
X1140079Y207471D01*
X1141211Y206339D01*
X1141087Y206216D01*
G37*
G36*
G01X1133648Y210933D02*
X1134286Y211338D01*
X1135039Y210903D01*
X1135007Y210148D01*
X1134920Y209996D01*
X1133560Y210782D01*
X1133648Y210933D01*
G37*
G36*
G01X1132162Y218907D02*
X1132832Y218557D01*
Y217687D01*
X1132162Y217337D01*
X1131987D01*
Y218907D01*
X1132162D01*
G37*
G36*
G01Y215007D02*
X1132832Y214657D01*
Y213787D01*
X1132162Y213437D01*
X1131987D01*
Y215007D01*
X1132162D01*
G37*
G36*
G01X1140734Y208125D02*
X1141518Y208415D01*
X1142155Y207778D01*
X1141865Y206994D01*
X1141741Y206870D01*
X1140610Y208001D01*
X1140734Y208125D01*
G37*
G36*
G01X1125402Y218907D02*
X1126072Y218557D01*
Y217687D01*
X1125402Y217337D01*
X1125227D01*
Y218907D01*
X1125402D01*
G37*
G36*
G01Y215007D02*
X1126072Y214657D01*
Y213787D01*
X1125402Y213437D01*
X1125227D01*
Y215007D01*
X1125402D01*
G37*
G36*
G01Y211107D02*
X1126072Y210757D01*
Y209887D01*
X1125402Y209537D01*
X1125227D01*
Y211107D01*
X1125402D01*
G37*
G36*
G01X1126888Y207033D02*
X1127526Y207438D01*
X1128279Y207003D01*
X1128247Y206248D01*
X1128160Y206096D01*
X1126800Y206882D01*
X1126888Y207033D01*
G37*
G36*
G01X1133034Y202935D02*
X1133818Y203225D01*
X1134455Y202588D01*
X1134165Y201804D01*
X1134041Y201680D01*
X1132910Y202811D01*
X1133034Y202935D01*
G37*
G36*
G01X1130215Y209015D02*
X1130853Y209420D01*
X1131606Y208985D01*
X1131574Y208230D01*
X1131487Y208078D01*
X1130127Y208864D01*
X1130215Y209015D01*
G37*
G36*
G01X1128782Y213081D02*
X1129452Y212731D01*
Y211861D01*
X1128782Y211511D01*
X1128607D01*
Y213081D01*
X1128782D01*
G37*
G36*
G01Y217006D02*
X1129452Y216656D01*
Y215786D01*
X1128782Y215436D01*
X1128607D01*
Y217006D01*
X1128782D01*
G37*
G36*
G01X1124489Y206496D02*
X1123734Y206464D01*
X1123299Y207217D01*
X1123704Y207855D01*
X1123856Y207943D01*
X1124640Y206583D01*
X1124489Y206496D01*
G37*
G36*
G01X1123778Y215436D02*
X1123108Y215786D01*
Y216656D01*
X1123778Y217006D01*
X1123953D01*
Y215436D01*
X1123778D01*
G37*
G36*
G01Y211536D02*
X1123108Y211886D01*
Y212756D01*
X1123778Y213106D01*
X1123953D01*
Y211536D01*
X1123778D01*
G37*
G36*
G01X1133387Y201026D02*
X1132602Y200736D01*
X1131966Y201372D01*
X1132256Y202157D01*
X1132379Y202281D01*
X1133511Y201149D01*
X1133387Y201026D01*
G37*
G36*
G01X1127158Y217337D02*
X1126488Y217687D01*
Y218557D01*
X1127158Y218907D01*
X1127333D01*
Y217337D01*
X1127158D01*
G37*
G36*
G01Y213437D02*
X1126488Y213787D01*
Y214657D01*
X1127158Y215007D01*
X1127333D01*
Y213437D01*
X1127158D01*
G37*
G36*
G01X1127865Y208453D02*
X1127110Y208421D01*
X1126675Y209174D01*
X1127080Y209812D01*
X1127232Y209900D01*
X1128016Y208540D01*
X1127865Y208453D01*
G37*
G36*
G01X1097112Y201541D02*
X1096327Y201251D01*
X1095691Y201887D01*
X1095981Y202672D01*
X1096104Y202796D01*
X1097236Y201664D01*
X1097112Y201541D01*
G37*
G36*
G01X1099425Y196635D02*
X1098665Y196985D01*
Y197885D01*
X1099425Y198235D01*
X1099600D01*
Y196635D01*
X1099425D01*
G37*
G36*
G01X1104642Y189979D02*
X1103857Y189689D01*
X1103221Y190326D01*
X1103511Y191111D01*
X1103635Y191234D01*
X1104766Y190103D01*
X1104642Y189979D01*
G37*
G36*
G01X1101885Y192737D02*
X1101100Y192447D01*
X1100464Y193084D01*
X1100754Y193869D01*
X1100878Y193992D01*
X1102009Y192861D01*
X1101885Y192737D01*
G37*
G36*
G01X1096759Y203450D02*
X1097543Y203740D01*
X1098180Y203103D01*
X1097890Y202319D01*
X1097766Y202195D01*
X1096635Y203326D01*
X1096759Y203450D01*
G37*
G36*
G01X1101532Y194647D02*
X1102317Y194937D01*
X1102954Y194301D01*
X1102664Y193516D01*
X1102540Y193392D01*
X1101409Y194523D01*
X1101532Y194647D01*
G37*
G36*
G01X1100525Y198235D02*
X1101285Y197885D01*
Y196985D01*
X1100525Y196635D01*
X1100350D01*
Y198235D01*
X1100525D01*
G37*
G36*
G01X1104290Y191889D02*
X1105075Y192179D01*
X1105711Y191543D01*
X1105421Y190758D01*
X1105298Y190634D01*
X1104166Y191766D01*
X1104290Y191889D01*
G37*
G36*
G01X1106879Y213437D02*
X1106209Y213787D01*
Y214657D01*
X1106879Y215007D01*
X1107054D01*
Y213437D01*
X1106879D01*
G37*
G36*
G01Y217337D02*
X1106209Y217687D01*
Y218557D01*
X1106879Y218907D01*
X1107054D01*
Y217337D01*
X1106879D01*
G37*
G36*
G01X1110142Y206371D02*
X1109357Y206081D01*
X1108721Y206717D01*
X1109011Y207502D01*
X1109134Y207626D01*
X1110266Y206494D01*
X1110142Y206371D01*
G37*
G36*
G01X1112900Y203614D02*
X1112115Y203324D01*
X1111479Y203960D01*
X1111769Y204745D01*
X1111892Y204869D01*
X1113024Y203737D01*
X1112900Y203614D01*
G37*
G36*
G01X1118049Y195704D02*
X1117264Y195414D01*
X1116627Y196050D01*
X1116917Y196835D01*
X1117041Y196959D01*
X1118172Y195828D01*
X1118049Y195704D01*
G37*
G36*
G01X1120806Y192946D02*
X1120021Y192656D01*
X1119385Y193293D01*
X1119675Y194078D01*
X1119799Y194201D01*
X1120930Y193070D01*
X1120806Y192946D01*
G37*
G36*
G01X1122765Y187853D02*
X1122005Y188203D01*
Y189103D01*
X1122765Y189453D01*
X1122940D01*
Y187853D01*
X1122765D01*
G37*
G36*
G01X1108503Y213081D02*
X1109173Y212731D01*
Y211861D01*
X1108503Y211511D01*
X1108328D01*
Y213081D01*
X1108503D01*
G37*
G36*
G01Y217006D02*
X1109173Y216656D01*
Y215786D01*
X1108503Y215436D01*
X1108328D01*
Y217006D01*
X1108503D01*
G37*
G36*
G01X1109843Y208334D02*
X1110628Y208624D01*
X1111264Y207988D01*
X1110974Y207203D01*
X1110851Y207079D01*
X1109719Y208211D01*
X1109843Y208334D01*
G37*
G36*
G01X1112601Y205577D02*
X1113386Y205867D01*
X1114022Y205230D01*
X1113732Y204445D01*
X1113608Y204322D01*
X1112477Y205453D01*
X1112601Y205577D01*
G37*
G36*
G01X1117696Y197614D02*
X1118481Y197904D01*
X1119117Y197267D01*
X1118827Y196482D01*
X1118703Y196359D01*
X1117572Y197490D01*
X1117696Y197614D01*
G37*
G36*
G01X1120453Y194856D02*
X1121238Y195146D01*
X1121875Y194510D01*
X1121585Y193725D01*
X1121461Y193601D01*
X1120330Y194732D01*
X1120453Y194856D01*
G37*
G36*
G01X1123955Y189453D02*
X1124715Y189103D01*
Y188203D01*
X1123955Y187853D01*
X1123780D01*
Y189453D01*
X1123955D01*
G37*
G36*
G01X1096275Y195746D02*
X1095515Y196096D01*
Y196995D01*
X1096275Y197345D01*
X1096450Y197346D01*
Y195745D01*
X1096275Y195746D01*
G37*
G36*
G01X1100055Y185826D02*
X1099295Y186176D01*
Y187076D01*
X1100055Y187426D01*
X1100230D01*
Y185826D01*
X1100055D01*
G37*
G36*
G01X1099866Y190418D02*
X1099081Y190128D01*
X1098445Y190764D01*
X1098735Y191549D01*
X1098858Y191673D01*
X1099990Y190541D01*
X1099866Y190418D01*
G37*
G36*
G01X1097375Y197346D02*
X1098135Y196996D01*
Y196096D01*
X1097375Y195746D01*
X1097200D01*
Y197346D01*
X1097375D01*
G37*
G36*
G01X1101279Y187426D02*
X1102039Y187076D01*
Y186176D01*
X1101279Y185826D01*
X1101104D01*
Y187426D01*
X1101279D01*
G37*
G36*
G01X1099512Y192327D02*
X1100297Y192617D01*
X1100934Y191981D01*
X1100644Y191196D01*
X1100520Y191072D01*
X1099389Y192203D01*
X1099512Y192327D01*
G37*
G36*
G01X1103499Y215436D02*
X1102829Y215786D01*
Y216656D01*
X1103499Y217006D01*
X1103674D01*
Y215436D01*
X1103499D01*
G37*
G36*
G01Y211536D02*
X1102829Y211886D01*
Y212756D01*
X1103499Y213106D01*
X1103674D01*
Y211536D01*
X1103499D01*
G37*
G36*
G01X1111623Y200368D02*
X1110839Y200078D01*
X1110202Y200715D01*
X1110492Y201499D01*
X1110616Y201623D01*
X1111747Y200492D01*
X1111623Y200368D01*
G37*
G36*
G01X1108865Y203126D02*
X1108081Y202836D01*
X1107444Y203473D01*
X1107734Y204257D01*
X1107858Y204381D01*
X1108989Y203250D01*
X1108865Y203126D01*
G37*
G36*
G01X1114755Y194626D02*
X1113970Y194336D01*
X1113334Y194972D01*
X1113624Y195757D01*
X1113747Y195881D01*
X1114879Y194749D01*
X1114755Y194626D01*
G37*
G36*
G01X1117845Y187672D02*
X1117085Y188022D01*
Y188922D01*
X1117845Y189272D01*
X1118020D01*
Y187672D01*
X1117845D01*
G37*
G36*
G01X1117513Y191868D02*
X1116728Y191578D01*
X1116091Y192214D01*
X1116381Y192999D01*
X1116505Y193123D01*
X1117636Y191992D01*
X1117513Y191868D01*
G37*
G36*
G01X1105123Y215007D02*
X1105793Y214657D01*
Y213787D01*
X1105123Y213437D01*
X1104948D01*
Y215007D01*
X1105123D01*
G37*
G36*
G01Y218907D02*
X1105793Y218557D01*
Y217687D01*
X1105123Y217337D01*
X1104948D01*
Y218907D01*
X1105123D01*
G37*
G36*
G01X1108607Y205130D02*
X1109392Y205420D01*
X1110028Y204784D01*
X1109738Y203999D01*
X1109615Y203875D01*
X1108483Y205007D01*
X1108607Y205130D01*
G37*
G36*
G01X1111365Y202372D02*
X1112150Y202662D01*
X1112786Y202026D01*
X1112496Y201241D01*
X1112373Y201117D01*
X1111241Y202249D01*
X1111365Y202372D01*
G37*
G36*
G01X1114403Y196536D02*
X1115188Y196826D01*
X1115824Y196189D01*
X1115534Y195404D01*
X1115410Y195281D01*
X1114279Y196412D01*
X1114403Y196536D01*
G37*
G36*
G01X1118945Y189272D02*
X1119705Y188922D01*
Y188022D01*
X1118945Y187672D01*
X1118770D01*
Y189272D01*
X1118945D01*
G37*
G36*
G01X1117160Y193778D02*
X1117945Y194068D01*
X1118581Y193431D01*
X1118291Y192646D01*
X1118167Y192523D01*
X1117036Y193654D01*
X1117160Y193778D01*
G37*
G36*
G01X1098363Y218907D02*
X1099033Y218557D01*
Y217687D01*
X1098363Y217337D01*
X1098188D01*
Y218907D01*
X1098363D01*
G37*
G36*
G01Y215007D02*
X1099033Y214657D01*
Y213787D01*
X1098363Y213437D01*
X1098188D01*
Y215007D01*
X1098363D01*
G37*
G36*
G01X1101184Y203994D02*
X1101968Y204284D01*
X1102605Y203647D01*
X1102315Y202863D01*
X1102191Y202739D01*
X1101060Y203870D01*
X1101184Y203994D01*
G37*
G36*
G01X1104835Y195734D02*
X1105620Y196024D01*
X1106256Y195388D01*
X1105966Y194603D01*
X1105843Y194479D01*
X1104711Y195611D01*
X1104835Y195734D01*
G37*
G36*
G01X1103375Y200615D02*
X1104135Y200265D01*
Y199365D01*
X1103375Y199015D01*
X1103200D01*
Y200615D01*
X1103375D01*
G37*
G36*
G01X1107592Y192976D02*
X1108377Y193266D01*
X1109013Y192630D01*
X1108723Y191845D01*
X1108600Y191721D01*
X1107468Y192853D01*
X1107592Y192976D01*
G37*
G36*
G01X1110529Y188812D02*
X1111289Y188462D01*
Y187562D01*
X1110529Y187212D01*
X1110354D01*
Y188812D01*
X1110529D01*
G37*
G36*
G01X1101743Y217006D02*
X1102413Y216656D01*
Y215786D01*
X1101743Y215436D01*
X1101568D01*
Y217006D01*
X1101743D01*
G37*
G36*
G01X1104078Y205299D02*
X1104863Y205589D01*
X1105499Y204953D01*
X1105209Y204168D01*
X1105086Y204044D01*
X1103954Y205176D01*
X1104078Y205299D01*
G37*
G36*
G01X1108722Y197855D02*
X1109507Y198145D01*
X1110143Y197509D01*
X1109853Y196724D01*
X1109730Y196600D01*
X1108598Y197732D01*
X1108722Y197855D01*
G37*
G36*
G01X1111480Y195098D02*
X1112265Y195388D01*
X1112901Y194751D01*
X1112611Y193966D01*
X1112487Y193843D01*
X1111356Y194974D01*
X1111480Y195098D01*
G37*
G36*
G01X1114392Y190040D02*
X1115152Y189690D01*
Y188790D01*
X1114392Y188440D01*
X1114217D01*
Y190040D01*
X1114392D01*
G37*
G36*
G01X1096739Y215436D02*
X1096069Y215786D01*
Y216656D01*
X1096739Y217006D01*
X1096914D01*
Y215436D01*
X1096739D01*
G37*
G36*
G01Y211511D02*
X1096069Y211861D01*
Y212731D01*
X1096739Y213081D01*
X1096914D01*
Y211511D01*
X1096739D01*
G37*
G36*
G01X1101537Y202085D02*
X1100752Y201795D01*
X1100116Y202431D01*
X1100406Y203216D01*
X1100529Y203340D01*
X1101661Y202208D01*
X1101537Y202085D01*
G37*
G36*
G01X1105188Y193825D02*
X1104404Y193535D01*
X1103767Y194172D01*
X1104057Y194956D01*
X1104181Y195080D01*
X1105312Y193949D01*
X1105188Y193825D01*
G37*
G36*
G01X1102275Y199015D02*
X1101515Y199365D01*
Y200265D01*
X1102275Y200615D01*
X1102450D01*
Y199015D01*
X1102275D01*
G37*
G36*
G01X1107945Y191067D02*
X1107161Y190777D01*
X1106524Y191414D01*
X1106814Y192198D01*
X1106938Y192322D01*
X1108069Y191191D01*
X1107945Y191067D01*
G37*
G36*
G01X1109429Y187212D02*
X1108669Y187562D01*
Y188462D01*
X1109429Y188812D01*
X1109604D01*
Y187212D01*
X1109429D01*
G37*
G36*
G01X1100119Y217337D02*
X1099449Y217687D01*
Y218557D01*
X1100119Y218907D01*
X1100294D01*
Y217337D01*
X1100119D01*
G37*
G36*
G01Y213437D02*
X1099449Y213787D01*
Y214657D01*
X1100119Y215007D01*
X1100294D01*
Y213437D01*
X1100119D01*
G37*
G36*
G01X1104431Y203390D02*
X1103647Y203100D01*
X1103010Y203737D01*
X1103300Y204521D01*
X1103424Y204645D01*
X1104555Y203514D01*
X1104431Y203390D01*
G37*
G36*
G01X1109075Y195946D02*
X1108291Y195656D01*
X1107654Y196293D01*
X1107944Y197077D01*
X1108068Y197201D01*
X1109199Y196070D01*
X1109075Y195946D01*
G37*
G36*
G01X1113292Y188440D02*
X1112532Y188790D01*
Y189690D01*
X1113292Y190040D01*
X1113467D01*
Y188440D01*
X1113292D01*
G37*
G36*
G01X1111833Y193188D02*
X1111049Y192898D01*
X1110412Y193535D01*
X1110702Y194319D01*
X1110826Y194443D01*
X1111957Y193312D01*
X1111833Y193188D01*
G37*
G36*
G01X1120398Y221226D02*
X1119728Y221576D01*
Y222446D01*
X1120398Y222796D01*
X1120573D01*
Y221226D01*
X1120398D01*
G37*
G36*
G01X1118919Y225356D02*
X1118281Y224951D01*
X1117528Y225386D01*
X1117560Y226141D01*
X1117647Y226293D01*
X1119007Y225507D01*
X1118919Y225356D01*
G37*
G36*
G01X1122023Y220917D02*
X1122693Y220567D01*
Y219697D01*
X1122023Y219347D01*
X1121848D01*
Y220917D01*
X1122023D01*
G37*
G36*
G01X1116743Y228487D02*
X1117381Y228892D01*
X1118134Y228457D01*
X1118102Y227702D01*
X1118015Y227550D01*
X1116655Y228336D01*
X1116743Y228487D01*
G37*
G36*
G01X1133918Y229062D02*
X1133248Y229412D01*
Y230282D01*
X1133918Y230632D01*
X1134093D01*
Y229062D01*
X1133918D01*
G37*
G36*
G01Y225137D02*
X1133248Y225487D01*
Y226357D01*
X1133918Y226707D01*
X1134093D01*
Y225137D01*
X1133918D01*
G37*
G36*
G01Y221237D02*
X1133248Y221587D01*
Y222457D01*
X1133918Y222807D01*
X1134093D01*
Y221237D01*
X1133918D01*
G37*
G36*
G01X1132432Y233159D02*
X1131794Y232754D01*
X1131041Y233189D01*
X1131073Y233944D01*
X1131160Y234096D01*
X1132520Y233310D01*
X1132432Y233159D01*
G37*
G36*
G01X1129067Y235101D02*
X1128429Y234696D01*
X1127676Y235131D01*
X1127708Y235886D01*
X1127795Y236038D01*
X1129155Y235252D01*
X1129067Y235101D01*
G37*
G36*
G01X1135542Y228706D02*
X1136212Y228356D01*
Y227486D01*
X1135542Y227136D01*
X1135367D01*
Y228706D01*
X1135542D01*
G37*
G36*
G01Y224806D02*
X1136212Y224456D01*
Y223586D01*
X1135542Y223236D01*
X1135367D01*
Y224806D01*
X1135542D01*
G37*
G36*
G01Y220906D02*
X1136212Y220556D01*
Y219686D01*
X1135542Y219336D01*
X1135367D01*
Y220906D01*
X1135542D01*
G37*
G36*
G01X1133641Y234338D02*
X1134279Y234743D01*
X1135032Y234309D01*
X1135000Y233554D01*
X1134913Y233401D01*
X1133554Y234187D01*
X1133641Y234338D01*
G37*
G36*
G01X1130253Y236292D02*
X1130891Y236697D01*
X1131644Y236262D01*
X1131612Y235507D01*
X1131525Y235355D01*
X1130165Y236141D01*
X1130253Y236292D01*
G37*
G36*
G01X1126873Y238242D02*
X1127511Y238647D01*
X1128264Y238212D01*
X1128232Y237457D01*
X1128145Y237305D01*
X1126785Y238091D01*
X1126873Y238242D01*
G37*
G36*
G01X1117019Y219336D02*
X1116349Y219686D01*
Y220556D01*
X1117019Y220906D01*
X1117194D01*
Y219336D01*
X1117019D01*
G37*
G36*
G01X1115533Y223410D02*
X1114895Y223005D01*
X1114142Y223440D01*
X1114174Y224195D01*
X1114261Y224346D01*
X1115621Y223561D01*
X1115533Y223410D01*
G37*
G36*
G01X1110259Y230987D02*
X1109589Y231337D01*
Y232207D01*
X1110259Y232557D01*
X1110434D01*
Y230987D01*
X1110259D01*
G37*
G36*
G01X1113369Y226533D02*
X1114007Y226938D01*
X1114760Y226503D01*
X1114728Y225748D01*
X1114641Y225596D01*
X1113281Y226382D01*
X1113369Y226533D01*
G37*
G36*
G01X1111882Y230676D02*
X1112552Y230326D01*
Y229456D01*
X1111882Y229106D01*
X1111707D01*
Y230676D01*
X1111882D01*
G37*
G36*
G01X1116742Y224588D02*
X1117380Y224993D01*
X1118133Y224559D01*
X1118101Y223804D01*
X1118015Y223652D01*
X1116654Y224437D01*
X1116742Y224588D01*
G37*
G36*
G01X1130538Y227136D02*
X1129868Y227486D01*
Y228356D01*
X1130538Y228706D01*
X1130713D01*
Y227136D01*
X1130538D01*
G37*
G36*
G01Y223236D02*
X1129868Y223586D01*
Y224456D01*
X1130538Y224806D01*
X1130713D01*
Y223236D01*
X1130538D01*
G37*
G36*
G01Y219336D02*
X1129868Y219686D01*
Y220556D01*
X1130538Y220906D01*
X1130713D01*
Y219336D01*
X1130538D01*
G37*
G36*
G01X1132162Y226707D02*
X1132832Y226357D01*
Y225487D01*
X1132162Y225137D01*
X1131987D01*
Y226707D01*
X1132162D01*
G37*
G36*
G01Y222807D02*
X1132832Y222457D01*
Y221587D01*
X1132162Y221237D01*
X1131987D01*
Y222807D01*
X1132162D01*
G37*
G36*
G01X1126882Y234337D02*
X1127520Y234742D01*
X1128273Y234307D01*
X1128241Y233552D01*
X1128154Y233400D01*
X1126794Y234186D01*
X1126882Y234337D01*
G37*
G36*
G01X1125402Y222807D02*
X1126072Y222457D01*
Y221587D01*
X1125402Y221237D01*
X1125227D01*
Y222807D01*
X1125402D01*
G37*
G36*
G01X1120122Y230438D02*
X1120760Y230843D01*
X1121513Y230408D01*
X1121481Y229653D01*
X1121394Y229502D01*
X1120034Y230287D01*
X1120122Y230438D01*
G37*
G36*
G01X1122023Y240417D02*
X1122693Y240067D01*
Y239197D01*
X1122023Y238847D01*
X1121848D01*
Y240417D01*
X1122023D01*
G37*
G36*
G01Y236506D02*
X1122693Y236156D01*
Y235286D01*
X1122023Y234936D01*
X1121848D01*
Y236506D01*
X1122023D01*
G37*
G36*
G01X1128782Y220906D02*
X1129452Y220556D01*
Y219686D01*
X1128782Y219336D01*
X1128607D01*
Y220906D01*
X1128782D01*
G37*
G36*
G01Y224806D02*
X1129452Y224456D01*
Y223586D01*
X1128782Y223236D01*
X1128607D01*
Y224806D01*
X1128782D01*
G37*
G36*
G01X1123778Y219336D02*
X1123108Y219686D01*
Y220556D01*
X1123778Y220906D01*
X1123953D01*
Y219336D01*
X1123778D01*
G37*
G36*
G01X1122290Y227313D02*
X1121652Y226908D01*
X1120899Y227343D01*
X1120931Y228098D01*
X1121018Y228250D01*
X1122378Y227464D01*
X1122290Y227313D01*
G37*
G36*
G01X1123778Y223236D02*
X1123108Y223586D01*
Y224456D01*
X1123778Y224806D01*
X1123953D01*
Y223236D01*
X1123778D01*
G37*
G36*
G01X1125687Y229251D02*
X1125049Y228846D01*
X1124296Y229281D01*
X1124328Y230036D01*
X1124415Y230188D01*
X1125775Y229402D01*
X1125687Y229251D01*
G37*
G36*
G01X1120398Y236826D02*
X1119728Y237176D01*
Y238046D01*
X1120398Y238396D01*
X1120573D01*
Y236826D01*
X1120398D01*
G37*
G36*
G01X1127158Y221237D02*
X1126488Y221587D01*
Y222457D01*
X1127158Y222807D01*
X1127333D01*
Y221237D01*
X1127158D01*
G37*
G36*
G01Y225137D02*
X1126488Y225487D01*
Y226357D01*
X1127158Y226707D01*
X1127333D01*
Y225137D01*
X1127158D01*
G37*
G36*
G01X1096235Y236134D02*
X1096974Y236296D01*
X1097533Y235630D01*
X1097245Y234931D01*
X1097111Y234819D01*
X1096101Y236021D01*
X1096235Y236134D01*
G37*
G36*
G01X1106879Y221237D02*
X1106209Y221587D01*
Y222457D01*
X1106879Y222807D01*
X1107054D01*
Y221237D01*
X1106879D01*
G37*
G36*
G01Y225137D02*
X1106209Y225487D01*
Y226357D01*
X1106879Y226707D01*
X1107054D01*
Y225137D01*
X1106879D01*
G37*
G36*
G01Y229062D02*
X1106209Y229412D01*
Y230282D01*
X1106879Y230632D01*
X1107054D01*
Y229062D01*
X1106879D01*
G37*
G36*
G01X1108503Y220906D02*
X1109173Y220556D01*
Y219686D01*
X1108503Y219336D01*
X1108328D01*
Y220906D01*
X1108503D01*
G37*
G36*
G01Y224806D02*
X1109173Y224456D01*
Y223586D01*
X1108503Y223236D01*
X1108328D01*
Y224806D01*
X1108503D01*
G37*
G36*
G01Y228706D02*
X1109173Y228356D01*
Y227486D01*
X1108503Y227136D01*
X1108328D01*
Y228706D01*
X1108503D01*
G37*
G36*
G01Y232557D02*
X1109173Y232207D01*
Y231337D01*
X1108503Y230987D01*
X1108328D01*
Y232557D01*
X1108503D01*
G37*
G36*
G01X1103499Y219336D02*
X1102829Y219686D01*
Y220556D01*
X1103499Y220906D01*
X1103674D01*
Y219336D01*
X1103499D01*
G37*
G36*
G01Y223236D02*
X1102829Y223586D01*
Y224456D01*
X1103499Y224806D01*
X1103674D01*
Y223236D01*
X1103499D01*
G37*
G36*
G01Y227136D02*
X1102829Y227486D01*
Y228356D01*
X1103499Y228706D01*
X1103674D01*
Y227136D01*
X1103499D01*
G37*
G36*
G01X1105123Y222807D02*
X1105793Y222457D01*
Y221587D01*
X1105123Y221237D01*
X1104948D01*
Y222807D01*
X1105123D01*
G37*
G36*
G01Y226707D02*
X1105793Y226357D01*
Y225487D01*
X1105123Y225137D01*
X1104948D01*
Y226707D01*
X1105123D01*
G37*
G36*
G01Y230632D02*
X1105793Y230282D01*
Y229412D01*
X1105123Y229062D01*
X1104948D01*
Y230632D01*
X1105123D01*
G37*
G36*
G01Y234556D02*
X1105793Y234206D01*
Y233336D01*
X1105123Y232986D01*
X1104948D01*
Y234556D01*
X1105123D01*
G37*
G36*
G01X1098363Y226707D02*
X1099033Y226357D01*
Y225487D01*
X1098363Y225137D01*
X1098188D01*
Y226707D01*
X1098363D01*
G37*
G36*
G01Y222807D02*
X1099033Y222457D01*
Y221587D01*
X1098363Y221237D01*
X1098188D01*
Y222807D01*
X1098363D01*
G37*
G36*
G01X1101743Y232557D02*
X1102413Y232207D01*
Y231337D01*
X1101743Y230987D01*
X1101568D01*
Y232557D01*
X1101743D01*
G37*
G36*
G01Y228706D02*
X1102413Y228356D01*
Y227486D01*
X1101743Y227136D01*
X1101568D01*
Y228706D01*
X1101743D01*
G37*
G36*
G01Y224806D02*
X1102413Y224456D01*
Y223586D01*
X1101743Y223236D01*
X1101568D01*
Y224806D01*
X1101743D01*
G37*
G36*
G01Y220906D02*
X1102413Y220556D01*
Y219686D01*
X1101743Y219336D01*
X1101568D01*
Y220906D01*
X1101743D01*
G37*
G36*
G01Y236481D02*
X1102413Y236131D01*
Y235261D01*
X1101743Y234911D01*
X1101568D01*
Y236481D01*
X1101743D01*
G37*
G36*
G01X1096739Y227136D02*
X1096069Y227486D01*
Y228356D01*
X1096739Y228706D01*
X1096914D01*
Y227136D01*
X1096739D01*
G37*
G36*
G01Y223236D02*
X1096069Y223586D01*
Y224456D01*
X1096739Y224806D01*
X1096914D01*
Y223236D01*
X1096739D01*
G37*
G36*
G01Y219336D02*
X1096069Y219686D01*
Y220556D01*
X1096739Y220906D01*
X1096914D01*
Y219336D01*
X1096739D01*
G37*
G36*
G01X1100119Y229062D02*
X1099449Y229412D01*
Y230282D01*
X1100119Y230632D01*
X1100294D01*
Y229062D01*
X1100119D01*
G37*
G36*
G01Y225137D02*
X1099449Y225487D01*
Y226357D01*
X1100119Y226707D01*
X1100294D01*
Y225137D01*
X1100119D01*
G37*
G36*
G01Y221237D02*
X1099449Y221587D01*
Y222457D01*
X1100119Y222807D01*
X1100294D01*
Y221237D01*
X1100119D01*
G37*
G36*
G01Y232962D02*
X1099449Y233312D01*
Y234182D01*
X1100119Y234532D01*
X1100294D01*
Y232962D01*
X1100119D01*
G37*
G36*
G01Y236837D02*
X1099449Y237187D01*
Y238057D01*
X1100119Y238407D01*
X1100294D01*
Y236837D01*
X1100119D01*
G37*
G36*
G01X1190200Y207200D02*
X1189338Y208062D01*
X1186660D01*
G02X1186260Y208448I0J400D01*
G03X1183458I-1401J-51D01*
G02X1183058Y208062I-400J14D01*
G01X1181238D01*
X1181031Y208269D01*
G02X1181351Y208950I283J283D01*
G03X1180083Y210218I128J1396D01*
G02X1179402Y209898I-398J-37D01*
G01X1178798Y210502D01*
G02X1178863Y211120I283J283D01*
G03X1176699Y212377I-764J1176D01*
G02X1176300Y212000I-399J23D01*
G01X1173616D01*
X1172371Y213245D01*
X1172368Y213248D01*
G03X1172291Y213325I-1029J-952D01*
G01X1172288Y213328D01*
X1169600Y216016D01*
Y218890D01*
G02X1170297Y219158I400J0D01*
G03Y221034I1042J938D01*
G02X1169600Y221302I-297J268D01*
G01Y222790D01*
G02X1170297Y223058I400J0D01*
G03Y224934I1042J938D01*
G02X1169600Y225202I-297J268D01*
G01Y226690D01*
G02X1170297Y226958I400J0D01*
G03Y228834I1042J938D01*
G02X1169600Y229102I-297J268D01*
G01Y230591D01*
G02X1170297Y230859I400J0D01*
G03Y232735I1042J938D01*
G02X1169600Y233003I-297J268D01*
G01Y234490D01*
G02X1170297Y234758I400J0D01*
G03Y236634I1042J938D01*
G02X1169600Y236902I-297J268D01*
G01Y238390D01*
G02X1170297Y238658I400J0D01*
G03Y240534I1042J938D01*
G02X1169600Y240802I-297J268D01*
G01Y242290D01*
G02X1170297Y242558I400J0D01*
G03Y244434I1042J938D01*
G02X1169600Y244702I-297J268D01*
G01Y246190D01*
G02X1170297Y246458I400J0D01*
G03Y248334I1042J938D01*
G02X1169600Y248602I-297J268D01*
G01Y250090D01*
G02X1170297Y250358I400J0D01*
G03Y252234I1042J938D01*
G02X1169600Y252502I-297J268D01*
G01Y253990D01*
G02X1170297Y254258I400J0D01*
G03Y256134I1042J938D01*
G02X1169600Y256402I-297J268D01*
G01Y257890D01*
G02X1170297Y258158I400J0D01*
G03Y260034I1042J938D01*
G02X1169600Y260302I-297J268D01*
G01Y261790D01*
G02X1170297Y262058I400J0D01*
G03Y263934I1042J938D01*
G02X1169600Y264202I-297J268D01*
G01Y265112D01*
X1169694Y265166D01*
X1169860Y265787D01*
G03X1169882Y265917I-653J177D01*
G02X1170239Y266027I200J-13D01*
G03X1172565Y267576I1100J869D01*
G02X1172915Y268170I350J194D01*
G01X1173492D01*
G03Y269524I1227J677D01*
G01X1172916D01*
G02X1172566Y270118I0J400D01*
G03X1170133Y271512I-1227J678D01*
G02X1169574Y271379I-344J204D01*
G03X1169347Y271510I-1613J-2533D01*
G02X1169183Y272061I184J355D01*
G03X1167976Y274149I-1223J686D01*
G02X1167581Y274566I4J400D01*
G03Y274827I-3001J131D01*
G02X1167976Y275244I399J17D01*
G03X1167975Y278048I-16J1402D01*
G02X1167580Y278465I5J400D01*
G03Y278728I-3000J131D01*
G02X1167975Y279145I400J17D01*
G03X1167976Y281949I-15J1402D01*
G02X1167581Y282366I4J400D01*
G03X1167580Y282628I-3001J120D01*
G02X1167976Y283045I400J17D01*
G03Y285849I-16J1402D01*
G02X1167581Y286266I4J400D01*
G03X1167580Y286528I-3001J120D01*
G02X1167976Y286945I400J17D01*
G03Y289749I-16J1402D01*
G02X1167581Y290166I4J400D01*
G03X1167580Y290428I-3001J120D01*
G02X1167976Y290845I400J17D01*
G03Y293649I-16J1402D01*
G02X1167581Y294066I4J400D01*
G03X1167580Y294328I-3001J120D01*
G02X1167976Y294745I400J17D01*
G03Y297549I-16J1402D01*
G02X1167581Y297966I4J400D01*
G03X1167580Y298228I-3001J120D01*
G02X1167976Y298645I400J17D01*
G03X1166754Y300762I-16J1402D01*
G02X1166195Y300628I-344J203D01*
G03X1165967Y300760I-1617J-2531D01*
G02X1165803Y301310I185J355D01*
G03X1164596Y303398I-1223J686D01*
G02X1164200Y303815I4J400D01*
G03X1164201Y304077I-3000J142D01*
G02X1164596Y304494I399J17D01*
G03X1163713Y306998I-16J1402D01*
G01X1163659Y306955D01*
X1163343D01*
X1162716Y307583D01*
Y313845D01*
X1162232Y314330D01*
X1162049Y314513D01*
X1162190Y314655D01*
G03X1159994Y316362I-990J993D01*
G02X1159435Y316228I-344J203D01*
G03X1159207Y316360I-1617J-2531D01*
G02X1159043Y316910I185J355D01*
G03X1156754Y318506I-1223J686D01*
G02X1156167Y318483I-304J260D01*
G01X1155710Y318940D01*
X1155755Y319060D01*
G03X1154456Y320949I-1315J487D01*
G02X1154061Y321366I4J400D01*
G03Y321627I-3001J131D01*
G02X1154456Y322044I399J17D01*
G03X1153234Y324161I-16J1402D01*
G02X1152675Y324028I-344J204D01*
G03X1152447Y324160I-1617J-2531D01*
G02X1152283Y324710I185J355D01*
G03X1149854Y326111I-1223J686D01*
G02X1149295Y325978I-344J204D01*
G03X1149066Y326110I-1613J-2533D01*
G02X1148902Y326660I185J355D01*
G03X1146765Y328409I-1222J687D01*
G02X1146221Y328429I-261J303D01*
G01X1145670Y328980D01*
X1145685Y329081D01*
G03X1144034Y330673I-1385J215D01*
G01X1144016Y330669D01*
X1142960D01*
X1142323Y331306D01*
X1142316Y331378D01*
G03X1141051Y332643I-1396J-131D01*
G01X1140979Y332650D01*
X1140565Y333064D01*
G02X1140864Y333746I283J282D01*
G03X1140018Y336221I56J1401D01*
G02X1139361Y336527I-257J306D01*
G01Y337667D01*
G02X1140018Y337973I400J0D01*
G03Y340121I902J1074D01*
G02X1139361Y340427I-257J306D01*
G01Y341567D01*
G02X1140018Y341873I400J0D01*
G03Y344021I902J1074D01*
G02X1139361Y344327I-257J306D01*
G01Y345467D01*
G02X1140018Y345773I400J0D01*
G03Y347921I902J1074D01*
G02X1139361Y348227I-257J306D01*
G01Y349367D01*
G02X1140018Y349673I400J0D01*
G03Y351821I902J1074D01*
G02X1139361Y352127I-257J306D01*
G01Y353267D01*
G02X1140018Y353573I400J0D01*
G03X1139731Y355389I902J1073D01*
G01X1139672Y355295D01*
X1139361D01*
Y355896D01*
X1140370Y356905D01*
Y356920D01*
X1140623Y357173D01*
X1140722Y357159D01*
G03X1142308Y358745I198J1388D01*
G01X1142294Y358844D01*
X1142853Y359403D01*
G02X1143394Y359426I283J-283D01*
G03X1145344Y361432I906J1070D01*
G01X1145218Y361573D01*
X1145719Y362074D01*
G02X1146374Y361936I282J-283D01*
G03X1147766Y363846I1306J511D01*
G01X1147691Y363851D01*
X1147496Y364046D01*
X1147940Y364490D01*
X1149649D01*
X1149661Y364303D01*
G03X1152459I1399J93D01*
G01X1152471Y364490D01*
X1156409D01*
X1156421Y364303D01*
G03X1159219I1399J93D01*
G01X1159231Y364490D01*
X1162174D01*
G03X1163235Y363999I2406J3806D01*
G03X1164911Y363034I1345J397D01*
G03X1166616Y362049I3050J3312D01*
G03X1168289Y361084I1344J398D01*
G03X1169994Y360099I3050J3312D01*
G03X1171670Y359134I1345J397D01*
G03X1173375Y358149I3050J3312D01*
G03X1174650Y357147I1344J398D01*
G01X1174727Y357143D01*
X1175060Y356810D01*
X1175512D01*
X1175563Y356775D01*
G03X1176754Y356199I2535J3721D01*
G03X1179214Y355745I1345J397D01*
G02X1179814Y355786I318J-242D01*
G01X1180255Y355345D01*
X1180199Y355219D01*
G03X1182051Y353367I1280J-572D01*
G01X1182177Y353423D01*
X1183315Y352285D01*
Y350330D01*
G03X1183172Y350171I1545J-1533D01*
G02X1182825Y350353I-155J126D01*
G03X1182123Y349502I-1345J395D01*
G02X1182703Y349092I184J-356D01*
G03X1182702Y348502I2156J-299D01*
G02X1182123Y348093I-396J-54D01*
G03Y345602I-644J-1245D01*
G02X1182703Y345192I184J-356D01*
G03X1182682Y344896I2156J-302D01*
G01Y344560D01*
G02X1182104Y344202I-400J0D01*
G03Y341692I-625J-1255D01*
G02X1182682Y341334I178J-358D01*
G01Y340996D01*
G03X1182702Y340702I2177J0D01*
G02X1182123Y340293I-396J-54D01*
G03X1182879Y338980I-644J-1245D01*
G02X1183524Y339277I400J-19D01*
G03X1184035Y338981I1336J1718D01*
G02X1184100Y338275I-151J-370D01*
G03X1185762Y336024I758J-1179D01*
G02X1186420Y335718I258J-306D01*
G01Y332442D01*
G03X1186083Y330951I1819J-1195D01*
G02X1185503Y330541I-396J-54D01*
G03Y328050I-644J-1245D01*
G02X1186082Y327641I183J-355D01*
G03X1186062Y327347I2157J-294D01*
G01Y323446D01*
G03X1186083Y323151I2177J7D01*
G02X1185503Y322742I-396J-54D01*
G03X1184100Y320317I-644J-1246D01*
G02X1184035Y319611I-216J-336D01*
G03X1183524Y319315I825J-2014D01*
G02X1182879Y319612I-245J316D01*
G03X1182123Y318302I-1400J-65D01*
G02X1182703Y317892I184J-356D01*
G03X1182682Y317596I2156J-302D01*
G01Y317260D01*
G02X1182104Y316902I-400J0D01*
G03Y314392I-625J-1255D01*
G02X1182682Y314034I178J-358D01*
G01Y313696D01*
G03X1182702Y313402I2177J0D01*
G02X1182123Y312993I-396J-54D01*
G03X1182879Y311680I-644J-1245D01*
G02X1183524Y311977I400J-19D01*
G03X1184034Y311682I1335J1719D01*
G02X1184099Y310975I-151J-370D01*
G03X1184084Y308629I760J-1178D01*
G02X1184062Y307949I-221J-333D01*
G01X1183771Y307781D01*
G03X1183524Y307615I1088J-1885D01*
G02X1182879Y307912I-245J316D01*
G03X1182123Y306602I-1400J-65D01*
G02X1182703Y306192I184J-356D01*
G03X1182702Y305602I2156J-299D01*
G02X1182123Y305193I-396J-54D01*
G03X1182879Y303880I-644J-1245D01*
G02X1183524Y304177I400J-19D01*
G03X1184035Y303881I1336J1718D01*
G02X1184100Y303175I-151J-370D01*
G03X1183645Y301295I759J-1179D01*
G01X1183722Y301162D01*
X1183286Y300726D01*
G02X1182665Y300795I-283J283D01*
G03X1180731Y298861I-1186J-748D01*
G02X1180800Y298240I-214J-338D01*
G01X1180763Y298203D01*
X1180722Y298188D01*
G03X1180144Y297866I758J-2040D01*
G02X1179499Y298163I-245J316D01*
G03X1178743Y296850I-1400J-68D01*
G02X1179322Y296441I183J-355D01*
G03X1179323Y295851I2157J-291D01*
G02X1178743Y295441I-396J-54D01*
G03X1179499Y294131I-644J-1245D01*
G02X1180144Y294428I400J-19D01*
G03X1180643Y294137I1336J1718D01*
G01X1180680Y294122D01*
X1180769Y294033D01*
G02X1180706Y293417I-283J-282D01*
G03X1182649Y291474I773J-1170D01*
G02X1183265Y291537I334J-220D01*
G01X1183701Y291101D01*
X1183629Y290969D01*
G03X1185532Y289066I1230J-673D01*
G01X1185664Y289138D01*
X1185957Y288845D01*
X1186440D01*
G02X1186839Y288423I0J-400D01*
G03X1189639I1400J-76D01*
G02X1190038Y288845I399J22D01*
G01X1193200D01*
G02X1193599Y288423I0J-400D01*
G03X1196171Y287578I1400J-76D01*
G01X1196756D01*
G02X1197116Y287004I0J-400D01*
G03X1199642I1263J-608D01*
G02X1200002Y287578I360J174D01*
G01X1200587D01*
G03X1202218Y287022I1172J769D01*
G01X1202337Y287063D01*
X1204897Y284503D01*
G02X1204731Y283837I-283J-283D01*
G03X1206480Y282088I408J-1341D01*
G02X1207146Y282254I383J-117D01*
G01X1207737Y281663D01*
Y281441D01*
X1207697Y281388D01*
G03X1207737Y279655I1122J-841D01*
G01Y273911D01*
G03Y271583I782J-1164D01*
G01Y270011D01*
G03Y267683I782J-1164D01*
G01Y266111D01*
G03Y263783I782J-1164D01*
G01Y258649D01*
X1207909Y258477D01*
X1207754Y258322D01*
X1207738Y258311D01*
G03X1209569Y256218I781J-1164D01*
G02X1210151Y256235I299J-266D01*
G01X1210900Y255486D01*
Y251825D01*
X1210887Y251791D01*
G03Y250801I1312J-495D01*
G01X1210900Y250767D01*
Y244025D01*
X1210887Y243991D01*
G03Y243001I1312J-495D01*
G01X1210900Y242967D01*
Y240125D01*
X1210887Y240091D01*
G03Y239101I1312J-495D01*
G01X1210900Y239067D01*
Y232326D01*
X1210887Y232292D01*
G03Y231302I1312J-495D01*
G01X1210900Y231268D01*
Y228425D01*
X1210887Y228391D01*
G03Y227401I1312J-495D01*
G01X1210900Y227367D01*
Y224525D01*
X1210887Y224491D01*
G03Y223501I1312J-495D01*
G01X1210900Y223467D01*
Y219200D01*
X1198900Y207200D01*
X1190200D01*
G37*
G36*
G01X1121520Y387011D02*
X1120850Y387361D01*
Y388231D01*
X1121520Y388581D01*
X1121695D01*
Y387011D01*
X1121520D01*
G37*
G36*
G01Y379211D02*
X1120850Y379561D01*
Y380431D01*
X1121520Y380781D01*
X1121695D01*
Y379211D01*
X1121520D01*
G37*
G36*
G01Y383111D02*
X1120850Y383461D01*
Y384331D01*
X1121520Y384681D01*
X1121695D01*
Y383111D01*
X1121520D01*
G37*
G36*
G01X1121519Y402636D02*
X1120849Y402986D01*
Y403856D01*
X1121519Y404206D01*
X1121694D01*
Y402636D01*
X1121519D01*
G37*
G36*
G01Y390936D02*
X1120849Y391286D01*
Y392156D01*
X1121519Y392506D01*
X1121694D01*
Y390936D01*
X1121519D01*
G37*
G36*
G01Y394836D02*
X1120849Y395186D01*
Y396056D01*
X1121519Y396406D01*
X1121694D01*
Y394836D01*
X1121519D01*
G37*
G36*
G01Y398736D02*
X1120849Y399086D01*
Y399956D01*
X1121519Y400306D01*
X1121694D01*
Y398736D01*
X1121519D01*
G37*
G36*
G01X1122149Y375018D02*
X1122904Y375050D01*
X1123339Y374296D01*
X1122934Y373658D01*
X1122782Y373571D01*
X1121997Y374930D01*
X1122149Y375018D01*
G37*
G36*
G01X1123144Y390531D02*
X1123814Y390181D01*
Y389311D01*
X1123144Y388961D01*
X1122969D01*
Y390531D01*
X1123144D01*
G37*
G36*
G01Y386631D02*
X1123814Y386281D01*
Y385411D01*
X1123144Y385061D01*
X1122969D01*
Y386631D01*
X1123144D01*
G37*
G36*
G01Y382731D02*
X1123814Y382381D01*
Y381511D01*
X1123144Y381161D01*
X1122969D01*
Y382731D01*
X1123144D01*
G37*
G36*
G01X1123143Y402207D02*
X1123813Y401857D01*
Y400987D01*
X1123143Y400637D01*
X1122968D01*
Y402207D01*
X1123143D01*
G37*
G36*
G01Y398307D02*
X1123813Y397957D01*
Y397087D01*
X1123143Y396737D01*
X1122968D01*
Y398307D01*
X1123143D01*
G37*
G36*
G01Y394407D02*
X1123813Y394057D01*
Y393187D01*
X1123143Y392837D01*
X1122968D01*
Y394407D01*
X1123143D01*
G37*
G36*
G01X1135038Y387036D02*
X1134368Y387386D01*
Y388256D01*
X1135038Y388606D01*
X1135213D01*
Y387036D01*
X1135038D01*
G37*
G36*
G01X1132531Y373001D02*
X1133201Y372651D01*
Y371781D01*
X1132531Y371431D01*
X1132356D01*
Y373001D01*
X1132531D01*
G37*
G36*
G01Y369101D02*
X1133201Y368751D01*
Y367881D01*
X1132531Y367531D01*
X1132356D01*
Y369101D01*
X1132531D01*
G37*
G36*
G01X1135038Y383136D02*
X1134368Y383486D01*
Y384356D01*
X1135038Y384706D01*
X1135213D01*
Y383136D01*
X1135038D01*
G37*
G36*
G01Y379236D02*
X1134368Y379586D01*
Y380456D01*
X1135038Y380806D01*
X1135213D01*
Y379236D01*
X1135038D01*
G37*
G36*
G01Y390936D02*
X1134368Y391286D01*
Y392156D01*
X1135038Y392506D01*
X1135213D01*
Y390936D01*
X1135038D01*
G37*
G36*
G01Y394836D02*
X1134368Y395186D01*
Y396056D01*
X1135038Y396406D01*
X1135213D01*
Y394836D01*
X1135038D01*
G37*
G36*
G01X1135573Y397349D02*
X1135541Y398104D01*
X1136294Y398539D01*
X1136932Y398134D01*
X1137019Y397983D01*
X1135659Y397198D01*
X1135573Y397349D01*
G37*
G36*
G01X1138418Y400637D02*
X1137748Y400987D01*
Y401857D01*
X1138418Y402207D01*
X1138593D01*
Y400637D01*
X1138418D01*
G37*
G36*
G01X1135950Y376138D02*
X1136286Y375460D01*
X1135774Y374757D01*
X1135026Y374869D01*
X1134885Y374972D01*
X1135809Y376241D01*
X1135950Y376138D01*
G37*
G36*
G01X1136662Y390507D02*
X1137332Y390157D01*
Y389287D01*
X1136662Y388937D01*
X1136487D01*
Y390507D01*
X1136662D01*
G37*
G36*
G01Y378807D02*
X1137332Y378457D01*
Y377587D01*
X1136662Y377237D01*
X1136487D01*
Y378807D01*
X1136662D01*
G37*
G36*
G01Y386607D02*
X1137332Y386257D01*
Y385387D01*
X1136662Y385037D01*
X1136487D01*
Y386607D01*
X1136662D01*
G37*
G36*
G01Y382707D02*
X1137332Y382357D01*
Y381487D01*
X1136662Y381137D01*
X1136487D01*
Y382707D01*
X1136662D01*
G37*
G36*
G01X1140041Y400324D02*
X1140711Y399974D01*
Y399104D01*
X1140041Y398754D01*
X1139866Y398753D01*
Y400324D01*
X1140041D01*
G37*
G36*
G01X1140042Y404206D02*
X1140712Y403856D01*
Y402986D01*
X1140042Y402636D01*
X1139867D01*
Y404206D01*
X1140042D01*
G37*
G36*
G01X1139507Y397744D02*
X1139539Y396989D01*
X1138786Y396554D01*
X1138148Y396959D01*
X1138060Y397110D01*
X1139420Y397896D01*
X1139507Y397744D01*
G37*
G36*
G01X1136662Y394432D02*
X1137332Y394082D01*
Y393212D01*
X1136662Y392862D01*
X1136487D01*
Y394432D01*
X1136662D01*
G37*
G36*
G01X1118140Y388961D02*
X1117470Y389311D01*
Y390181D01*
X1118140Y390531D01*
X1118315D01*
Y388961D01*
X1118140D01*
G37*
G36*
G01Y377261D02*
X1117470Y377611D01*
Y378481D01*
X1118140Y378831D01*
X1118315D01*
Y377261D01*
X1118140D01*
G37*
G36*
G01Y381161D02*
X1117470Y381511D01*
Y382381D01*
X1118140Y382731D01*
X1118315D01*
Y381161D01*
X1118140D01*
G37*
G36*
G01Y385061D02*
X1117470Y385411D01*
Y386281D01*
X1118140Y386631D01*
X1118315D01*
Y385061D01*
X1118140D01*
G37*
G36*
G01X1118139Y392837D02*
X1117469Y393187D01*
Y394057D01*
X1118139Y394407D01*
X1118314D01*
Y392837D01*
X1118139D01*
G37*
G36*
G01Y396737D02*
X1117469Y397087D01*
Y397957D01*
X1118139Y398307D01*
X1118314D01*
Y396737D01*
X1118139D01*
G37*
G36*
G01Y400637D02*
X1117469Y400987D01*
Y401857D01*
X1118139Y402207D01*
X1118314D01*
Y400637D01*
X1118139D01*
G37*
G36*
G01X1119764Y388581D02*
X1120434Y388231D01*
Y387361D01*
X1119764Y387011D01*
X1119589D01*
Y388581D01*
X1119764D01*
G37*
G36*
G01Y384681D02*
X1120434Y384331D01*
Y383461D01*
X1119764Y383111D01*
X1119589D01*
Y384681D01*
X1119764D01*
G37*
G36*
G01Y380781D02*
X1120434Y380431D01*
Y379561D01*
X1119764Y379211D01*
X1119589D01*
Y380781D01*
X1119764D01*
G37*
G36*
G01X1119763Y404206D02*
X1120433Y403856D01*
Y402986D01*
X1119763Y402636D01*
X1119588D01*
Y404206D01*
X1119763D01*
G37*
G36*
G01Y400306D02*
X1120433Y399956D01*
Y399086D01*
X1119763Y398736D01*
X1119588D01*
Y400306D01*
X1119763D01*
G37*
G36*
G01Y396406D02*
X1120433Y396056D01*
Y395186D01*
X1119763Y394836D01*
X1119588D01*
Y396406D01*
X1119763D01*
G37*
G36*
G01Y392506D02*
X1120433Y392156D01*
Y391286D01*
X1119763Y390936D01*
X1119588D01*
Y392506D01*
X1119763D01*
G37*
G36*
G01X1131659Y388961D02*
X1130989Y389311D01*
Y390181D01*
X1131659Y390531D01*
X1131834D01*
Y388961D01*
X1131659D01*
G37*
G36*
G01X1130086Y369515D02*
X1129331Y369563D01*
X1128978Y370358D01*
X1129449Y370950D01*
X1129609Y371020D01*
X1130246Y369585D01*
X1130086Y369515D01*
G37*
G36*
G01X1129861Y374970D02*
X1130532Y374622D01*
X1130535Y373752D01*
X1129866Y373400D01*
X1129691D01*
X1129686Y374970D01*
X1129861D01*
G37*
G36*
G01X1131658Y381161D02*
X1130988Y381511D01*
Y382381D01*
X1131658Y382731D01*
X1131833D01*
Y381161D01*
X1131658D01*
G37*
G36*
G01Y385061D02*
X1130988Y385411D01*
Y386281D01*
X1131658Y386631D01*
X1131833D01*
Y385061D01*
X1131658D01*
G37*
G36*
G01Y396737D02*
X1130988Y397087D01*
Y397957D01*
X1131658Y398307D01*
X1131833D01*
Y396737D01*
X1131658D01*
G37*
G36*
G01Y392837D02*
X1130988Y393187D01*
Y394057D01*
X1131658Y394407D01*
X1131833D01*
Y392837D01*
X1131658D01*
G37*
G36*
G01X1132200Y399304D02*
X1132168Y400059D01*
X1132921Y400493D01*
X1133559Y400088D01*
X1133647Y399937D01*
X1132287Y399151D01*
X1132200Y399304D01*
G37*
G36*
G01X1135038Y402636D02*
X1134368Y402986D01*
Y403856D01*
X1135038Y404206D01*
X1135213D01*
Y402636D01*
X1135038D01*
G37*
G36*
G01X1133282Y388581D02*
X1133952Y388231D01*
Y387361D01*
X1133282Y387011D01*
X1133107D01*
Y388581D01*
X1133282D01*
G37*
G36*
G01X1132712Y377901D02*
X1132973Y377191D01*
X1132389Y376547D01*
X1131657Y376738D01*
X1131528Y376855D01*
X1132582Y378018D01*
X1132712Y377901D01*
G37*
G36*
G01X1133282Y384681D02*
X1133952Y384331D01*
Y383461D01*
X1133282Y383111D01*
X1133107D01*
Y384681D01*
X1133282D01*
G37*
G36*
G01X1133281Y380781D02*
X1133951Y380431D01*
Y379561D01*
X1133281Y379211D01*
X1133106D01*
Y380781D01*
X1133281D01*
G37*
G36*
G01X1136106Y399681D02*
X1136138Y398926D01*
X1135384Y398492D01*
X1134747Y398897D01*
X1134658Y399048D01*
X1136018Y399834D01*
X1136106Y399681D01*
G37*
G36*
G01X1133282Y396406D02*
X1133952Y396056D01*
Y395186D01*
X1133282Y394836D01*
X1133107D01*
Y396406D01*
X1133282D01*
G37*
G36*
G01Y392506D02*
X1133952Y392156D01*
Y391286D01*
X1133282Y390936D01*
X1133107D01*
Y392506D01*
X1133282D01*
G37*
G36*
G01X1136662Y402207D02*
X1137332Y401857D01*
Y400987D01*
X1136662Y400637D01*
X1136487D01*
Y402207D01*
X1136662D01*
G37*
G36*
G01X1126522Y388581D02*
X1127192Y388231D01*
Y387361D01*
X1126522Y387011D01*
X1126347D01*
Y388581D01*
X1126522D01*
G37*
G36*
G01Y372981D02*
X1127192Y372631D01*
Y371761D01*
X1126522Y371411D01*
X1126347D01*
Y372981D01*
X1126522D01*
G37*
G36*
G01Y376881D02*
X1127192Y376531D01*
Y375661D01*
X1126522Y375311D01*
X1126347D01*
Y376881D01*
X1126522D01*
G37*
G36*
G01Y384681D02*
X1127192Y384331D01*
Y383461D01*
X1126522Y383111D01*
X1126347D01*
Y384681D01*
X1126522D01*
G37*
G36*
G01Y380781D02*
X1127192Y380431D01*
Y379561D01*
X1126522Y379211D01*
X1126347D01*
Y380781D01*
X1126522D01*
G37*
G36*
G01X1126523Y400317D02*
X1127193Y399967D01*
Y399097D01*
X1126523Y398747D01*
X1126348D01*
Y400317D01*
X1126523D01*
G37*
G36*
G01Y396417D02*
X1127193Y396067D01*
Y395197D01*
X1126523Y394847D01*
X1126348D01*
Y396417D01*
X1126523D01*
G37*
G36*
G01Y392517D02*
X1127193Y392167D01*
Y391297D01*
X1126523Y390947D01*
X1126348D01*
Y392517D01*
X1126523D01*
G37*
G36*
G01X1129346Y403581D02*
X1129378Y402826D01*
X1128624Y402392D01*
X1127987Y402797D01*
X1127899Y402948D01*
X1129259Y403733D01*
X1129346Y403581D01*
G37*
G36*
G01X1128278Y387013D02*
X1127608Y387363D01*
Y388233D01*
X1128278Y388583D01*
X1128453D01*
Y387013D01*
X1128278D01*
G37*
G36*
G01Y383113D02*
X1127608Y383463D01*
Y384333D01*
X1128278Y384683D01*
X1128453D01*
Y383113D01*
X1128278D01*
G37*
G36*
G01Y398736D02*
X1127608Y399086D01*
Y399956D01*
X1128278Y400306D01*
X1128453D01*
Y398736D01*
X1128278D01*
G37*
G36*
G01Y390936D02*
X1127608Y391286D01*
Y392156D01*
X1128278Y392506D01*
X1128453D01*
Y390936D01*
X1128278D01*
G37*
G36*
G01Y394836D02*
X1127608Y395186D01*
Y396056D01*
X1128278Y396406D01*
X1128453D01*
Y394836D01*
X1128278D01*
G37*
G36*
G01X1128834Y401262D02*
X1128802Y402017D01*
X1129556Y402451D01*
X1130193Y402046D01*
X1130281Y401895D01*
X1128922Y401109D01*
X1128834Y401262D01*
G37*
G36*
G01X1124898Y388926D02*
X1124228Y389276D01*
Y390146D01*
X1124898Y390496D01*
X1125073D01*
Y388926D01*
X1124898D01*
G37*
G36*
G01Y377261D02*
X1124228Y377611D01*
Y378481D01*
X1124898Y378831D01*
X1125073D01*
Y377261D01*
X1124898D01*
G37*
G36*
G01Y373361D02*
X1124228Y373711D01*
Y374581D01*
X1124898Y374931D01*
X1125073D01*
Y373361D01*
X1124898D01*
G37*
G36*
G01Y385061D02*
X1124228Y385411D01*
Y386281D01*
X1124898Y386631D01*
X1125073D01*
Y385061D01*
X1124898D01*
G37*
G36*
G01Y381161D02*
X1124228Y381511D01*
Y382381D01*
X1124898Y382731D01*
X1125073D01*
Y381161D01*
X1124898D01*
G37*
G36*
G01Y400626D02*
X1124228Y400976D01*
Y401846D01*
X1124898Y402196D01*
X1125073D01*
Y400626D01*
X1124898D01*
G37*
G36*
G01Y396726D02*
X1124228Y397076D01*
Y397946D01*
X1124898Y398296D01*
X1125073D01*
Y396726D01*
X1124898D01*
G37*
G36*
G01Y392826D02*
X1124228Y393176D01*
Y394046D01*
X1124898Y394396D01*
X1125073D01*
Y392826D01*
X1124898D01*
G37*
G36*
G01X1129902Y390533D02*
X1130572Y390183D01*
Y389313D01*
X1129902Y388963D01*
X1129727D01*
Y390533D01*
X1129902D01*
G37*
G36*
G01Y386633D02*
X1130572Y386283D01*
Y385413D01*
X1129902Y385063D01*
X1129727D01*
Y386633D01*
X1129902D01*
G37*
G36*
G01Y382733D02*
X1130572Y382383D01*
Y381513D01*
X1129902Y381163D01*
X1129727D01*
Y382733D01*
X1129902D01*
G37*
G36*
G01Y394407D02*
X1130572Y394057D01*
Y393187D01*
X1129902Y392837D01*
X1129727D01*
Y394407D01*
X1129902D01*
G37*
G36*
G01X1133282Y404206D02*
X1133952Y403856D01*
Y402986D01*
X1133282Y402636D01*
X1133107D01*
Y404206D01*
X1133282D01*
G37*
G36*
G01X1132740Y401639D02*
X1132772Y400884D01*
X1132019Y400450D01*
X1131381Y400855D01*
X1131294Y401006D01*
X1132654Y401791D01*
X1132740Y401639D01*
G37*
G36*
G01X1129902Y398307D02*
X1130572Y397957D01*
Y397087D01*
X1129902Y396737D01*
X1129727D01*
Y398307D01*
X1129902D01*
G37*
G36*
G01X1101239Y387013D02*
X1100569Y387363D01*
Y388233D01*
X1101239Y388583D01*
X1101414D01*
Y387013D01*
X1101239D01*
G37*
G36*
G01Y375313D02*
X1100569Y375663D01*
Y376533D01*
X1101239Y376883D01*
X1101414D01*
Y375313D01*
X1101239D01*
G37*
G36*
G01Y379213D02*
X1100569Y379563D01*
Y380433D01*
X1101239Y380783D01*
X1101414D01*
Y379213D01*
X1101239D01*
G37*
G36*
G01Y383113D02*
X1100569Y383463D01*
Y384333D01*
X1101239Y384683D01*
X1101414D01*
Y383113D01*
X1101239D01*
G37*
G36*
G01Y390913D02*
X1100569Y391263D01*
Y392133D01*
X1101239Y392483D01*
X1101414D01*
Y390913D01*
X1101239D01*
G37*
G36*
G01Y394836D02*
X1100569Y395186D01*
Y396056D01*
X1101239Y396406D01*
X1101414D01*
Y394836D01*
X1101239D01*
G37*
G36*
G01Y398736D02*
X1100569Y399086D01*
Y399956D01*
X1101239Y400306D01*
X1101414D01*
Y398736D01*
X1101239D01*
G37*
G36*
G01Y402636D02*
X1100569Y402986D01*
Y403856D01*
X1101239Y404206D01*
X1101414D01*
Y402636D01*
X1101239D01*
G37*
G36*
G01X1102091Y374764D02*
X1102846Y374722D01*
X1103204Y373929D01*
X1102738Y373334D01*
X1102579Y373262D01*
X1101932Y374692D01*
X1102091Y374764D01*
G37*
G36*
G01X1102863Y390533D02*
X1103533Y390183D01*
Y389313D01*
X1102863Y388963D01*
X1102688D01*
Y390533D01*
X1102863D01*
G37*
G36*
G01Y386633D02*
X1103533Y386283D01*
Y385413D01*
X1102863Y385063D01*
X1102688D01*
Y386633D01*
X1102863D01*
G37*
G36*
G01Y382733D02*
X1103533Y382383D01*
Y381513D01*
X1102863Y381163D01*
X1102688D01*
Y382733D01*
X1102863D01*
G37*
G36*
G01Y402207D02*
X1103533Y401857D01*
Y400987D01*
X1102863Y400637D01*
X1102688D01*
Y402207D01*
X1102863D01*
G37*
G36*
G01Y398307D02*
X1103533Y397957D01*
Y397087D01*
X1102863Y396737D01*
X1102688D01*
Y398307D01*
X1102863D01*
G37*
G36*
G01Y394433D02*
X1103533Y394083D01*
Y393213D01*
X1102863Y392863D01*
X1102688D01*
Y394433D01*
X1102863D01*
G37*
G36*
G01X1114759Y387013D02*
X1114089Y387363D01*
Y388233D01*
X1114759Y388583D01*
X1114934D01*
Y387013D01*
X1114759D01*
G37*
G36*
G01X1111992Y374071D02*
X1111482Y374629D01*
X1111780Y375447D01*
X1112529Y375547D01*
X1112693Y375487D01*
X1112157Y374011D01*
X1111992Y374071D01*
G37*
G36*
G01X1114759Y379213D02*
X1114089Y379563D01*
Y380433D01*
X1114759Y380783D01*
X1114934D01*
Y379213D01*
X1114759D01*
G37*
G36*
G01Y383113D02*
X1114089Y383463D01*
Y384333D01*
X1114759Y384683D01*
X1114934D01*
Y383113D01*
X1114759D01*
G37*
G36*
G01Y390913D02*
X1114089Y391263D01*
Y392133D01*
X1114759Y392483D01*
X1114934D01*
Y390913D01*
X1114759D01*
G37*
G36*
G01Y394786D02*
X1114089Y395136D01*
Y396006D01*
X1114759Y396356D01*
X1114934D01*
Y394786D01*
X1114759D01*
G37*
G36*
G01Y398675D02*
X1114089Y399025D01*
Y399895D01*
X1114759Y400245D01*
X1114934D01*
Y398675D01*
X1114759D01*
G37*
G36*
G01Y402611D02*
X1114089Y402961D01*
Y403831D01*
X1114759Y404181D01*
X1114934D01*
Y402611D01*
X1114759D01*
G37*
G36*
G01X1116383Y390533D02*
X1117053Y390183D01*
Y389313D01*
X1116383Y388963D01*
X1116208D01*
Y390533D01*
X1116383D01*
G37*
G36*
G01Y378833D02*
X1117053Y378483D01*
Y377613D01*
X1116383Y377263D01*
X1116208D01*
Y378833D01*
X1116383D01*
G37*
G36*
G01Y386633D02*
X1117053Y386283D01*
Y385413D01*
X1116383Y385063D01*
X1116208D01*
Y386633D01*
X1116383D01*
G37*
G36*
G01Y382733D02*
X1117053Y382383D01*
Y381513D01*
X1116383Y381163D01*
X1116208D01*
Y382733D01*
X1116383D01*
G37*
G36*
G01Y402255D02*
X1117053Y401905D01*
Y401035D01*
X1116383Y400685D01*
X1116208D01*
Y402255D01*
X1116383D01*
G37*
G36*
G01Y398365D02*
X1117053Y398015D01*
Y397145D01*
X1116383Y396795D01*
X1116208D01*
Y398365D01*
X1116383D01*
G37*
G36*
G01Y394455D02*
X1117053Y394105D01*
Y393235D01*
X1116383Y392885D01*
X1116208D01*
Y394455D01*
X1116383D01*
G37*
G36*
G01X1097859Y388963D02*
X1097189Y389313D01*
Y390183D01*
X1097859Y390533D01*
X1098034D01*
Y388963D01*
X1097859D01*
G37*
G36*
G01Y373363D02*
X1097189Y373713D01*
Y374583D01*
X1097859Y374933D01*
X1098034D01*
Y373363D01*
X1097859D01*
G37*
G36*
G01Y377263D02*
X1097189Y377613D01*
Y378483D01*
X1097859Y378833D01*
X1098034D01*
Y377263D01*
X1097859D01*
G37*
G36*
G01Y381163D02*
X1097189Y381513D01*
Y382383D01*
X1097859Y382733D01*
X1098034D01*
Y381163D01*
X1097859D01*
G37*
G36*
G01Y385063D02*
X1097189Y385413D01*
Y386283D01*
X1097859Y386633D01*
X1098034D01*
Y385063D01*
X1097859D01*
G37*
G36*
G01Y392837D02*
X1097189Y393187D01*
Y394057D01*
X1097859Y394407D01*
X1098034D01*
Y392837D01*
X1097859D01*
G37*
G36*
G01Y396737D02*
X1097189Y397087D01*
Y397957D01*
X1097859Y398307D01*
X1098034D01*
Y396737D01*
X1097859D01*
G37*
G36*
G01Y400637D02*
X1097189Y400987D01*
Y401857D01*
X1097859Y402207D01*
X1098034D01*
Y400637D01*
X1097859D01*
G37*
G36*
G01X1099483Y388583D02*
X1100153Y388233D01*
Y387363D01*
X1099483Y387013D01*
X1099308D01*
Y388583D01*
X1099483D01*
G37*
G36*
G01Y384683D02*
X1100153Y384333D01*
Y383463D01*
X1099483Y383113D01*
X1099308D01*
Y384683D01*
X1099483D01*
G37*
G36*
G01Y380783D02*
X1100153Y380433D01*
Y379563D01*
X1099483Y379213D01*
X1099308D01*
Y380783D01*
X1099483D01*
G37*
G36*
G01Y404206D02*
X1100153Y403856D01*
Y402986D01*
X1099483Y402636D01*
X1099308D01*
Y404206D01*
X1099483D01*
G37*
G36*
G01Y400306D02*
X1100153Y399956D01*
Y399086D01*
X1099483Y398736D01*
X1099308D01*
Y400306D01*
X1099483D01*
G37*
G36*
G01Y396406D02*
X1100153Y396056D01*
Y395186D01*
X1099483Y394836D01*
X1099308D01*
Y396406D01*
X1099483D01*
G37*
G36*
G01Y392506D02*
X1100153Y392156D01*
Y391286D01*
X1099483Y390936D01*
X1099308D01*
Y392506D01*
X1099483D01*
G37*
G36*
G01X1111380Y388962D02*
X1110710Y389312D01*
Y390182D01*
X1111380Y390532D01*
X1111555D01*
Y388962D01*
X1111380D01*
G37*
G36*
G01X1108750Y371412D02*
X1108080Y371762D01*
Y372632D01*
X1108750Y372982D01*
X1108925D01*
Y371412D01*
X1108750D01*
G37*
G36*
G01X1111379Y381163D02*
X1110709Y381513D01*
Y382383D01*
X1111379Y382733D01*
X1111554D01*
Y381163D01*
X1111379D01*
G37*
G36*
G01Y385063D02*
X1110709Y385413D01*
Y386283D01*
X1111379Y386633D01*
X1111554D01*
Y385063D01*
X1111379D01*
G37*
G36*
G01Y396784D02*
X1110709Y397134D01*
Y398004D01*
X1111379Y398354D01*
X1111554D01*
Y396784D01*
X1111379D01*
G37*
G36*
G01Y400660D02*
X1110709Y401010D01*
Y401880D01*
X1111379Y402230D01*
X1111554D01*
Y400660D01*
X1111379D01*
G37*
G36*
G01X1111380Y392862D02*
X1110710Y393212D01*
Y394082D01*
X1111380Y394432D01*
X1111555D01*
Y392862D01*
X1111380D01*
G37*
G36*
G01X1113003Y388606D02*
X1113673Y388256D01*
Y387386D01*
X1113003Y387036D01*
X1112828D01*
Y388606D01*
X1113003D01*
G37*
G36*
G01Y384706D02*
X1113673Y384356D01*
Y383486D01*
X1113003Y383136D01*
X1112828D01*
Y384706D01*
X1113003D01*
G37*
G36*
G01Y380806D02*
X1113673Y380456D01*
Y379586D01*
X1113003Y379236D01*
X1112828D01*
Y380806D01*
X1113003D01*
G37*
G36*
G01Y404205D02*
X1113673Y403855D01*
Y402985D01*
X1113003Y402635D01*
X1112828D01*
Y404205D01*
X1113003D01*
G37*
G36*
G01Y400280D02*
X1113673Y399930D01*
Y399060D01*
X1113003Y398710D01*
X1112828D01*
Y400280D01*
X1113003D01*
G37*
G36*
G01Y396355D02*
X1113673Y396005D01*
Y395135D01*
X1113003Y394785D01*
X1112828D01*
Y396355D01*
X1113003D01*
G37*
G36*
G01Y392506D02*
X1113673Y392156D01*
Y391286D01*
X1113003Y390936D01*
X1112828D01*
Y392506D01*
X1113003D01*
G37*
G36*
G01X1106243Y388606D02*
X1106913Y388256D01*
Y387386D01*
X1106243Y387036D01*
X1106068D01*
Y388606D01*
X1106243D01*
G37*
G36*
G01Y376881D02*
X1106913Y376531D01*
Y375661D01*
X1106243Y375311D01*
X1106068D01*
Y376881D01*
X1106243D01*
G37*
G36*
G01Y372957D02*
X1106913Y372607D01*
Y371737D01*
X1106243Y371387D01*
X1106068D01*
Y372957D01*
X1106243D01*
G37*
G36*
G01Y384706D02*
X1106913Y384356D01*
Y383486D01*
X1106243Y383136D01*
X1106068D01*
Y384706D01*
X1106243D01*
G37*
G36*
G01Y380806D02*
X1106913Y380456D01*
Y379586D01*
X1106243Y379236D01*
X1106068D01*
Y380806D01*
X1106243D01*
G37*
G36*
G01Y404206D02*
X1106913Y403856D01*
Y402986D01*
X1106243Y402636D01*
X1106068D01*
Y404206D01*
X1106243D01*
G37*
G36*
G01Y400306D02*
X1106913Y399956D01*
Y399086D01*
X1106243Y398736D01*
X1106068D01*
Y400306D01*
X1106243D01*
G37*
G36*
G01Y396406D02*
X1106913Y396056D01*
Y395186D01*
X1106243Y394836D01*
X1106068D01*
Y396406D01*
X1106243D01*
G37*
G36*
G01Y392506D02*
X1106913Y392156D01*
Y391286D01*
X1106243Y390936D01*
X1106068D01*
Y392506D01*
X1106243D01*
G37*
G36*
G01X1107999Y387013D02*
X1107329Y387363D01*
Y388233D01*
X1107999Y388583D01*
X1108174D01*
Y387013D01*
X1107999D01*
G37*
G36*
G01Y383113D02*
X1107329Y383463D01*
Y384333D01*
X1107999Y384683D01*
X1108174D01*
Y383113D01*
X1107999D01*
G37*
G36*
G01Y394846D02*
X1107329Y395196D01*
Y396066D01*
X1107999Y396416D01*
X1108174D01*
Y394846D01*
X1107999D01*
G37*
G36*
G01Y398746D02*
X1107329Y399096D01*
Y399966D01*
X1107999Y400316D01*
X1108174D01*
Y398746D01*
X1107999D01*
G37*
G36*
G01Y402646D02*
X1107329Y402996D01*
Y403866D01*
X1107999Y404216D01*
X1108174D01*
Y402646D01*
X1107999D01*
G37*
G36*
G01Y390913D02*
X1107329Y391263D01*
Y392133D01*
X1107999Y392483D01*
X1108174D01*
Y390913D01*
X1107999D01*
G37*
G36*
G01X1104619Y388937D02*
X1103949Y389287D01*
Y390157D01*
X1104619Y390507D01*
X1104794D01*
Y388937D01*
X1104619D01*
G37*
G36*
G01Y369486D02*
X1103949Y369836D01*
Y370706D01*
X1104619Y371056D01*
X1104794D01*
Y369486D01*
X1104619D01*
G37*
G36*
G01Y373386D02*
X1103949Y373736D01*
Y374606D01*
X1104619Y374956D01*
X1104794D01*
Y373386D01*
X1104619D01*
G37*
G36*
G01Y377237D02*
X1103949Y377587D01*
Y378457D01*
X1104619Y378807D01*
X1104794D01*
Y377237D01*
X1104619D01*
G37*
G36*
G01Y381137D02*
X1103949Y381487D01*
Y382357D01*
X1104619Y382707D01*
X1104794D01*
Y381137D01*
X1104619D01*
G37*
G36*
G01Y385037D02*
X1103949Y385387D01*
Y386257D01*
X1104619Y386607D01*
X1104794D01*
Y385037D01*
X1104619D01*
G37*
G36*
G01Y396737D02*
X1103949Y397087D01*
Y397957D01*
X1104619Y398307D01*
X1104794D01*
Y396737D01*
X1104619D01*
G37*
G36*
G01Y400637D02*
X1103949Y400987D01*
Y401857D01*
X1104619Y402207D01*
X1104794D01*
Y400637D01*
X1104619D01*
G37*
G36*
G01Y392837D02*
X1103949Y393187D01*
Y394057D01*
X1104619Y394407D01*
X1104794D01*
Y392837D01*
X1104619D01*
G37*
G36*
G01X1109623Y390533D02*
X1110293Y390183D01*
Y389313D01*
X1109623Y388963D01*
X1109448D01*
Y390533D01*
X1109623D01*
G37*
G36*
G01Y386633D02*
X1110293Y386283D01*
Y385413D01*
X1109623Y385063D01*
X1109448D01*
Y386633D01*
X1109623D01*
G37*
G36*
G01Y382733D02*
X1110293Y382383D01*
Y381513D01*
X1109623Y381163D01*
X1109448D01*
Y382733D01*
X1109623D01*
G37*
G36*
G01Y402196D02*
X1110293Y401846D01*
Y400976D01*
X1109623Y400626D01*
X1109448D01*
Y402196D01*
X1109623D01*
G37*
G36*
G01Y398296D02*
X1110293Y397946D01*
Y397076D01*
X1109623Y396726D01*
X1109448D01*
Y398296D01*
X1109623D01*
G37*
G36*
G01Y394407D02*
X1110293Y394057D01*
Y393187D01*
X1109623Y392837D01*
X1109448D01*
Y394407D01*
X1109623D01*
G37*
G36*
G01X1124898Y408426D02*
X1124228Y408776D01*
Y409646D01*
X1124898Y409996D01*
X1125073D01*
Y408426D01*
X1124898D01*
G37*
G36*
G01Y412326D02*
X1124228Y412676D01*
Y413546D01*
X1124898Y413896D01*
X1125073D01*
Y412326D01*
X1124898D01*
G37*
G36*
G01X1125439Y414903D02*
X1125407Y415658D01*
X1126161Y416092D01*
X1126798Y415687D01*
X1126886Y415536D01*
X1125527Y414750D01*
X1125439Y414903D01*
G37*
G36*
G01X1128813Y416848D02*
X1128781Y417603D01*
X1129534Y418038D01*
X1130172Y417633D01*
X1130260Y417482D01*
X1128900Y416696D01*
X1128813Y416848D01*
G37*
G36*
G01X1126523Y408117D02*
X1127193Y407767D01*
Y406897D01*
X1126523Y406547D01*
X1126348D01*
Y408117D01*
X1126523D01*
G37*
G36*
G01Y412017D02*
X1127193Y411667D01*
Y410797D01*
X1126523Y410447D01*
X1126348D01*
Y412017D01*
X1126523D01*
G37*
G36*
G01X1125983Y405540D02*
X1126014Y404785D01*
X1125261Y404350D01*
X1124623Y404755D01*
X1124535Y404907D01*
X1125895Y405692D01*
X1125983Y405540D01*
G37*
G36*
G01X1132743Y417241D02*
X1132775Y416486D01*
X1132022Y416051D01*
X1131384Y416456D01*
X1131296Y416607D01*
X1132656Y417393D01*
X1132743Y417241D01*
G37*
G36*
G01X1129367Y415295D02*
X1129399Y414540D01*
X1128646Y414105D01*
X1128008Y414510D01*
X1127920Y414661D01*
X1129280Y415447D01*
X1129367Y415295D01*
G37*
G36*
G01X1142333Y409048D02*
X1142301Y409803D01*
X1143054Y410238D01*
X1143692Y409833D01*
X1143780Y409682D01*
X1142420Y408896D01*
X1142333Y409048D01*
G37*
G36*
G01X1145713Y410998D02*
X1145681Y411753D01*
X1146434Y412188D01*
X1147072Y411783D01*
X1147160Y411632D01*
X1145800Y410846D01*
X1145713Y410998D01*
G37*
G36*
G01X1138960Y407104D02*
X1138928Y407859D01*
X1139681Y408293D01*
X1140319Y407888D01*
X1140406Y407737D01*
X1139046Y406952D01*
X1138960Y407104D01*
G37*
G36*
G01X1138418Y404537D02*
X1137748Y404887D01*
Y405757D01*
X1138418Y406107D01*
X1138593D01*
Y404537D01*
X1138418D01*
G37*
G36*
G01X1146267Y409444D02*
X1146299Y408689D01*
X1145546Y408254D01*
X1144908Y408659D01*
X1144820Y408810D01*
X1146180Y409595D01*
X1146267Y409444D01*
G37*
G36*
G01X1142887Y407495D02*
X1142919Y406740D01*
X1142166Y406305D01*
X1141528Y406710D01*
X1141440Y406861D01*
X1142800Y407647D01*
X1142887Y407495D01*
G37*
G36*
G01X1118139Y404537D02*
X1117469Y404887D01*
Y405757D01*
X1118139Y406107D01*
X1118314D01*
Y404537D01*
X1118139D01*
G37*
G36*
G01X1118681Y407104D02*
X1118649Y407859D01*
X1119402Y408293D01*
X1120040Y407888D01*
X1120128Y407737D01*
X1118767Y406952D01*
X1118681Y407104D01*
G37*
G36*
G01X1121519Y410436D02*
X1120849Y410786D01*
Y411656D01*
X1121519Y412006D01*
X1121694D01*
Y410436D01*
X1121519D01*
G37*
G36*
G01Y414336D02*
X1120849Y414686D01*
Y415556D01*
X1121519Y415906D01*
X1121694D01*
Y414336D01*
X1121519D01*
G37*
G36*
G01X1122075Y416862D02*
X1122043Y417617D01*
X1122797Y418051D01*
X1123434Y417646D01*
X1123523Y417495D01*
X1122162Y416710D01*
X1122075Y416862D01*
G37*
G36*
G01X1125428Y418796D02*
X1125396Y419551D01*
X1126149Y419986D01*
X1126787Y419581D01*
X1126875Y419430D01*
X1125515Y418645D01*
X1125428Y418796D01*
G37*
G36*
G01X1123143Y410007D02*
X1123813Y409657D01*
Y408787D01*
X1123143Y408437D01*
X1122968D01*
Y410007D01*
X1123143D01*
G37*
G36*
G01X1122587Y407481D02*
X1122619Y406726D01*
X1121865Y406292D01*
X1121228Y406697D01*
X1121139Y406848D01*
X1122500Y407633D01*
X1122587Y407481D01*
G37*
G36*
G01X1125982Y417241D02*
X1126014Y416486D01*
X1125261Y416051D01*
X1124623Y416456D01*
X1124535Y416607D01*
X1125895Y417393D01*
X1125982Y417241D01*
G37*
G36*
G01X1123143Y413907D02*
X1123813Y413557D01*
Y412687D01*
X1123143Y412337D01*
X1122968D01*
Y413907D01*
X1123143D01*
G37*
G36*
G01X1129373Y419196D02*
X1129405Y418441D01*
X1128652Y418006D01*
X1128014Y418411D01*
X1127926Y418562D01*
X1129286Y419347D01*
X1129373Y419196D01*
G37*
G36*
G01X1135038Y406536D02*
X1134368Y406886D01*
Y407756D01*
X1135038Y408106D01*
X1135213D01*
Y406536D01*
X1135038D01*
G37*
G36*
G01X1138959Y411002D02*
X1138927Y411757D01*
X1139680Y412192D01*
X1140318Y411787D01*
X1140406Y411636D01*
X1139046Y410850D01*
X1138959Y411002D01*
G37*
G36*
G01X1142333Y412948D02*
X1142301Y413703D01*
X1143054Y414138D01*
X1143692Y413733D01*
X1143780Y413582D01*
X1142420Y412796D01*
X1142333Y412948D01*
G37*
G36*
G01X1142887Y411395D02*
X1142919Y410640D01*
X1142166Y410205D01*
X1141528Y410610D01*
X1141440Y410761D01*
X1142800Y411547D01*
X1142887Y411395D01*
G37*
G36*
G01X1139501Y409441D02*
X1139533Y408686D01*
X1138780Y408251D01*
X1138142Y408656D01*
X1138054Y408807D01*
X1139414Y409593D01*
X1139501Y409441D01*
G37*
G36*
G01X1146267Y413344D02*
X1146299Y412589D01*
X1145546Y412154D01*
X1144908Y412559D01*
X1144820Y412710D01*
X1146180Y413495D01*
X1146267Y413344D01*
G37*
G36*
G01X1136662Y406107D02*
X1137332Y405757D01*
Y404887D01*
X1136662Y404537D01*
X1136487D01*
Y406107D01*
X1136662D01*
G37*
G36*
G01X1129902D02*
X1130572Y405757D01*
Y404887D01*
X1129902Y404537D01*
X1129727D01*
Y406107D01*
X1129902D01*
G37*
G36*
G01Y410007D02*
X1130572Y409657D01*
Y408787D01*
X1129902Y408437D01*
X1129727D01*
Y410007D01*
X1129902D01*
G37*
G36*
G01X1136127Y415295D02*
X1136159Y414540D01*
X1135406Y414105D01*
X1134768Y414510D01*
X1134680Y414661D01*
X1136040Y415447D01*
X1136127Y415295D01*
G37*
G36*
G01X1132741Y413341D02*
X1132773Y412586D01*
X1132020Y412151D01*
X1131382Y412556D01*
X1131294Y412707D01*
X1132654Y413493D01*
X1132741Y413341D01*
G37*
G36*
G01X1131658Y408437D02*
X1130988Y408787D01*
Y409657D01*
X1131658Y410007D01*
X1131833D01*
Y408437D01*
X1131658D01*
G37*
G36*
G01Y404537D02*
X1130988Y404887D01*
Y405757D01*
X1131658Y406107D01*
X1131833D01*
Y404537D01*
X1131658D01*
G37*
G36*
G01X1132200Y411004D02*
X1132168Y411759D01*
X1132921Y412193D01*
X1133559Y411788D01*
X1133647Y411637D01*
X1132287Y410851D01*
X1132200Y411004D01*
G37*
G36*
G01X1138959Y414902D02*
X1138927Y415657D01*
X1139680Y416092D01*
X1140318Y415687D01*
X1140406Y415536D01*
X1139046Y414750D01*
X1138959Y414902D01*
G37*
G36*
G01X1135573Y412949D02*
X1135541Y413704D01*
X1136294Y414138D01*
X1136932Y413733D01*
X1137020Y413582D01*
X1135660Y412796D01*
X1135573Y412949D01*
G37*
G36*
G01X1125439Y403203D02*
X1125407Y403958D01*
X1126161Y404392D01*
X1126798Y403987D01*
X1126886Y403836D01*
X1125527Y403050D01*
X1125439Y403203D01*
G37*
G36*
G01X1128278Y410436D02*
X1127608Y410786D01*
Y411656D01*
X1128278Y412006D01*
X1128453D01*
Y410436D01*
X1128278D01*
G37*
G36*
G01Y406536D02*
X1127608Y406886D01*
Y407756D01*
X1128278Y408106D01*
X1128453D01*
Y406536D01*
X1128278D01*
G37*
G36*
G01X1128834Y412962D02*
X1128802Y413717D01*
X1129556Y414151D01*
X1130193Y413746D01*
X1130281Y413595D01*
X1128922Y412809D01*
X1128834Y412962D01*
G37*
G36*
G01X1132199Y414902D02*
X1132167Y415657D01*
X1132920Y416092D01*
X1133558Y415687D01*
X1133646Y415536D01*
X1132286Y414750D01*
X1132199Y414902D01*
G37*
G36*
G01X1136127Y411395D02*
X1136159Y410640D01*
X1135406Y410205D01*
X1134768Y410610D01*
X1134680Y410761D01*
X1136040Y411547D01*
X1136127Y411395D01*
G37*
G36*
G01X1133282Y408106D02*
X1133952Y407756D01*
Y406886D01*
X1133282Y406536D01*
X1133107D01*
Y408106D01*
X1133282D01*
G37*
G36*
G01X1142887Y415295D02*
X1142919Y414540D01*
X1142166Y414105D01*
X1141528Y414510D01*
X1141440Y414661D01*
X1142800Y415447D01*
X1142887Y415295D01*
G37*
G36*
G01X1139501Y413341D02*
X1139533Y412586D01*
X1138780Y412151D01*
X1138142Y412556D01*
X1138054Y412707D01*
X1139414Y413493D01*
X1139501Y413341D01*
G37*
G36*
G01X1101239Y406536D02*
X1100569Y406886D01*
Y407756D01*
X1101239Y408106D01*
X1101414D01*
Y406536D01*
X1101239D01*
G37*
G36*
G01Y410436D02*
X1100569Y410786D01*
Y411656D01*
X1101239Y412006D01*
X1101414D01*
Y410436D01*
X1101239D01*
G37*
G36*
G01Y414294D02*
X1100569Y414644D01*
X1100570Y415513D01*
X1101239Y415863D01*
X1101415Y415864D01*
X1101414Y414293D01*
X1101239Y414294D01*
G37*
G36*
G01X1101795Y416862D02*
X1101763Y417617D01*
X1102517Y418051D01*
X1103154Y417646D01*
X1103243Y417495D01*
X1101882Y416710D01*
X1101795Y416862D01*
G37*
G36*
G01X1102863Y410007D02*
X1103533Y409657D01*
Y408787D01*
X1102863Y408437D01*
X1102688D01*
Y410007D01*
X1102863D01*
G37*
G36*
G01Y406107D02*
X1103533Y405757D01*
Y404887D01*
X1102863Y404537D01*
X1102688D01*
Y406107D01*
X1102863D01*
G37*
G36*
G01X1106243Y419806D02*
X1106913Y419456D01*
Y418586D01*
X1106243Y418236D01*
X1106068D01*
Y419806D01*
X1106243D01*
G37*
G36*
G01X1105723Y417253D02*
X1105755Y416498D01*
X1105002Y416063D01*
X1104364Y416468D01*
X1104276Y416619D01*
X1105636Y417405D01*
X1105723Y417253D01*
G37*
G36*
G01X1102863Y413907D02*
X1103533Y413557D01*
Y412687D01*
X1102863Y412337D01*
X1102688D01*
Y413907D01*
X1102863D01*
G37*
G36*
G01X1114759Y406536D02*
X1114089Y406886D01*
Y407756D01*
X1114759Y408106D01*
X1114934D01*
Y406536D01*
X1114759D01*
G37*
G36*
G01X1115294Y409048D02*
X1115262Y409803D01*
X1116015Y410238D01*
X1116653Y409833D01*
X1116741Y409682D01*
X1115381Y408896D01*
X1115294Y409048D01*
G37*
G36*
G01X1118139Y412337D02*
X1117469Y412687D01*
Y413557D01*
X1118139Y413907D01*
X1118314D01*
Y412337D01*
X1118139D01*
G37*
G36*
G01X1118118Y416237D02*
X1117448Y416587D01*
Y417457D01*
X1118118Y417807D01*
X1118293D01*
Y416237D01*
X1118118D01*
G37*
G36*
G01X1118680Y418802D02*
X1118648Y419557D01*
X1119401Y419992D01*
X1120039Y419587D01*
X1120127Y419436D01*
X1118767Y418650D01*
X1118680Y418802D01*
G37*
G36*
G01X1119763Y412006D02*
X1120433Y411656D01*
Y410786D01*
X1119763Y410436D01*
X1119588D01*
Y412006D01*
X1119763D01*
G37*
G36*
G01X1119222Y409441D02*
X1119254Y408686D01*
X1118501Y408251D01*
X1117863Y408656D01*
X1117775Y408807D01*
X1119135Y409593D01*
X1119222Y409441D01*
G37*
G36*
G01X1116383Y406107D02*
X1117053Y405757D01*
Y404887D01*
X1116383Y404537D01*
X1116208D01*
Y406107D01*
X1116383D01*
G37*
G36*
G01X1122608Y419195D02*
X1122640Y418440D01*
X1121887Y418005D01*
X1121249Y418410D01*
X1121161Y418561D01*
X1122521Y419347D01*
X1122608Y419195D01*
G37*
G36*
G01X1119763Y415906D02*
X1120433Y415556D01*
Y414686D01*
X1119763Y414336D01*
X1119588D01*
Y415906D01*
X1119763D01*
G37*
G36*
G01X1097859Y404537D02*
X1097189Y404887D01*
Y405757D01*
X1097859Y406107D01*
X1098034D01*
Y404537D01*
X1097859D01*
G37*
G36*
G01Y412337D02*
X1097189Y412687D01*
Y413557D01*
X1097859Y413907D01*
X1098034D01*
Y412337D01*
X1097859D01*
G37*
G36*
G01X1099381Y419424D02*
X1098621Y419774D01*
Y420674D01*
X1099381Y421024D01*
X1099556D01*
Y419424D01*
X1099381D01*
G37*
G36*
G01X1099483Y412006D02*
X1100153Y411656D01*
Y410786D01*
X1099483Y410436D01*
X1099308D01*
Y412006D01*
X1099483D01*
G37*
G36*
G01Y408106D02*
X1100153Y407756D01*
Y406886D01*
X1099483Y406536D01*
X1099308D01*
Y408106D01*
X1099483D01*
G37*
G36*
G01Y415906D02*
X1100153Y415556D01*
Y414686D01*
X1099483Y414336D01*
X1099308D01*
Y415906D01*
X1099483D01*
G37*
G36*
G01X1100481Y420810D02*
X1101241Y420460D01*
Y419560D01*
X1100481Y419210D01*
X1100306D01*
Y420810D01*
X1100481D01*
G37*
G36*
G01X1111379Y408426D02*
X1110709Y408776D01*
Y409646D01*
X1111379Y409996D01*
X1111554D01*
Y408426D01*
X1111379D01*
G37*
G36*
G01Y404526D02*
X1110709Y404876D01*
Y405746D01*
X1111379Y406096D01*
X1111554D01*
Y404526D01*
X1111379D01*
G37*
G36*
G01X1111920Y411003D02*
X1111888Y411758D01*
X1112642Y412192D01*
X1113279Y411787D01*
X1113368Y411636D01*
X1112007Y410851D01*
X1111920Y411003D01*
G37*
G36*
G01X1114759Y414336D02*
X1114089Y414686D01*
Y415556D01*
X1114759Y415906D01*
X1114934D01*
Y414336D01*
X1114759D01*
G37*
G36*
G01X1115827Y411381D02*
X1115859Y410626D01*
X1115105Y410192D01*
X1114468Y410597D01*
X1114379Y410748D01*
X1115740Y411533D01*
X1115827Y411381D01*
G37*
G36*
G01X1113003Y408116D02*
X1113673Y407766D01*
Y406896D01*
X1113003Y406546D01*
X1112828D01*
Y408116D01*
X1113003D01*
G37*
G36*
G01X1116383Y413949D02*
X1117053Y413599D01*
X1117052Y412730D01*
X1116383Y412380D01*
X1116207Y412379D01*
X1116208Y413950D01*
X1116383Y413949D01*
G37*
G36*
G01X1116378Y417849D02*
X1117048Y417499D01*
X1117047Y416630D01*
X1116378Y416280D01*
X1116202Y416279D01*
X1116203Y417850D01*
X1116378Y417849D01*
G37*
G36*
G01X1106243Y412006D02*
X1106913Y411656D01*
Y410786D01*
X1106243Y410436D01*
X1106068D01*
Y412006D01*
X1106243D01*
G37*
G36*
G01Y408106D02*
X1106913Y407756D01*
Y406886D01*
X1106243Y406536D01*
X1106068D01*
Y408106D01*
X1106243D01*
G37*
G36*
G01X1109063Y415279D02*
X1109095Y414524D01*
X1108342Y414089D01*
X1107704Y414495D01*
X1107616Y414646D01*
X1108976Y415431D01*
X1109063Y415279D01*
G37*
G36*
G01X1107999Y410446D02*
X1107329Y410796D01*
Y411666D01*
X1107999Y412016D01*
X1108174D01*
Y410446D01*
X1107999D01*
G37*
G36*
G01Y406546D02*
X1107329Y406896D01*
Y407766D01*
X1107999Y408116D01*
X1108174D01*
Y406546D01*
X1107999D01*
G37*
G36*
G01X1108601Y412987D02*
X1108569Y413743D01*
X1109323Y414178D01*
X1109961Y413772D01*
X1110049Y413621D01*
X1108689Y412836D01*
X1108601Y412987D01*
G37*
G36*
G01X1111379Y416226D02*
X1110709Y416576D01*
Y417446D01*
X1111379Y417796D01*
X1111554D01*
Y416226D01*
X1111379D01*
G37*
G36*
G01X1112581Y420256D02*
X1111821Y420606D01*
Y421506D01*
X1112581Y421856D01*
X1112756D01*
Y420256D01*
X1112581D01*
G37*
G36*
G01X1104619Y404537D02*
X1103949Y404887D01*
Y405757D01*
X1104619Y406107D01*
X1104794D01*
Y404537D01*
X1104619D01*
G37*
G36*
G01Y408437D02*
X1103949Y408787D01*
Y409657D01*
X1104619Y410007D01*
X1104794D01*
Y408437D01*
X1104619D01*
G37*
G36*
G01Y412337D02*
X1103949Y412687D01*
Y413557D01*
X1104619Y413907D01*
X1104794D01*
Y412337D01*
X1104619D01*
G37*
G36*
G01X1105161Y414904D02*
X1105129Y415659D01*
X1105882Y416093D01*
X1106520Y415688D01*
X1106608Y415537D01*
X1105247Y414752D01*
X1105161Y414904D01*
G37*
G36*
G01X1109623Y409996D02*
X1110293Y409646D01*
Y408776D01*
X1109623Y408426D01*
X1109448D01*
Y409996D01*
X1109623D01*
G37*
G36*
G01Y406096D02*
X1110293Y405746D01*
Y404876D01*
X1109623Y404526D01*
X1109448D01*
Y406096D01*
X1109623D01*
G37*
G36*
G01X1113003Y415916D02*
X1113672Y415566D01*
Y414696D01*
X1113002Y414346D01*
X1112827D01*
Y415916D01*
X1113003D01*
G37*
G36*
G01X1112463Y413339D02*
X1112494Y412584D01*
X1111741Y412149D01*
X1111103Y412554D01*
X1111015Y412706D01*
X1112375Y413491D01*
X1112463Y413339D01*
G37*
G36*
G01X1113681Y421700D02*
X1114441Y421350D01*
Y420450D01*
X1113681Y420100D01*
X1113506D01*
Y421700D01*
X1113681D01*
G37*
G36*
G01X1274064Y141400D02*
X1273911Y141553D01*
Y141809D01*
X1272688Y143032D01*
X1269267D01*
X1268935Y143364D01*
X1265436D01*
X1263342Y145458D01*
G02X1263391Y146065I283J283D01*
G03X1261433Y148023I-822J1136D01*
G02X1260826Y147974I-324J234D01*
G01X1253100Y155700D01*
X1252832D01*
X1250014Y158518D01*
X1238082D01*
X1225200Y171400D01*
Y184600D01*
X1226460Y185860D01*
X1230316D01*
X1230699Y185551D01*
X1239400Y176850D01*
X1244167D01*
X1246225Y174792D01*
X1247758D01*
X1253350Y169200D01*
X1257455D01*
G02X1257842Y168700I0J-400D01*
G03X1260558I1358J-350D01*
G02X1260945Y169200I387J100D01*
G01X1261485D01*
X1262658Y168027D01*
X1263893D01*
X1264255Y168389D01*
X1267636D01*
X1268447Y169200D01*
X1271700D01*
X1271710Y169210D01*
X1277710D01*
X1292095Y154825D01*
X1295881D01*
X1297002Y153704D01*
Y149202D01*
X1289200Y141400D01*
X1274064D01*
G37*
G36*
G01X1253394Y172344D02*
X1250610Y175128D01*
Y176737D01*
G02X1251085Y177130I400J0D01*
G01X1259648Y175491D01*
X1259811Y175507D01*
G02X1260249Y175109I38J-398D01*
G01Y172344D01*
X1253394D01*
G37*
G36*
G01X1299089Y160947D02*
G03X1301273Y159491I818J-1139D01*
G02X1301884Y159734I390J-90D01*
G01X1303734Y158501D01*
X1307512Y157746D01*
X1309097Y156161D01*
G02X1309117Y155615I-282J-284D01*
G03X1309978Y153308I1058J-919D01*
G01X1310150Y153284D01*
Y151635D01*
G02X1309968Y151436I-200J0D01*
G03Y148644I130J-1396D01*
G02X1310150Y148445I-18J-199D01*
G01Y143600D01*
X1315030D01*
G03X1315170I70J1400D01*
G01X1320430D01*
G03X1320570I70J1400D01*
G01X1325030D01*
G03X1325170I70J1400D01*
G01X1326120D01*
G02X1326515Y143137I0J-400D01*
G03X1329285I1385J-219D01*
G02X1329680Y143600I395J63D01*
G01X1330030D01*
G03X1330170I70J1400D01*
G01X1332600D01*
X1341900Y134300D01*
Y99700D01*
X1339471Y97271D01*
X1339093D01*
X1339055Y97287D01*
G03X1337945I-555J-1287D01*
G01X1337907Y97271D01*
X1325025D01*
X1324093Y98203D01*
Y101034D01*
X1325993Y102934D01*
X1326315D01*
X1326347Y102923D01*
G03X1327253I453J1327D01*
G01X1327285Y102934D01*
X1328534D01*
X1329900Y104300D01*
Y132600D01*
X1327900Y134600D01*
X1326606D01*
X1326569Y134616D01*
G03X1325483I-543J-1293D01*
G01X1325446Y134600D01*
X1323606D01*
X1323569Y134616D01*
G03X1322483I-543J-1293D01*
G01X1322446Y134600D01*
X1306930D01*
X1300200Y141330D01*
Y152015D01*
X1296275Y155940D01*
X1292628D01*
X1288822Y159746D01*
Y166193D01*
X1289449Y166820D01*
X1295068D01*
X1298120Y162243D01*
X1299078Y161605D01*
G02X1299089Y160947I-222J-333D01*
G37*
G36*
G01X1330800Y553000D02*
X1329900Y553900D01*
Y615100D01*
X1335800Y621000D01*
X1361900D01*
X1366900Y616000D01*
Y598900D01*
X1363700Y595700D01*
Y590700D01*
X1366700Y587700D01*
Y568200D01*
X1362150Y563650D01*
Y561937D01*
X1359013Y558800D01*
X1353800D01*
X1352838Y557838D01*
X1352426D01*
X1347588Y553000D01*
X1330800D01*
G37*
G36*
G01X1398000Y54400D02*
X1388200D01*
X1386016Y56584D01*
X1386050Y56698D01*
G03X1385566Y59359I-2879J851D01*
G01Y79444D01*
X1386637Y80515D01*
X1398798D01*
X1399900Y79413D01*
Y56300D01*
X1398000Y54400D01*
G37*
G36*
G01X1375402Y369000D02*
X1374301Y370102D01*
X1371635D01*
G03X1371565I-35J-1402D01*
G01X1359770D01*
G02X1359490Y370788I-1J400D01*
G03Y372797I-978J1004D01*
G02X1359502Y373381I279J286D01*
G03X1359778Y375290I-1002J1119D01*
G02X1360135Y375899I340J210D01*
G03X1360480Y378876I65J1501D01*
G02X1360156Y379286I75J393D01*
G03Y379393I-1501J53D01*
G02X1360350Y379599I200J6D01*
G03X1360302Y382602I-50J1501D01*
G02X1360102Y382802I0J200D01*
G01Y382817D01*
G02X1360438Y383217I400J5D01*
G03X1360513Y386169I-238J1483D01*
G02X1360198Y386590I84J391D01*
G03X1360163Y387040I-1498J110D01*
G02X1360478Y387524I389J91D01*
G03X1361702Y388987I-278J1476D01*
G02X1362095Y389383I400J-4D01*
G03X1363200Y391872I-27J1502D01*
G02Y392398I302J263D01*
G03X1360936I-1132J987D01*
G02Y391872I-302J-263D01*
G03X1360576Y390715I1132J-987D01*
G02X1360356Y390494I-199J-22D01*
G03X1360253Y390501I-153J-1494D01*
G02X1360061Y390723I7J200D01*
G03X1359700Y391872I-1493J162D01*
G02Y392398I302J263D01*
G03X1357436I-1132J987D01*
G02Y391872I-302J-263D01*
G03X1358355Y389398I1132J-987D01*
G02X1358698Y389002I-57J-396D01*
G03X1358737Y388660I1502J-2D01*
G02X1358422Y388176I-389J-91D01*
G03X1358387Y385231I278J-1476D01*
G02X1358702Y384810I-84J-391D01*
G03X1358698Y384683I1498J-111D01*
G02X1358362Y384283I-400J-5D01*
G03X1358598Y381298I238J-1483D01*
G02X1358798Y381098I0J-200D01*
G03X1358799Y381059I1502J19D01*
G02X1358605Y380853I-200J-6D01*
G03X1358375Y377876I50J-1501D01*
G02X1358699Y377466I-75J-393D01*
G03X1358922Y376610I1501J-66D01*
G02X1358565Y376001I-340J-210D01*
G03X1357508Y373372I-65J-1501D01*
G02X1357525Y372788I-264J-300D01*
G03X1357534Y370788I987J-996D01*
G02X1357254Y370102I-279J-286D01*
G01X1353795D01*
X1352000Y371897D01*
Y392000D01*
X1357811Y397811D01*
G02X1358375Y397813I283J-283D01*
G03X1360584Y398126I985J997D01*
G02X1361225Y398203I349J-196D01*
G03X1363491Y399813I1025J956D01*
G02X1363713Y400377I354J186D01*
G03X1363781Y402997I-463J1323D01*
G02X1363650Y403650I152J370D01*
G01X1367500Y407500D01*
X1385971D01*
X1388300Y405171D01*
Y396700D01*
X1386700Y395100D01*
X1384783D01*
X1384749Y395113D01*
G03X1383278Y395272I-1048J-2813D01*
G02X1382840Y395786I-56J396D01*
G03X1380190Y395700I-1340J414D01*
G02X1379932Y395174I-373J-143D01*
G03X1379712Y395098I870J-2873D01*
G02X1379461Y395195I-72J186D01*
G03X1377753Y393242I-1254J-627D01*
G02X1377882Y393006I-65J-189D01*
G03X1378700Y390155I2918J-706D01*
G01Y383400D01*
X1379782Y382318D01*
X1379790Y382308D01*
G03X1380044Y382054I1110J856D01*
G01X1380054Y382046D01*
X1382100Y380000D01*
Y379698D01*
G02X1381516Y379343I-400J0D01*
G03Y376853I-644J-1245D01*
G02X1382100Y376498I184J-355D01*
G01Y370100D01*
X1381000Y369000D01*
X1375402D01*
G37*
G36*
G01X1373612Y561938D02*
X1372450Y563100D01*
Y583067D01*
G02X1373039Y583420I400J0D01*
G03X1374832Y583829I661J1236D01*
G02X1375520Y583756I323J-236D01*
G03X1375668Y585155I1280J572D01*
G02X1374980Y585228I-323J236D01*
G03X1373039Y585892I-1280J-572D01*
G02X1372450Y586245I-189J353D01*
G01Y600200D01*
X1374650Y602400D01*
X1379229D01*
X1380819Y600810D01*
X1396490D01*
X1399650Y597650D01*
X1408450D01*
X1413300Y592800D01*
X1428200D01*
X1437618Y602218D01*
Y609589D01*
X1439239Y611210D01*
X1457530D01*
X1457566Y611246D01*
X1460159D01*
X1461627Y609778D01*
Y598384D01*
X1460277Y597034D01*
X1457274D01*
X1450450Y590210D01*
X1446210D01*
X1443770Y587770D01*
X1440943D01*
X1430774Y577600D01*
X1423676D01*
G03X1423296Y577983I-1167J-777D01*
G02X1423294Y578644I224J331D01*
G03X1421713Y578640I-793J1156D01*
G02X1421715Y577979I-224J-331D01*
G03X1421342Y577600I795J-1155D01*
G01X1420903D01*
G03X1418715I-1094J-877D01*
G01X1418298D01*
X1418240Y577653D01*
G03X1416336I-952J-1029D01*
G01X1416278Y577600D01*
X1415861D01*
X1415803Y577653D01*
G03X1415493Y577870I-952J-1029D01*
G02X1415482Y578575I184J355D01*
G03X1414158Y578554I-682J1225D01*
G02X1414169Y577849I-184J-355D01*
G03X1413845Y577600I683J-1224D01*
G01X1405015D01*
X1404977Y577616D01*
G03X1403863I-557J-1286D01*
G01X1403825Y577600D01*
X1399800D01*
X1395498Y573298D01*
X1393279D01*
X1381919Y561938D01*
X1381262D01*
X1380300Y562900D01*
X1379070D01*
G03X1378930I-70J-1400D01*
G01X1378300D01*
X1377338Y561938D01*
X1373612D01*
G37*
G36*
G01X1443300Y378900D02*
X1449700D01*
Y397300D01*
X1443300D01*
Y378900D01*
G37*
G36*
G01X1447400Y417300D02*
X1437000D01*
Y428800D01*
X1437869Y429669D01*
X1437930Y429700D01*
X1447400D01*
Y427870D01*
G03Y427730I1400J-70D01*
G01Y417300D01*
G37*
G36*
G01X1514600Y400770D02*
X1514277Y401093D01*
Y401176D01*
G03X1512877Y402576I-1402J-2D01*
G01X1512794D01*
X1511869Y403501D01*
X1511990Y403642D01*
G03X1512308Y404323I-1065J912D01*
G03X1511700Y405722I-1383J231D01*
G01Y408025D01*
X1512600Y408925D01*
X1515693D01*
G03X1517738Y410842I1007J975D01*
G03X1517662Y410920I-1041J-938D01*
G01Y411897D01*
G02X1518186Y412277I400J0D01*
G03Y414923I464J1323D01*
G02X1517662Y415303I-124J380D01*
G01Y417214D01*
X1518348Y417900D01*
X1520000D01*
X1523684Y414216D01*
X1523638Y414095D01*
G03X1525675Y412400I1312J-495D01*
G01X1527537D01*
X1527607Y412387D01*
X1527623Y412382D01*
G03X1527844Y412322I477J1318D01*
G02Y411928I-37J-197D01*
G03X1526736Y410226I256J-1378D01*
G03X1527302Y409397I1364J324D01*
G02X1527398Y408831I-227J-330D01*
G03X1528772Y406564I1077J-897D01*
G03X1529273Y409087I-296J1370D01*
G02X1529177Y409653I227J330D01*
G03X1528356Y411928I-1077J897D01*
G02Y412322I37J197D01*
G03X1528530Y412366I-256J1378D01*
G03X1528592Y412387I-419J1338D01*
G01X1528626Y412400D01*
X1533531D01*
G03X1535647Y412859I869J1100D01*
G02X1536346Y412881I356J-183D01*
G03X1538231Y414825I1204J719D01*
G02Y415525I194J350D01*
G03X1538775Y416069I-681J1225D01*
G02X1539475I350J-194D01*
G03X1541925I1225J681D01*
G02X1542625I350J-194D01*
G03X1543169Y415525I1225J681D01*
G02Y414825I-194J-350D01*
G03X1544531I681J-1225D01*
G02Y415525I194J350D01*
G03X1545075Y416069I-681J1225D01*
G02X1545775I350J-194D01*
G03Y417431I1225J681D01*
G02X1545075I-350J194D01*
G03X1542625I-1225J-681D01*
G02X1541925I-350J194D01*
G03X1541381Y417975I-1225J-681D01*
G02Y418675I194J350D01*
G03X1541942Y419250I-681J1225D01*
G01X1552188D01*
G02X1552550Y418679I0J-400D01*
G03X1553824Y416662I1275J-605D01*
G01X1555912D01*
Y416295D01*
G02X1555720Y416095I-200J0D01*
G03Y413293I55J-1401D01*
G02X1555912Y413093I-8J-200D01*
G01Y411136D01*
G02X1555716Y410936I-200J0D01*
G03X1554274Y410535I58J-3002D01*
G02X1553376I-449J779D01*
G03X1550465Y410585I-1501J-2601D01*
G03X1550447Y410575I319J-596D01*
G01X1550377Y410535D01*
G03X1549909Y410203I1495J-2603D01*
G03X1549907Y410202I302J-606D01*
G03X1549752Y410057I1972J-2263D01*
G01X1549495Y409800D01*
X1547950D01*
X1547095Y408944D01*
X1546020D01*
X1542842Y405767D01*
X1542715Y405826D01*
G03X1541410Y403348I-591J-1272D01*
G02X1541543Y402789I-204J-344D01*
G03X1541411Y402561I2530J-1617D01*
G02X1540861Y402397I-355J185D01*
G03X1538773Y401171I-686J-1223D01*
G02X1538484Y400786I-400J-1D01*
G03X1537966I-259J-2992D01*
G02X1537677Y401171I111J384D01*
G03X1534873I-1402J3D01*
G02X1534584Y400786I-400J-1D01*
G03X1534066I-259J-2992D01*
G02X1533777Y401171I111J384D01*
G03X1530973I-1402J3D01*
G02X1530573Y400770I-400J-1D01*
G01X1530277D01*
G02X1529877Y401171I0J400D01*
G03X1527073I-1402J3D01*
G02X1526673Y400770I-400J-1D01*
G01X1526377D01*
G02X1525977Y401171I0J400D01*
G03X1523173I-1402J3D01*
G02X1522773Y400770I-400J-1D01*
G01X1522477D01*
G02X1522077Y401171I0J400D01*
G03X1519273I-1402J3D01*
G02X1518873Y400770I-400J-1D01*
G01X1518577D01*
G02X1518177Y401171I0J400D01*
G03X1515373I-1402J3D01*
G02X1514973Y400770I-400J-1D01*
G01X1514600D01*
G37*
G36*
G01X1700250Y115700D02*
X1691400Y124550D01*
X1675494D01*
X1674431Y125613D01*
X1673342D01*
X1672279Y124550D01*
X1663470D01*
X1661760Y126260D01*
X1660974D01*
X1660646Y126588D01*
X1660849Y126791D01*
X1660937Y126788D01*
G03X1659695Y128262I48J1301D01*
G02X1659132Y127952I-396J54D01*
G03X1658437Y128102I-693J-1527D01*
G01X1653389D01*
X1651547Y126260D01*
X1643776D01*
X1643400Y126636D01*
Y138600D01*
X1644150Y139350D01*
X1689616D01*
X1690579Y138387D01*
X1691862D01*
X1692825Y139350D01*
X1693334D01*
G02X1693734Y138948I0J-400D01*
G03X1694394Y137694I1502J-10D01*
G02Y137032I-224J-331D01*
G03X1693831Y135256I842J-1244D01*
G02X1693493Y134716I-374J-142D01*
G03X1695030Y133752I132J-1496D01*
G02X1695368Y134292I374J142D01*
G03X1696078Y137032I-132J1496D01*
G02Y137694I224J331D01*
G03X1696738Y138948I-842J1244D01*
G02X1697138Y139350I400J2D01*
G01X1715075D01*
X1716300Y138125D01*
X1734875D01*
X1738000Y135000D01*
X1740350D01*
X1742475Y137125D01*
X1749875D01*
X1750950Y136050D01*
Y119450D01*
X1747200Y115700D01*
X1700250D01*
G37*
G36*
G01X1609558Y396491D02*
G03X1609620Y396484I188J1389D01*
G01Y386511D01*
X1609150Y386041D01*
X1596996D01*
Y396491D01*
X1609558D01*
G37*
G36*
G01X1741731Y498136D02*
X1740912D01*
X1740478Y497702D01*
X1740396D01*
G03X1739012Y496498I4J-1402D01*
G01X1738988Y496326D01*
X1727526D01*
X1723291Y497169D01*
X1721850Y497766D01*
Y502100D01*
X1722356Y502606D01*
X1726136D01*
X1726621Y502121D01*
Y501027D01*
X1726604Y500988D01*
G03X1728639Y497858I2035J-903D01*
G01X1730307D01*
X1730999Y498550D01*
X1731351D01*
X1732043Y497858D01*
X1733639D01*
G03X1735196Y498493I0J2226D01*
G01X1735254Y498550D01*
X1735300D01*
X1736227Y499477D01*
Y504220D01*
X1739412Y507405D01*
X1765613D01*
X1765719Y507298D01*
X1798581D01*
X1798702Y507420D01*
X1806050D01*
X1809520Y503950D01*
X1830050D01*
X1837500Y496500D01*
X1842500D01*
X1844500Y494500D01*
Y492124D01*
X1842376Y490000D01*
X1830760D01*
X1827000Y493760D01*
X1824470D01*
X1824280Y493950D01*
X1803750D01*
X1797150Y500550D01*
X1776150D01*
X1773100Y497500D01*
X1761081D01*
X1760445Y498136D01*
X1759978D01*
X1759924Y498177D01*
G03X1758575Y498632I-1349J-1772D01*
G01X1757100D01*
G03X1756075Y498383I-2J-2226D01*
G03X1755050Y498632I-1023J-1977D01*
G01X1753575D01*
G03X1752173Y498136I-1J-2226D01*
G01X1749519D01*
G03X1748125Y498626I-1393J-1736D01*
G01X1747100D01*
G03X1745950Y498307I-2J-2226D01*
G03X1744800Y498626I-1148J-1907D01*
G01X1743125D01*
G03X1741731Y498136I-1J-2226D01*
G37*
G36*
G01X1861700Y157700D02*
Y170500D01*
X1868880D01*
G03X1869020I70J1400D01*
G01X1872100D01*
Y157700D01*
X1861700D01*
G37*
G36*
G01X1903320Y446700D02*
X1903072Y446948D01*
Y448530D01*
X1901887Y449715D01*
X1893280D01*
X1892900Y450095D01*
Y452270D01*
X1893638Y453008D01*
X1899037D01*
X1899836Y453807D01*
Y454983D01*
X1899514Y455305D01*
X1899508Y455312D01*
G03X1899315Y455505I-1083J-890D01*
G01X1899308Y455511D01*
X1898807Y456012D01*
X1889935D01*
X1889500Y456447D01*
Y488000D01*
X1890100Y488600D01*
X1917260D01*
G02X1917608Y488002I0J-400D01*
G03X1920392I1392J-792D01*
G02X1920740Y488600I348J198D01*
G01X1942200D01*
X1942500Y488300D01*
Y455700D01*
X1939830Y453030D01*
X1933409D01*
G03X1927229I-3090J-1851D01*
G01X1913740D01*
X1910763Y450053D01*
X1907514D01*
X1906319Y448858D01*
Y447296D01*
X1905723Y446700D01*
X1903320D01*
G37*
%LPC*%
G75*
G36*
G01X746700Y-37400D02*
X783207D01*
Y-57199D01*
X746700D01*
Y-57200D01*
X501300D01*
Y-37300D01*
X746700D01*
Y-37400D01*
G37*
G36*
G01X397000Y-39100D02*
X450380D01*
Y-57500D01*
X394400D01*
Y-57530D01*
X75000D01*
Y-37300D01*
X145500D01*
Y-39050D01*
X397000D01*
Y-39100D01*
G37*
G36*
G01X834000Y-37100D02*
X1115285D01*
Y-57100D01*
X834000D01*
Y-37100D01*
G37*
G36*
G01X4973Y301570D02*
G02Y303124I-1167J777D01*
G03X5639I333J222D01*
G02Y301570I1167J-777D01*
G03X4973I-333J-222D01*
G37*
G36*
G01X587500Y639900D02*
X427600D01*
Y659600D01*
X562300D01*
Y659500D01*
X587500D01*
Y639900D01*
G37*
G36*
G01X1245000Y659600D02*
X1530200D01*
Y639900D01*
X1245000D01*
Y659600D01*
G37*
G36*
G01X28987Y589962D02*
G03X28729Y589961I-128J-153D01*
G02X28720Y592864I-1234J1448D01*
G03X28978Y592865I128J153D01*
G02X31336Y592951I1233J-1448D01*
G02X33799Y593022I1273J-1413D01*
G02X33895Y590137I1286J-1401D01*
G02X31485Y590004I-1286J1401D01*
G02X28987Y589962I-1273J1413D01*
G37*
G36*
G01X47796Y579554D02*
G03Y578946I260J-304D01*
G02X45324I-1236J-1446D01*
G03Y579554I-260J304D01*
G02X47796I1236J1446D01*
G37*
G36*
G01X15150Y573407D02*
G02X15110Y577179I650J1893D01*
G02Y577621I1990J221D01*
G02X14691Y581167I690J1879D01*
G03Y581833I-221J333D01*
G02X14987Y585330I1109J1667D01*
G01X15106Y585382D01*
Y585514D01*
G02X15127Y585804I2002J1D01*
G02X15139Y589600I643J1896D01*
G02X17770Y587783I2000J83D01*
G02X17751Y587409I-2000J-86D01*
G02X18216Y583846I-643J-1896D01*
G03X18224Y583174I221J-333D01*
G02X17800Y579585I-1068J-1693D01*
G02X17790Y579279I-2000J-88D01*
G02Y575521I-690J-1879D01*
G02X17789Y575076I-1990J-218D01*
G02X18703Y571933I-650J-1893D01*
G02X15575I-1564J-1250D01*
G02X15150Y573407I1564J1249D01*
G37*
G36*
G01X20698Y565266D02*
G02Y568134I-1250J1434D01*
G02X23215Y568119I1250J-1434D01*
G03X23481I133J149D01*
G02Y565281I1267J-1419D01*
G03X23215I-133J-149D01*
G02X20698Y565266I-1267J1419D01*
G37*
G36*
G01X28381Y558982D02*
G03X28647I133J149D01*
G02X31315Y558849I1267J-1419D01*
G03X31920Y558868I294J271D01*
G02X34646Y559102I1476J-1200D01*
G02X37163Y559087I1250J-1434D01*
G03X37429I133J149D01*
G02Y556249I1267J-1419D01*
G03X37163I-133J-149D01*
G02X34646Y556234I-1267J1419D01*
G02X31995Y556382I-1250J1434D01*
G03X31390Y556363I-294J-271D01*
G02X28647Y556144I-1476J1200D01*
G03X28381I-133J-149D01*
G02Y558982I-1267J1419D01*
G37*
G36*
G01X47282Y556535D02*
G03Y555995I295J-270D01*
G02X44478I-1402J-1285D01*
G03Y556535I-295J270D01*
G02X47282I1402J1285D01*
G37*
G36*
G01X43566Y534091D02*
G03X43400Y533885I34J-197D01*
G02X41175Y535674I-1900J-85D01*
G03X41341Y535880I-34J197D01*
G02X41933Y537346I1900J85D01*
G03X41958Y537607I-138J145D01*
G02X44210Y540481I1547J1107D01*
G03X44713Y540668I148J371D01*
G02X47636Y538344I1687J-878D01*
G03Y537736I260J-304D01*
G02X45236Y534786I-1235J-1446D01*
G03X44687Y534729I-245J-316D01*
G02X43566Y534091I-1446J1236D01*
G37*
G36*
G01X28200Y530824D02*
G02Y533776I-1200J1476D01*
G02Y530824I1200J-1476D01*
G37*
G36*
G01X12075Y535933D02*
G02X13600Y539185I1564J1250D01*
G02X15104Y541040I2000J-85D01*
G02X15110Y541421I1996J159D01*
G02Y545179I690J1879D01*
G02Y545621I1990J221D01*
G02X15043Y549354I690J1879D01*
G02X15053Y549838I1992J201D01*
G02X15139Y553594I734J1862D01*
G02X17787Y551789I2000J89D01*
G02X17769Y551420I-2000J-87D01*
G02X17792Y547704I-734J-1863D01*
G02X17790Y547279I-1992J-203D01*
G02Y543521I-690J-1879D01*
G02Y543079I-1990J-221D01*
G02X18214Y539537I-690J-1879D01*
G03X18221Y538868I223J-332D01*
G02X18703Y535933I-1082J-1685D01*
G02X19138Y534580I-1564J-1249D01*
G03X19462Y534167I400J-20D01*
G02X20400Y533688I-362J-1867D01*
G02Y530912I1300J-1388D01*
G02X17198Y532304I-1300J1388D01*
G03X16855Y532701I-400J1D01*
G02X15680Y533312I284J1982D01*
G03X15098I-291J-274D01*
G02X12075Y535933I-1460J1370D01*
G37*
G36*
G01X45419Y525634D02*
G03X45563Y526142I-217J336D01*
G02X49355Y526752I1806J863D01*
G03X49760Y526302I397J-50D01*
G02X48580Y522713I40J-2002D01*
G03X48031Y522655I-244J-317D01*
G02X45419Y525634I-1524J1298D01*
G37*
G36*
G01X38219Y521278D02*
G03X37933Y521799I-378J132D01*
G02X40008Y524925I456J1949D01*
G03X40609Y524871I324J235D01*
G02X42391Y521463I1384J-1446D01*
G03X42078Y520996I80J-392D01*
G02X38219Y521278I-1967J-373D01*
G37*
G36*
G01X39597Y507538D02*
G02X35628Y507055I-1997J-137D01*
G02X33705Y509088I79J2000D01*
G02X33295Y509269I598J1910D01*
G02X32805Y512331I-1495J1331D01*
G02X35541Y512571I1495J-1331D01*
G02X38981Y511490I1459J-1371D01*
G02X39597Y507538I218J-1990D01*
G37*
G36*
G01X45515Y505748D02*
G03X46098Y505745I293J272D01*
G02X46085Y503002I1452J-1378D01*
G03X45502Y503005I-293J-272D01*
G02X45515Y505748I-1452J1378D01*
G37*
G36*
G01X108874Y392919D02*
G03X108274I-300J-265D01*
G02Y394777I-1050J929D01*
G03X108874I300J265D01*
G02Y392919I1050J-929D01*
G37*
G36*
G01X118570Y384194D02*
G02X116059Y379642I59J-3001D01*
G02X115807Y385639I-59J3001D01*
G02X118364Y384493I1256J-622D01*
G02X118570Y384194I-2364J-1849D01*
G37*
G36*
G01X124461Y379637D02*
G03X124474Y380166I-293J272D01*
G02X124492Y382120I1150J966D01*
G03Y382646I-302J263D01*
G02X126756I1132J987D01*
G03Y382120I302J-263D01*
G02X126726Y380112I-1132J-987D01*
G03X126713Y379583I293J-272D01*
G02X126837Y379411I-1153J-962D01*
G03X127182Y379421I170J106D01*
G02X127368Y377713I1318J-721D01*
G03X126750Y377696I-302J-262D01*
G02X124461Y379637I-1187J920D01*
G37*
G36*
G01X121407Y373181D02*
G03X121446Y373762I-254J309D01*
G02X123366Y373635I1027J954D01*
G03X123327Y373054I254J-309D01*
G02X121407Y373181I-1027J-954D01*
G37*
G36*
G01X127135Y345549D02*
G03X126602Y345531I-256J-307D01*
G02X124461Y347637I-1039J1085D01*
G03X124474Y348166I-293J272D01*
G02X124492Y350120I1150J966D01*
G03Y350646I-302J263D01*
G02X126756I1132J987D01*
G03Y350120I302J-263D01*
G02X126608Y347998I-1132J-987D01*
G03X126600Y347702I131J-152D01*
G02X126649Y347653I-1037J-1086D01*
G03X126947Y347663I145J138D01*
G02X127135Y345549I1153J-963D01*
G37*
G36*
G01X127234Y313650D02*
G03X126679Y313611I-257J-306D01*
G02X124461Y315637I-1116J1005D01*
G03X124474Y316166I-293J272D01*
G02X124492Y318120I1150J966D01*
G03Y318646I-302J263D01*
G02X126756I1132J987D01*
G03Y318120I302J-263D01*
G02X126608Y315998I-1132J-987D01*
G03X126600Y315702I131J-152D01*
G02X126661Y315641I-1031J-1092D01*
G03X126971Y315663I146J137D01*
G02X127234Y313650I1229J-863D01*
G37*
G36*
G01X122105Y308776D02*
G03X121926Y309351I-341J209D01*
G02X123689Y309901I567J1282D01*
G03X123868Y309326I341J-209D01*
G02X122105Y308776I-567J-1282D01*
G37*
G36*
G01X127152Y281524D02*
G03X126598Y281527I-279J-287D01*
G02X124461Y283637I-1035J1089D01*
G03X124474Y284166I-293J272D01*
G02X124492Y286120I1150J966D01*
G03Y286646I-302J263D01*
G02X126756I1132J987D01*
G03Y286120I302J-263D01*
G02X126726Y284112I-1132J-987D01*
G03X126713Y283583I293J-272D01*
G02X126732Y283559I-1168J-944D01*
G03X127042Y283557I156J125D01*
G02X127152Y281524I1158J-957D01*
G37*
G36*
G01X127193Y249585D02*
G03X126639Y249568I-268J-297D01*
G02X124461Y251637I-1076J1048D01*
G03X124474Y252166I-293J272D01*
G02X124492Y254120I1150J966D01*
G03Y254646I-302J263D01*
G02X126756I1132J987D01*
G03Y254120I302J-263D01*
G02X126608Y251998I-1132J-987D01*
G03X126600Y251702I131J-152D01*
G02X126696Y251602I-1034J-1089D01*
G03X127006Y251612I151J131D01*
G02X127193Y249585I1194J-912D01*
G37*
G36*
G01X121643Y244894D02*
G03X121506Y245459I-336J218D01*
G02X123380Y245914I697J1216D01*
G03X123517Y245349I336J-218D01*
G02X121643Y244894I-697J-1216D01*
G37*
G36*
G01X127368Y217713D02*
G03X126750Y217696I-302J-262D01*
G02X124461Y219637I-1187J920D01*
G03X124474Y220166I-293J272D01*
G02X124492Y222120I1150J966D01*
G03Y222646I-302J263D01*
G02X126756I1132J987D01*
G03Y222120I302J-263D01*
G02X126726Y220112I-1132J-987D01*
G03X126713Y219583I293J-272D01*
G02X126837Y219411I-1153J-962D01*
G03X127182Y219421I170J106D01*
G02X127368Y217713I1318J-721D01*
G37*
G36*
G01X109073Y405734D02*
G02X108570Y407543I-1502J557D01*
G03X109182Y407686I250J313D01*
G02X109687Y408267I1270J-594D01*
G03X109679Y408943I-218J335D01*
G02X109660Y411659I840J1364D01*
G03X109596Y412368I-214J338D01*
G02X111058Y412500I603J1484D01*
G03X111122Y411791I214J-338D01*
G02X111302Y408909I-603J-1484D01*
G03X111265Y408234I195J-349D01*
G02X109671Y405928I-813J-1142D01*
G03X109073Y405734I-223J-332D01*
G37*
G36*
G01X128750Y371148D02*
G02X128552Y372417I-1330J442D01*
G03X129255Y372527I323J236D01*
G02X129453Y371258I1330J-442D01*
G03X128750Y371148I-323J-236D01*
G37*
G36*
G01X128370Y338700D02*
G02X127731Y340196I-1370J299D01*
G03X128330Y340452I208J341D01*
G02X128969Y338956I1370J-299D01*
G03X128370Y338700I-208J-341D01*
G37*
G36*
G01X128755Y306876D02*
G02X128442Y308539I-1255J625D01*
G03X129069Y308657I269J296D01*
G02X129382Y306994I1255J-625D01*
G03X128755Y306876I-269J-296D01*
G37*
G36*
G01X123666Y277219D02*
G02X121957Y276796I-592J-1271D01*
G03X121808Y277400I-318J242D01*
G02X123517Y277823I592J1271D01*
G03X123666Y277219I318J-242D01*
G37*
G36*
G01X128755Y274876D02*
G02X128442Y276539I-1255J625D01*
G03X129069Y276657I269J296D01*
G02X129382Y274994I1255J-625D01*
G03X128755Y274876I-269J-296D01*
G37*
G36*
G01Y242876D02*
G02X128442Y244539I-1255J625D01*
G03X129069Y244657I269J296D01*
G02X129382Y242994I1255J-625D01*
G03X128755Y242876I-269J-296D01*
G37*
G36*
G01X128822Y210945D02*
G02X126588Y211074I-1068J908D01*
G03X125954Y211114I-332J-222D01*
G02X123725Y211260I-1059J919D01*
G02X125461Y213316I-1183J2759D01*
G02X126061Y212812I-566J-1283D01*
G03X126695Y212772I332J222D01*
G02X128685Y212901I1059J-919D01*
G03X129256Y212941I266J299D01*
G02X129393Y210985I1068J-908D01*
G03X128822Y210945I-266J-299D01*
G37*
G36*
G01X58175Y255329D02*
G02X56785Y255306I-675J-1229D01*
G03X56753Y256011I-204J344D01*
G02X58183Y256034I692J1445D01*
G03X58175Y255329I184J-355D01*
G37*
G36*
G01X193564Y331470D02*
G03X193010I-277J-288D01*
G02Y333490I-973J1010D01*
G03X193564I277J288D01*
G02X195510I973J-1010D01*
G03X196064I277J288D01*
G02Y331470I973J-1010D01*
G03X195510I-277J-288D01*
G02X193564I-973J1010D01*
G37*
G36*
G01X376998Y330627D02*
G03X377585Y330641I287J279D01*
G02X379464Y328129I1200J-1061D01*
G03X379286Y327569I170J-362D01*
G02X376816Y325592I-1392J-792D01*
G03X376282Y325596I-269J-296D01*
G02X374111Y325645I-1059J1202D01*
G03X373545Y325635I-278J-288D01*
G02X371263Y325609I-1154J1111D01*
G03X370735Y325640I-282J-284D01*
G02X368626Y325759I-987J1262D01*
G03X368101Y325790I-280J-286D01*
G02X368083Y325776I-992J1257D01*
G03X368050Y325488I120J-160D01*
G02X365736Y325637I-1228J-1029D01*
G03X365796Y326156I-271J294D01*
G02X368243Y328200I1325J901D01*
G03X368768Y328169I280J286D01*
G02X370876Y328039I980J-1267D01*
G03X371404Y328008I282J284D01*
G02X373503Y327899I987J-1262D01*
G03X374069Y327909I278J288D01*
G02X374351Y328142I1155J-1110D01*
G03X374476Y328684I-217J336D01*
G02X376998Y330627I1371J828D01*
G37*
G36*
G01X434694Y323112D02*
G03X434094I-300J-265D01*
G02Y325234I-1200J1061D01*
G03X434694I300J265D01*
G02Y323112I1200J-1061D01*
G37*
G36*
G01X427494D02*
G03X426894I-300J-265D01*
G02Y325234I-1200J1061D01*
G03X427494I300J265D01*
G02Y323112I1200J-1061D01*
G37*
G36*
G01X367579Y311230D02*
G03X367069Y311072I-167J-363D01*
G02X366528Y313260I-1376J821D01*
G03X367053Y313358I208J342D01*
G02X369157Y313494I1112J-854D01*
G03X369709Y313480I283J283D01*
G02X371644Y313430I941J-1039D01*
G03X372201Y313421I283J282D01*
G02X374123I961J-1021D01*
G03X374680Y313430I274J291D01*
G02X376640Y313458I994J-989D01*
G03X377190I275J290D01*
G02Y311424I966J-1017D01*
G03X376640I-275J-290D01*
G02X374713Y311420I-966J1017D01*
G03X374156Y311411I-274J-291D01*
G02X372168I-994J989D01*
G03X371611Y311420I-283J-282D01*
G02X369658Y311451I-961J1021D01*
G03X369106Y311465I-283J-283D01*
G02X367579Y311230I-941J1039D01*
G37*
G36*
G01X193564Y298740D02*
G03X193010I-277J-288D01*
G02Y300760I-973J1010D01*
G03X193564I277J288D01*
G02X195510I973J-1010D01*
G03X196064I277J288D01*
G02Y298740I973J-1010D01*
G03X195510I-277J-288D01*
G02X193564I-973J1010D01*
G37*
G36*
G01X405894Y294843D02*
G03X405294I-300J-265D01*
G02Y296965I-1200J1061D01*
G03X405894I300J265D01*
G02Y294843I1200J-1061D01*
G37*
G36*
G01X398694D02*
G03X398094I-300J-265D01*
G02Y296965I-1200J1061D01*
G03X398694I300J265D01*
G02Y294843I1200J-1061D01*
G37*
G36*
G01X391494D02*
G03X390894I-300J-265D01*
G02Y296965I-1200J1061D01*
G03X391494I300J265D01*
G02Y294843I1200J-1061D01*
G37*
G36*
G01X384294D02*
G03X383694I-300J-265D01*
G02Y296965I-1200J1061D01*
G03X384294I300J265D01*
G02Y294843I1200J-1061D01*
G37*
G36*
G01X377094D02*
G03X376494I-300J-265D01*
G02Y296965I-1200J1061D01*
G03X377094I300J265D01*
G02Y294843I1200J-1061D01*
G37*
G36*
G01X369894D02*
G03X369294I-300J-265D01*
G02Y296965I-1200J1061D01*
G03X369894I300J265D01*
G02Y294843I1200J-1061D01*
G37*
G36*
G01X434727Y292127D02*
G03X434061I-333J-222D01*
G02X431986Y293972I-1167J777D01*
G03X431960Y294602I-259J305D01*
G02X434094Y296965I934J1302D01*
G03X434694I300J265D01*
G02X436828Y294602I1200J-1061D01*
G03X436802Y293972I233J-325D01*
G02X434727Y292127I-908J-1068D01*
G37*
G36*
G01X427527D02*
G03X426861I-333J-222D01*
G02X424786Y293972I-1167J777D01*
G03X424760Y294602I-259J305D01*
G02X426894Y296965I934J1302D01*
G03X427494I300J265D01*
G02X429628Y294602I1200J-1061D01*
G03X429602Y293972I233J-325D01*
G02X427527Y292127I-908J-1068D01*
G37*
G36*
G01X420327D02*
G03X419661I-333J-222D01*
G02X417586Y293972I-1167J777D01*
G03X417560Y294602I-259J305D01*
G02X419694Y296965I934J1302D01*
G03X420294I300J265D01*
G02X422428Y294602I1200J-1061D01*
G03X422402Y293972I233J-325D01*
G02X420327Y292127I-908J-1068D01*
G37*
G36*
G01X413127D02*
G03X412461I-333J-222D01*
G02X410386Y293972I-1167J777D01*
G03X410360Y294602I-259J305D01*
G02X412494Y296965I934J1302D01*
G03X413094I300J265D01*
G02X415228Y294602I1200J-1061D01*
G03X415202Y293972I233J-325D01*
G02X413127Y292127I-908J-1068D01*
G37*
G36*
G01X434704Y277866D02*
G03X434104Y277860I-297J-268D01*
G02X434084Y279982I-1210J1050D01*
G03X434684Y279988I297J268D01*
G02X434704Y277866I1210J-1050D01*
G37*
G36*
G01X427494Y277849D02*
G03X426894I-300J-265D01*
G02Y279971I-1200J1061D01*
G03X427494I300J265D01*
G02Y277849I1200J-1061D01*
G37*
G36*
G01X420335Y277870D02*
G03X419735Y277863I-297J-268D01*
G02X419711Y279984I-1212J1047D01*
G03X420311Y279991I297J268D01*
G02X420335Y277870I1212J-1047D01*
G37*
G36*
G01X413039Y277813D02*
G03X412456I-291J-273D01*
G02Y280007I-1168J1097D01*
G03X413039I291J273D01*
G02Y277813I1168J-1097D01*
G37*
G36*
G01X391494Y277843D02*
G03X390894I-300J-265D01*
G02Y279965I-1200J1061D01*
G03X391494I300J265D01*
G02Y277843I1200J-1061D01*
G37*
G36*
G01X377094D02*
G03X376494I-300J-265D01*
G02Y279965I-1200J1061D01*
G03X377094I300J265D01*
G02Y277843I1200J-1061D01*
G37*
G36*
G01X369894D02*
G03X369294I-300J-265D01*
G02Y279965I-1200J1061D01*
G03X369894I300J265D01*
G02Y277843I1200J-1061D01*
G37*
G36*
G01X193564Y269740D02*
G03X193010I-277J-288D01*
G02Y271760I-973J1010D01*
G03X193564I277J288D01*
G02X195510I973J-1010D01*
G03X196064I277J288D01*
G02Y269740I973J-1010D01*
G03X195510I-277J-288D01*
G02X193564I-973J1010D01*
G37*
G36*
G01X381946Y272676D02*
G03Y272076I265J-300D01*
G02X379824I-1061J-1200D01*
G03Y272676I-265J300D01*
G02X381946I1061J1200D01*
G37*
G36*
G01X198627Y239616D02*
G03Y239062I288J-277D01*
G02X196607I-1010J-973D01*
G03Y239616I-288J277D01*
G02Y241562I1010J973D01*
G03Y242116I-288J277D01*
G02X198627I1010J973D01*
G03Y241562I288J-277D01*
G02Y239616I-1010J-973D01*
G37*
G36*
G01X192547Y239516D02*
G03Y238962I288J-277D01*
G02X190527I-1010J-973D01*
G03Y239516I-288J277D01*
G02Y241462I1010J973D01*
G03Y242016I-288J277D01*
G02X192547I1010J973D01*
G03Y241462I288J-277D01*
G02Y239516I-1010J-973D01*
G37*
G36*
G01X386654Y323068D02*
G02Y325278I-1160J1105D01*
G03X387234I290J275D01*
G02X389494Y325337I1160J-1105D01*
G03X390044I275J291D01*
G02X392244I1100J-1164D01*
G03X392794I275J291D01*
G02X395094Y325234I1100J-1164D01*
G03X395694I300J265D01*
G02X398094I1200J-1061D01*
G03X398694I300J265D01*
G02X401094I1200J-1061D01*
G03X401694I300J265D01*
G02X404094I1200J-1061D01*
G03X404694I300J265D01*
G02X407094I1200J-1061D01*
G03X407694I300J265D01*
G02X410094I1200J-1061D01*
G03X410694I300J265D01*
G02X413094I1200J-1061D01*
G03X413694I300J265D01*
G02X416334Y324874I1200J-1061D01*
G03X417054I360J175D01*
G02X419694Y325234I1440J-701D01*
G03X420294I300J265D01*
G02Y323112I1200J-1061D01*
G03X419694I-300J-265D01*
G02X417054Y323472I-1200J1061D01*
G03X416334I-360J-175D01*
G02X413694Y323112I-1440J701D01*
G03X413094I-300J-265D01*
G02X410694I-1200J1061D01*
G03X410094I-300J-265D01*
G02X407694I-1200J1061D01*
G03X407094I-300J-265D01*
G02X404694I-1200J1061D01*
G03X404094I-300J-265D01*
G02X401694I-1200J1061D01*
G03X401094I-300J-265D01*
G02X398694I-1200J1061D01*
G03X398094I-300J-265D01*
G02X395694I-1200J1061D01*
G03X395094I-300J-265D01*
G02X392794Y323009I-1200J1061D01*
G03X392244I-275J-291D01*
G02X390044I-1100J1164D01*
G03X389494I-275J-291D01*
G02X387234Y323068I-1100J1164D01*
G03X386654I-290J-275D01*
G37*
G36*
G01X434061Y309127D02*
G02Y310681I-1167J777D01*
G03X434727I333J222D01*
G02Y309127I1167J-777D01*
G03X434061I-333J-222D01*
G37*
G36*
G01X426861D02*
G02Y310681I-1167J777D01*
G03X427527I333J222D01*
G02Y309127I1167J-777D01*
G03X426861I-333J-222D01*
G37*
G36*
G01X419661D02*
G02Y310681I-1167J777D01*
G03X420327I333J222D01*
G02Y309127I1167J-777D01*
G03X419661I-333J-222D01*
G37*
G36*
G01X412461D02*
G02Y310681I-1167J777D01*
G03X413127I333J222D01*
G02Y309127I1167J-777D01*
G03X412461I-333J-222D01*
G37*
G36*
G01X405294Y277849D02*
G02X402792Y277977I-1200J1061D01*
G03X402142Y277978I-325J-233D01*
G02X402144Y279847I-1300J936D01*
G03X402794Y279846I325J233D01*
G02X405294Y279971I1300J-936D01*
G03X405894I300J265D01*
G02Y277849I1200J-1061D01*
G03X405294I-300J-265D01*
G37*
G36*
G01X384661Y279438D02*
G02X384467Y277861I1284J-958D01*
G03X383778Y277946I-369J-154D01*
G02X383972Y279523I-1284J958D01*
G03X384661Y279438I369J154D01*
G37*
G36*
G01X450519Y16087D02*
G03X449939Y16068I-281J-285D01*
G02X449823Y18048I-1047J932D01*
G03X450401Y18097I266J299D01*
G02X450519Y16087I1172J-940D01*
G37*
G36*
G01X596456Y13817D02*
G03X596470Y13234I281J-285D01*
G02X594470I-1000J-1120D01*
G03X594484Y13817I-267J298D01*
G02X596456I986J997D01*
G37*
G36*
G01X589763D02*
G03X589777Y13234I281J-285D01*
G02X587777I-1000J-1120D01*
G03X587791Y13817I-267J298D01*
G02X589763I986J997D01*
G37*
G36*
G01X572331D02*
G03X572345Y13234I281J-285D01*
G02X570345I-1000J-1120D01*
G03X570359Y13817I-267J298D01*
G02X572331I986J997D01*
G37*
G36*
G01X566039Y13782D02*
G03X566067Y13221I299J-266D01*
G02X563987Y13173I-1015J-1107D01*
G03X563989Y13734I-284J282D01*
G02X566039Y13782I1003J980D01*
G37*
G36*
G01X559645Y13817D02*
G03X559659Y13234I281J-285D01*
G02X557659I-1000J-1120D01*
G03X557673Y13817I-267J298D01*
G02X559645I986J997D01*
G37*
G36*
G01X552952D02*
G03X552966Y13234I281J-285D01*
G02X550966I-1000J-1120D01*
G03X550980Y13817I-267J298D01*
G02X552952I986J997D01*
G37*
G36*
G01X535520D02*
G03X535534Y13234I281J-285D01*
G02X533534I-1000J-1120D01*
G03X533548Y13817I-267J298D01*
G02X535520I986J997D01*
G37*
G36*
G01X479330D02*
G03X479344Y13234I281J-285D01*
G02X477344I-1000J-1120D01*
G03X477358Y13817I-267J298D01*
G02X479330I986J997D01*
G37*
G36*
G01X461898D02*
G03X461912Y13234I281J-285D01*
G02X459912I-1000J-1120D01*
G03X459926Y13817I-267J298D01*
G02X461898I986J997D01*
G37*
G36*
G01X455612Y13778D02*
G03X455639Y13217I298J-267D01*
G02X453558Y13177I-1020J-1103D01*
G03X453562Y13738I-283J283D01*
G02X455612Y13778I1006J976D01*
G37*
G36*
G01X449237Y12664D02*
G03X449222Y12087I269J-296D01*
G02X447281Y12136I-996J-987D01*
G03X447296Y12713I-269J296D01*
G02X449237Y12664I996J987D01*
G37*
G36*
G01X581270Y10797D02*
G03X581239Y10233I267J-298D01*
G02X579200Y10291I-1047J-933D01*
G03X579201Y10855I-283J283D01*
G02X579170Y12941I1065J1059D01*
G03Y13487I-292J273D01*
G02X579225Y15597I1096J1027D01*
G03X579241Y16158I-277J289D01*
G02X581291I1025J956D01*
G03X581307Y15597I293J-272D01*
G02X581362Y13487I-1041J-1083D01*
G03Y12941I292J-273D01*
G02X581270Y10797I-1096J-1027D01*
G37*
G36*
G01X544474Y10810D02*
G03X544450Y10246I271J-294D01*
G02X542410Y10277I-1035J-946D01*
G03X542403Y10842I-287J279D01*
G02X542359Y12941I1052J1072D01*
G03Y13487I-292J273D01*
G02X542414Y15597I1096J1027D01*
G03X542430Y16158I-277J289D01*
G02X544480I1025J956D01*
G03X544496Y15597I293J-272D01*
G02X544551Y13487I-1041J-1083D01*
G03Y12941I292J-273D01*
G02X544474Y10810I-1096J-1027D01*
G37*
G36*
G01X470851D02*
G03X470827Y10246I271J-294D01*
G02X468787Y10277I-1035J-946D01*
G03X468780Y10842I-287J279D01*
G02X468736Y12941I1052J1072D01*
G03Y13487I-292J273D01*
G02X468791Y15597I1096J1027D01*
G03X468807Y16158I-277J289D01*
G02X470857I1025J956D01*
G03X470873Y15597I293J-272D01*
G02X470928Y13487I-1041J-1083D01*
G03Y12941I292J-273D01*
G02X470851Y10810I-1096J-1027D01*
G37*
G36*
G01X576206Y10616D02*
G03X576191Y10055I277J-288D01*
G02X574141I-1025J-957D01*
G03X574126Y10616I-292J273D01*
G02X574070Y12727I1040J1084D01*
G03Y13273I-292J273D01*
G02X574132Y15389I1096J1027D01*
G03X574151Y15950I-275J290D01*
G02X576202Y15938I1031J950D01*
G03X576213Y15376I290J-275D01*
G02X576262Y13273I-1047J-1076D01*
G03Y12727I292J-273D01*
G02X576206Y10616I-1096J-1027D01*
G37*
G36*
G01X539395D02*
G03X539380Y10055I277J-288D01*
G02X537330I-1025J-957D01*
G03X537315Y10616I-292J273D01*
G02X537259Y12727I1040J1084D01*
G03Y13273I-292J273D01*
G02X537298Y15367I1096J1027D01*
G03X537304Y15928I-282J284D01*
G02X539355Y15960I1011J972D01*
G03X539379Y15399I297J-268D01*
G02X539451Y13273I-1024J-1099D01*
G03Y12727I292J-273D01*
G02X539395Y10616I-1096J-1027D01*
G37*
G36*
G01X465772D02*
G03X465757Y10055I277J-288D01*
G02X463707I-1025J-957D01*
G03X463692Y10616I-292J273D01*
G02X463636Y12727I1040J1084D01*
G03Y13273I-292J273D01*
G02X463675Y15367I1096J1027D01*
G03X463681Y15928I-282J284D01*
G02X465732Y15960I1011J972D01*
G03X465756Y15399I297J-268D01*
G02X465828Y13273I-1024J-1099D01*
G03Y12727I292J-273D01*
G02X465772Y10616I-1096J-1027D01*
G37*
G36*
G01X576222Y-8143D02*
G03X576212Y-8715I274J-291D01*
G02X574200Y-8732I-998J-985D01*
G03X574180Y-8160I-289J276D01*
G02X574104Y-6015I1012J1110D01*
G03X574098Y-5458I-290J275D01*
G02X574125Y-3318I1068J1057D01*
G03X574141Y-2757I-277J289D01*
G02X576191I1025J956D01*
G03X576207Y-3318I293J-272D01*
G02X576254Y-5436I-1041J-1083D01*
G03X576260Y-5993I290J-275D01*
G02X576222Y-8143I-1068J-1056D01*
G37*
G36*
G01X539411D02*
G03X539401Y-8715I274J-291D01*
G02X537389Y-8732I-998J-985D01*
G03X537369Y-8160I-289J276D01*
G02X537293Y-6015I1012J1110D01*
G03X537287Y-5458I-290J275D01*
G02X537314Y-3318I1068J1057D01*
G03X537330Y-2757I-277J289D01*
G02X539380I1025J956D01*
G03X539396Y-3318I293J-272D01*
G02X539443Y-5436I-1041J-1083D01*
G03X539449Y-5993I290J-275D01*
G02X539411Y-8143I-1068J-1056D01*
G37*
G36*
G01X502600D02*
G03X502590Y-8715I274J-291D01*
G02X500578Y-8732I-998J-985D01*
G03X500558Y-8160I-289J276D01*
G02X500482Y-6015I1012J1110D01*
G03X500476Y-5458I-290J275D01*
G02X500503Y-3318I1068J1057D01*
G03X500519Y-2757I-277J289D01*
G02X502569I1025J956D01*
G03X502585Y-3318I293J-272D01*
G02X502632Y-5436I-1041J-1083D01*
G03X502638Y-5993I290J-275D01*
G02X502600Y-8143I-1068J-1056D01*
G37*
G36*
G01X581311Y-8339D02*
G03X581298Y-8901I278J-288D01*
G02X579250Y-8911I-1019J-963D01*
G03X579232Y-8350I-293J271D01*
G02X579173Y-6230I1034J1090D01*
G03Y-5681I-291J274D01*
G02X579266Y-3531I1093J1030D01*
G03X579291Y-2959I-267J298D01*
G02X581302Y-2995I1023J959D01*
G03X581306Y-3568I281J-285D01*
G02X581359Y-5681I-1040J-1083D01*
G03Y-6230I291J-274D01*
G02X581311Y-8339I-1093J-1030D01*
G37*
G36*
G01X544500D02*
G03X544487Y-8901I278J-288D01*
G02X542439Y-8911I-1019J-963D01*
G03X542421Y-8350I-293J271D01*
G02X542362Y-6230I1034J1090D01*
G03Y-5681I-291J274D01*
G02X542455Y-3531I1093J1030D01*
G03X542480Y-2959I-267J298D01*
G02X544491Y-2995I1023J959D01*
G03X544495Y-3568I281J-285D01*
G02X544548Y-5681I-1040J-1083D01*
G03Y-6230I291J-274D01*
G02X544500Y-8339I-1093J-1030D01*
G37*
G36*
G01X507689D02*
G03X507676Y-8901I278J-288D01*
G02X505628Y-8911I-1019J-963D01*
G03X505610Y-8350I-293J271D01*
G02X505551Y-6230I1034J1090D01*
G03Y-5681I-291J274D01*
G02X505644Y-3531I1093J1030D01*
G03X505669Y-2959I-267J298D01*
G02X507680Y-2995I1023J959D01*
G03X507684Y-3568I281J-285D01*
G02X507737Y-5681I-1040J-1083D01*
G03Y-6230I291J-274D01*
G02X507689Y-8339I-1093J-1030D01*
G37*
G36*
G01X470877D02*
G03X470864Y-8901I278J-288D01*
G02X468816Y-8911I-1019J-963D01*
G03X468798Y-8350I-293J271D01*
G02X468739Y-6230I1034J1090D01*
G03Y-5681I-291J274D01*
G02X468791Y-3568I1093J1030D01*
G03X468807Y-3007I-277J289D01*
G02X470857I1025J956D01*
G03X470873Y-3568I293J-272D01*
G02X470925Y-5681I-1041J-1083D01*
G03Y-6230I291J-274D01*
G02X470877Y-8339I-1093J-1030D01*
G37*
G36*
G01X376959Y5723D02*
G02Y7277I-1167J777D01*
G03X377625I333J222D01*
G02Y5723I1167J-777D01*
G03X376959I-333J-222D01*
G37*
G36*
G01X629517Y611700D02*
G03X629012Y611466I-132J-378D01*
G02X628165Y613297I-1307J507D01*
G03X628670Y613531I132J378D01*
G02X629517Y611700I1307J-507D01*
G37*
G36*
G01X656071Y613089D02*
G03Y612511I277J-289D01*
G02X654129I-971J-1011D01*
G03Y613089I-277J289D01*
G02X656071I971J1011D01*
G37*
G36*
G01X576233Y606267D02*
G03X576217Y605706I277J-289D01*
G02X574167I-1025J-956D01*
G03X574151Y606267I-293J272D01*
G02X574104Y608385I1041J1083D01*
G03X574098Y608942I-290J275D01*
G02X574125Y611082I1068J1057D01*
G03X574141Y611643I-277J289D01*
G02X576191I1025J956D01*
G03X576207Y611082I293J-272D01*
G02X576254Y608964I-1041J-1083D01*
G03X576260Y608407I290J-275D01*
G02X576233Y606267I-1068J-1057D01*
G37*
G36*
G01X539422D02*
G03X539406Y605706I277J-289D01*
G02X537356I-1025J-956D01*
G03X537340Y606267I-293J272D01*
G02X537293Y608385I1041J1083D01*
G03X537287Y608942I-290J275D01*
G02X537314Y611082I1068J1057D01*
G03X537330Y611643I-277J289D01*
G02X539380I1025J956D01*
G03X539396Y611082I293J-272D01*
G02X539443Y608964I-1041J-1083D01*
G03X539449Y608407I290J-275D01*
G02X539422Y606267I-1068J-1057D01*
G37*
G36*
G01X502611D02*
G03X502595Y605706I277J-289D01*
G02X500545I-1025J-956D01*
G03X500529Y606267I-293J272D01*
G02X500482Y608385I1041J1083D01*
G03X500476Y608942I-290J275D01*
G02X500503Y611082I1068J1057D01*
G03X500519Y611643I-277J289D01*
G02X502569I1025J956D01*
G03X502585Y611082I293J-272D01*
G02X502632Y608964I-1041J-1083D01*
G03X502638Y608407I290J-275D01*
G02X502611Y606267I-1068J-1057D01*
G37*
G36*
G01X463733Y605706D02*
G03X463717Y606267I-293J272D01*
G02X463670Y608385I1041J1083D01*
G03X463664Y608942I-290J275D01*
G02X463691Y611082I1068J1057D01*
G03X463707Y611643I-277J289D01*
G02X465757I1025J956D01*
G03X465773Y611082I293J-272D01*
G02X465820Y608964I-1041J-1083D01*
G03X465826Y608407I290J-275D01*
G02X465799Y606267I-1068J-1057D01*
G03X465783Y605706I277J-289D01*
G02X463733I-1025J-956D01*
G37*
G36*
G01X581311Y606061D02*
G03X581298Y605499I278J-288D01*
G02X579250Y605489I-1019J-963D01*
G03X579232Y606050I-293J271D01*
G02X579173Y608170I1034J1090D01*
G03Y608719I-291J274D01*
G02X579236Y610843I1093J1031D01*
G03X579257Y611404I-274J291D01*
G02X581307Y611383I1035J946D01*
G03X581317Y610822I290J-275D01*
G02X581359Y608719I-1051J-1073D01*
G03Y608170I291J-274D01*
G02X581311Y606061I-1093J-1030D01*
G37*
G36*
G01X544500D02*
G03X544487Y605499I278J-288D01*
G02X542439Y605489I-1019J-963D01*
G03X542421Y606050I-293J271D01*
G02X542362Y608170I1034J1090D01*
G03Y608719I-291J274D01*
G02X542425Y610843I1093J1031D01*
G03X542446Y611404I-274J291D01*
G02X544496Y611383I1035J946D01*
G03X544506Y610822I290J-275D01*
G02X544548Y608719I-1051J-1073D01*
G03Y608170I291J-274D01*
G02X544500Y606061I-1093J-1030D01*
G37*
G36*
G01X507689D02*
G03X507676Y605499I278J-288D01*
G02X505628Y605489I-1019J-963D01*
G03X505610Y606050I-293J271D01*
G02X505551Y608170I1034J1090D01*
G03Y608719I-291J274D01*
G02X505614Y610843I1093J1031D01*
G03X505635Y611404I-274J291D01*
G02X507685Y611383I1035J946D01*
G03X507695Y610822I290J-275D01*
G02X507737Y608719I-1051J-1073D01*
G03Y608170I291J-274D01*
G02X507689Y606061I-1093J-1030D01*
G37*
G36*
G01X470877Y606060D02*
G03X470865Y605498I278J-287D01*
G02X468817Y605489I-1020J-962D01*
G03X468799Y606051I-294J272D01*
G02X468740Y608170I1034J1089D01*
G03X468739Y608718I-292J273D01*
G02X468802Y610843I1093J1031D01*
G03X468823Y611404I-274J291D01*
G02X470873Y611383I1035J946D01*
G03X470883Y610822I290J-275D01*
G02X470925Y608719I-1051J-1073D01*
G03X470926Y608171I292J-273D01*
G02X470877Y606060I-1093J-1031D01*
G37*
G36*
G01X648104Y592592D02*
G03X648419Y592084I383J-114D01*
G02X646836Y591102I-239J-1382D01*
G03X646521Y591610I-383J114D01*
G02X645381Y592738I239J1382D01*
G03X644880Y593050I-393J-73D01*
G02X645879Y594654I-380J1350D01*
G03X646380Y594342I393J73D01*
G02X648104Y592592I380J-1350D01*
G37*
G36*
G01X479330Y590417D02*
G03X479344Y589834I281J-285D01*
G02X477344I-1000J-1120D01*
G03X477358Y590417I-267J298D01*
G02X479330I986J997D01*
G37*
G36*
G01X461937Y590358D02*
G03X461953Y589797I293J-272D01*
G02X459871I-1041J-1083D01*
G03X459887Y590358I-277J289D01*
G02X461937I1025J956D01*
G37*
G36*
G01X455612Y590378D02*
G03X455639Y589817I298J-267D01*
G02X453558Y589777I-1020J-1103D01*
G03X453562Y590338I-283J283D01*
G02X455612Y590378I1006J976D01*
G37*
G36*
G01X449194Y589591D02*
G03X448982Y589035I144J-373D01*
G02X447233Y589703I-1247J-641D01*
G03X447445Y590259I-144J373D01*
G02X449194Y589591I1247J641D01*
G37*
G36*
G01X470772Y587343D02*
G03X470753Y586736I251J-312D01*
G02X468881Y586751I-944J-1036D01*
G03X468872Y587359I-265J300D01*
G02X468736Y589541I960J1155D01*
G03Y590087I-292J273D01*
G02X468791Y592197I1096J1027D01*
G03X468807Y592758I-277J289D01*
G02X470857I1025J956D01*
G03X470873Y592197I293J-272D01*
G02X470928Y590087I-1041J-1083D01*
G03Y589541I292J-273D01*
G02X470772Y587343I-1096J-1027D01*
G37*
G36*
G01X463707Y586655D02*
G03X463692Y587216I-292J273D01*
G02X463636Y589327I1040J1084D01*
G03Y589873I-292J273D01*
G02X463681Y591973I1096J1027D01*
G03X463691Y592535I-280J286D01*
G02X465742Y592553I1017J965D01*
G03X465763Y591992I295J-270D01*
G02X465828Y589873I-1031J-1092D01*
G03Y589327I292J-273D01*
G02X465772Y587216I-1096J-1027D01*
G03X465757Y586655I277J-288D01*
G02X463707I-1025J-957D01*
G37*
G36*
G01X479845Y610757D02*
G02X478979Y612061I-1501J-57D01*
G03X479548Y612425I169J363D01*
G02X480401Y611140I1402J5D01*
G03X479845Y610757I-156J-368D01*
G37*
G36*
G01X375160Y594586D02*
G02X375066Y592831I1044J-936D01*
G03X374444Y592864I-324J-234D01*
G02X374538Y594619I-1044J936D01*
G03X375160Y594586I324J234D01*
G37*
G36*
G01X652889Y584968D02*
G02X651662Y585549I-1138J-818D01*
G03X651961Y586182I-25J399D01*
G02X653188Y585601I1138J818D01*
G03X652889Y584968I25J-399D01*
G37*
G36*
G01X463914Y314235D02*
G03X463891Y313677I275J-291D01*
G02X461882Y313757I-1043J-936D01*
G03X461905Y314315I-275J291D01*
G02X463914Y314235I1043J936D01*
G37*
G36*
G01X459399Y277949D02*
G03X459398Y277385I283J-283D01*
G02X457409Y277391I-997J-985D01*
G03X457410Y277955I-283J283D01*
G02X459399Y277949I997J985D01*
G37*
G36*
G01X579182Y231552D02*
G03X579740Y231317I381J124D01*
G02X579027Y229627I620J-1257D01*
G03X578469Y229862I-381J-124D01*
G02X576876Y232128I-619J1257D01*
G03X576872Y232707I-278J288D01*
G02X578512Y234955I960J1022D01*
G03X579073Y235146I194J350D01*
G02X579680Y233364I1287J-556D01*
G03X579119Y233173I-194J-350D01*
G02X578805Y232720I-1287J557D01*
G03X578809Y232141I278J-288D01*
G02X579182Y231552I-961J-1021D01*
G37*
G36*
G01X571697Y229557D02*
G03X572258Y229360I369J154D01*
G02X571637Y227588I672J-1230D01*
G03X571076Y227785I-369J-154D01*
G02X569455Y230047I-672J1230D01*
G03X569483Y230608I-270J295D01*
G02X571043Y232847I1045J935D01*
G03X571576Y233115I147J372D01*
G02X572415Y231446I1354J-365D01*
G03X571882Y231178I-147J-372D01*
G02X571477Y230511I-1354J365D01*
G03X571449Y229950I270J-295D01*
G02X571697Y229557I-1045J-934D01*
G37*
G36*
G01X591383Y214711D02*
G03Y214089I252J-311D01*
G02X589617I-883J-1089D01*
G03Y214711I-252J311D01*
G02X591383I883J1089D01*
G37*
G36*
G01X617675Y205984D02*
G03X617121I-277J-288D01*
G02Y208004I-973J1010D01*
G03X617675I277J288D01*
G02X617771Y208088I970J-1012D01*
G03Y208400I-125J156D01*
G02X619658Y208521I877J1094D01*
G03Y207967I288J-277D01*
G02X619742Y207871I-1012J-970D01*
G03X620054I156J125D01*
G02X622121Y208004I1094J-877D01*
G03X622675I277J288D01*
G02X622771Y208088I970J-1012D01*
G03Y208400I-125J156D01*
G02X622638Y210467I877J1094D01*
G03Y211021I-288J277D01*
G02X622554Y211117I1012J970D01*
G03X622242I-156J-125D01*
G02X622121Y213004I-1094J877D01*
G03X622675I277J288D01*
G02X622771Y213088I970J-1012D01*
G03Y213400I-125J156D01*
G02X622638Y215467I877J1094D01*
G03Y216021I-288J277D01*
G02X622554Y216117I1012J970D01*
G03X622242I-156J-125D01*
G02X622121Y218004I-1094J877D01*
G03X622675I277J288D01*
G02X622771Y218088I970J-1012D01*
G03Y218400I-125J156D01*
G02X622638Y220467I877J1094D01*
G03Y221021I-288J277D01*
G02X622554Y221117I1012J970D01*
G03X622242I-156J-125D01*
G02X622121Y223004I-1094J877D01*
G03X622675I277J288D01*
G02X622771Y223088I970J-1012D01*
G03Y223400I-125J156D01*
G02X622638Y225467I877J1094D01*
G03Y226021I-288J277D01*
G02X622554Y226117I1012J970D01*
G03X622242I-156J-125D01*
G02X620175Y225984I-1094J877D01*
G03X619621I-277J-288D01*
G02X619525Y225900I-970J1012D01*
G03Y225588I125J-156D01*
G02X617638Y225467I-877J-1094D01*
G03Y226021I-288J277D01*
G02X617554Y226117I1012J970D01*
G03X617242I-156J-125D01*
G02X615175Y225984I-1094J877D01*
G03X614621I-277J-288D01*
G02X614525Y225900I-970J1012D01*
G03Y225588I125J-156D01*
G02X614658Y223521I-877J-1094D01*
G03Y222967I288J-277D01*
G02X614742Y222871I-1012J-970D01*
G03X615054I156J125D01*
G02X615175Y220984I1094J-877D01*
G03X614621I-277J-288D01*
G02X614525Y220900I-970J1012D01*
G03Y220588I125J-156D01*
G02X614658Y218521I-877J-1094D01*
G03Y217967I288J-277D01*
G02X614742Y217871I-1012J-970D01*
G03X615054I156J125D01*
G02X615175Y215984I1094J-877D01*
G03X614621I-277J-288D01*
G02X614525Y215900I-970J1012D01*
G03Y215588I125J-156D01*
G02X614658Y213521I-877J-1094D01*
G03Y212967I288J-277D01*
G02X614742Y212871I-1012J-970D01*
G03X615054I156J125D01*
G02X615175Y210984I1094J-877D01*
G03X614621I-277J-288D01*
G02X614525Y210900I-970J1012D01*
G03Y210588I125J-156D01*
G02X612638Y210467I-877J-1094D01*
G03Y211021I-288J277D01*
G02Y212967I1010J973D01*
G03Y213521I-288J277D01*
G02Y215467I1010J973D01*
G03Y216021I-288J277D01*
G02Y217967I1010J973D01*
G03Y218521I-288J277D01*
G02Y220467I1010J973D01*
G03Y221021I-288J277D01*
G02X612554Y221117I1012J970D01*
G03X612242I-156J-125D01*
G02X610138Y222967I-1094J877D01*
G03Y223521I-288J277D01*
G02X610054Y223617I1012J970D01*
G03X609742I-156J-125D01*
G02X607638Y225467I-1094J877D01*
G03Y226021I-288J277D01*
G02X609658I1010J973D01*
G03Y225467I288J-277D01*
G02X609742Y225371I-1012J-970D01*
G03X610054I156J125D01*
G02X612121Y225504I1094J-877D01*
G03X612675I277J288D01*
G02X612771Y225588I970J-1012D01*
G03Y225900I-125J156D01*
G02X612638Y227967I877J1094D01*
G03Y228521I-288J277D01*
G02X612554Y228617I1012J970D01*
G03X612242I-156J-125D01*
G02X612121Y230504I-1094J877D01*
G03X612675I277J288D01*
G02X614658Y228521I973J-1010D01*
G03Y227967I288J-277D01*
G02X614742Y227871I-1012J-970D01*
G03X615054I156J125D01*
G02X617121Y228004I1094J-877D01*
G03X617675I277J288D01*
G02X617771Y228088I970J-1012D01*
G03Y228400I-125J156D01*
G02X619621Y230504I877J1094D01*
G03X620175I277J288D01*
G02X622158Y228521I973J-1010D01*
G03Y227967I288J-277D01*
G02X622242Y227871I-1012J-970D01*
G03X622554I156J125D01*
G02X624658Y226021I1094J-877D01*
G03Y225467I288J-277D01*
G02Y223521I-1010J-973D01*
G03Y222967I288J-277D01*
G02Y221021I-1010J-973D01*
G03Y220467I288J-277D01*
G02Y218521I-1010J-973D01*
G03Y217967I288J-277D01*
G02Y216021I-1010J-973D01*
G03Y215467I288J-277D01*
G02Y213521I-1010J-973D01*
G03Y212967I288J-277D01*
G02Y211021I-1010J-973D01*
G03Y210467I288J-277D01*
G02Y208521I-1010J-973D01*
G03Y207967I288J-277D01*
G02X622675Y205984I-1010J-973D01*
G03X622121I-277J-288D01*
G02X620175I-973J1010D01*
G03X619621I-277J-288D01*
G02X617675I-973J1010D01*
G37*
G36*
G01X465845Y293836D02*
G02X464680Y292661I221J-1384D01*
G03X464221Y293116I-396J60D01*
G02X465386Y294291I-221J1384D01*
G03X465845Y293836I396J-60D01*
G37*
G36*
G01X451230Y266487D02*
G02X450517Y264930I653J-1241D01*
G03X449941Y265194I-390J-90D01*
G02X448489Y267587I-654J1240D01*
G03X448402Y268289I-229J328D01*
G02X449699Y268448I498J1311D01*
G03X449786Y267746I229J-328D01*
G02X450654Y266751I-498J-1311D01*
G03X451230Y266487I390J90D01*
G37*
G36*
G01X602200Y227570D02*
G02X602143Y225908I1100J-870D01*
G03X601500Y225930I-330J-226D01*
G02X601557Y227592I-1100J870D01*
G03X602200Y227570I330J226D01*
G37*
G36*
G01X580354Y218161D02*
G02X579257Y219258I-1374J-277D01*
G03X579728Y219729I79J392D01*
G02X580825Y218632I1374J277D01*
G03X580354Y218161I-79J-392D01*
G37*
G36*
G01X565773Y212929D02*
G02X564656Y211694I278J-1374D01*
G03X564178Y212126I-398J40D01*
G02X565295Y213361I-278J1374D01*
G03X565773Y212929I398J-40D01*
G37*
G36*
G01X579220Y203377D02*
G02X578123Y202280I277J-1374D01*
G03X577652Y202751I-392J79D01*
G02X578749Y203848I-277J1374D01*
G03X579220Y203377I392J-79D01*
G37*
G36*
G01X607489Y199401D02*
G02X605767Y199172I-716J-1205D01*
G03X605684Y199795I-287J279D01*
G02X605006Y201146I716J1205D01*
G03X604573Y201586I-398J41D01*
G02X605847Y202837I-120J1397D01*
G03X606280Y202397I398J-41D01*
G02X607406Y200024I120J-1397D01*
G03X607489Y199401I287J-279D01*
G37*
G36*
G01X776892Y377686D02*
G03X776286Y377668I-295J-270D01*
G02X774019Y379637I-1164J949D01*
G03X774032Y380166I-293J272D01*
G02X774050Y382120I1150J966D01*
G03Y382646I-302J263D01*
G02X776314I1132J987D01*
G03Y382120I302J-263D01*
G02X776284Y380112I-1132J-987D01*
G03X776271Y379583I293J-272D01*
G02X776368Y379453I-1154J-962D01*
G03X776706Y379463I166J112D01*
G02X776892Y377686I1294J-763D01*
G37*
G36*
G01X778810Y371129D02*
G03X778193Y371122I-306J-258D01*
G02X778172Y372904I-1093J878D01*
G03X778789Y372911I306J258D01*
G02X778810Y371129I1093J-878D01*
G37*
G36*
G01X771160Y372542D02*
G03X770929Y373080I-366J161D01*
G02X772683Y373834I472J1320D01*
G03X772914Y373296I366J-161D01*
G02X771160Y372542I-472J-1320D01*
G37*
G36*
G01X767955Y352504D02*
G03X768121Y351953I349J-195D01*
G02X766254Y351393I-644J-1245D01*
G03X766088Y351944I-349J195D01*
G02X767955Y352504I644J1245D01*
G37*
G36*
G01X776250Y347661D02*
G03X776535Y347659I143J139D01*
G02X776633Y345450I1065J-1059D01*
G03X776122Y345454I-258J-306D01*
G02X774069Y347637I-951J1163D01*
G03X774082Y348166I-293J272D01*
G02X774100Y350120I1150J966D01*
G03Y350646I-302J263D01*
G02X776364I1132J987D01*
G03Y350120I302J-263D01*
G02X776216Y347998I-1132J-987D01*
G03X776208Y347702I131J-152D01*
G02X776250Y347661I-1028J-1095D01*
G37*
G36*
G01X776797Y313582D02*
G03X776244Y313565I-268J-297D01*
G02X774069Y315637I-1073J1051D01*
G03X774082Y316166I-293J272D01*
G02X774100Y318120I1150J966D01*
G03Y318646I-302J263D01*
G02X776364I1132J987D01*
G03Y318120I302J-263D01*
G02X776216Y315998I-1132J-987D01*
G03X776208Y315702I131J-152D01*
G02X776301Y315606I-1031J-1092D01*
G03X776610Y315616I150J132D01*
G02X776797Y313582I1190J-916D01*
G37*
G36*
G01X772396Y309446D02*
G03X772325Y308851I227J-329D01*
G02X770482Y309072I-1047J-933D01*
G03X770553Y309667I-227J329D01*
G02X772396Y309446I1047J933D01*
G37*
G36*
G01X776293Y283614D02*
G03X776590Y283612I149J133D01*
G02X776694Y281484I1110J-1012D01*
G03X776162Y281488I-268J-297D01*
G02X774069Y283637I-991J1129D01*
G03X774082Y284166I-293J272D01*
G02X774100Y286120I1150J966D01*
G03Y286646I-302J263D01*
G02X776364I1132J987D01*
G03Y286120I302J-263D01*
G02X776216Y283998I-1132J-987D01*
G03X776208Y283702I131J-152D01*
G02X776293Y283614I-1037J-1086D01*
G37*
G36*
G01X746896Y281538D02*
G02X752004Y280262I2904J762D01*
G02X746896Y281538I-2904J-762D01*
G37*
G36*
G01X778572Y275068D02*
G03X777973Y274913I-236J-323D01*
G02X777528Y276632I-1273J588D01*
G03X778127Y276787I236J323D01*
G02X778572Y275068I1273J-588D01*
G37*
G36*
G01X752199Y274925D02*
G02X757405Y274771I2647J1415D01*
G02X752199Y274925I-2647J-1415D01*
G37*
G36*
G01X746387Y268945D02*
G02X751693Y268755I2703J1305D01*
G02X746387Y268945I-2703J-1305D01*
G37*
G36*
G01X752813Y251578D02*
G02X750240Y251423I-1450J2629D01*
G02X746261Y255750I-1540J2577D01*
G02X751686Y257192I2439J1750D01*
G02X752813Y256836I-323J-2985D01*
G02Y251578I1450J-2629D01*
G37*
G36*
G01X766693Y253259D02*
G03X766354Y252751I45J-397D01*
G02X764846Y253756I-1347J-388D01*
G03X765185Y254264I-45J397D01*
G02X765602Y255701I1347J388D01*
G03X765624Y256278I-266J299D01*
G02X767562Y256203I1008J974D01*
G03X767540Y255626I266J-299D01*
G02X766693Y253259I-1008J-974D01*
G37*
G36*
G01X776293Y251614D02*
G03X776590Y251612I149J133D01*
G02X776694Y249484I1110J-1012D01*
G03X776162Y249488I-268J-297D01*
G02X774069Y251637I-991J1129D01*
G03X774082Y252166I-293J272D01*
G02X774100Y254120I1150J966D01*
G03Y254646I-302J263D01*
G02X776364I1132J987D01*
G03Y254120I302J-263D01*
G02X776216Y251998I-1132J-987D01*
G03X776208Y251702I131J-152D01*
G02X776293Y251614I-1037J-1086D01*
G37*
G36*
G01X740938Y250822D02*
G03X740950Y250128I205J-344D01*
G02X737962Y250078I-1450J-2628D01*
G03X737950Y250772I-205J344D01*
G02X740938Y250822I1450J2628D01*
G37*
G36*
G01X747300Y242136D02*
G03X747304Y241569I284J-282D01*
G02X745324Y241555I-983J-1000D01*
G03X745320Y242122I-284J282D01*
G02X747300Y242136I983J1000D01*
G37*
G36*
G01X737666Y239369D02*
G03X737663Y238836I297J-268D01*
G02X735571Y238847I-1051J-928D01*
G03X735574Y239380I-297J268D01*
G02X737666Y239369I1051J928D01*
G37*
G36*
G01X767662Y224140D02*
G03X767640Y223563I266J-299D01*
G02X765702Y223638I-1008J-974D01*
G03X765724Y224215I-266J299D01*
G02X767662Y224140I1008J974D01*
G37*
G36*
G01X776293Y219614D02*
G03X776590Y219612I149J133D01*
G02X776694Y217484I1110J-1012D01*
G03X776162Y217488I-268J-297D01*
G02X774069Y219637I-991J1129D01*
G03X774082Y220166I-293J272D01*
G02X774100Y222120I1150J966D01*
G03Y222646I-302J263D01*
G02X776364I1132J987D01*
G03Y222120I302J-263D01*
G02X776216Y219998I-1132J-987D01*
G03X776208Y219702I131J-152D01*
G02X776293Y219614I-1037J-1086D01*
G37*
G36*
G01X707632Y216413D02*
G03Y215887I302J-263D01*
G02X705368I-1132J-987D01*
G03Y216413I-302J263D01*
G02X705398Y218421I1132J987D01*
G03X705411Y218950I-293J272D01*
G02X707663Y218896I1150J967D01*
G03X707650Y218367I293J-272D01*
G02X707632Y216413I-1150J-966D01*
G37*
G36*
G01X766290Y380798D02*
G02X764936Y381765I-1333J-435D01*
G03X765310Y382289I-6J400D01*
G02X766009Y383974I1333J435D01*
G03X766122Y384602I-181J357D01*
G02X767789Y384300I1033J948D01*
G03X767676Y383672I181J-357D01*
G02X766664Y381322I-1033J-948D01*
G03X766290Y380798I6J-400D01*
G37*
G36*
G01X764923Y374919D02*
G02X763374Y374904I-763J-1176D01*
G03X763367Y375571I-224J331D01*
G02X764916Y375586I763J1176D01*
G03X764923Y374919I224J-331D01*
G37*
G36*
G01X761107Y361064D02*
G02X759612Y360885I-607J-1264D01*
G03X759533Y361555I-253J310D01*
G02X761028Y361734I607J1264D01*
G03X761107Y361064I253J-310D01*
G37*
G36*
G01X775465Y339137D02*
G02X775435Y340868I-1118J846D01*
G03X776064Y340879I310J252D01*
G02X778252Y340939I1118J-846D01*
G03X778862I305J259D01*
G02Y339127I1070J-906D01*
G03X778252I-305J-259D01*
G02X776094Y339148I-1070J906D01*
G03X775465Y339137I-310J-252D01*
G37*
G36*
G01X764141Y339743D02*
G02X763234Y340819I-1381J-244D01*
G03X763763Y341265I135J377D01*
G02X764359Y342669I1381J242D01*
G03X764352Y343336I-224J331D01*
G02X765901Y343351I763J1176D01*
G03X765908Y342684I224J-331D01*
G02X764670Y340189I-764J-1176D01*
G03X764141Y339743I-135J-377D01*
G37*
G36*
G01X766382Y316635D02*
G02X765182Y317754I-1375J-272D01*
G03X765625Y318228I50J397D01*
G02X765973Y319454I1375J272D01*
G03X765913Y320051I-293J272D01*
G02X767759Y320235I819J1138D01*
G03X767819Y319638I293J-272D01*
G02X766825Y317109I-819J-1138D01*
G03X766382Y316635I-50J-397D01*
G37*
G36*
G01X765908Y310684D02*
G02X764359Y310669I-763J-1176D01*
G03X764352Y311336I-224J331D01*
G02X765901Y311351I763J1176D01*
G03X765908Y310684I224J-331D01*
G37*
G36*
G01X777591Y306631D02*
G02X777150Y308191I-1321J469D01*
G03X777779Y308369I252J311D01*
G02X778220Y306809I1321J-469D01*
G03X777591Y306631I-252J-311D01*
G37*
G36*
G01X766364Y284716D02*
G02X765442Y285696I-1357J-353D01*
G03X765953Y286177I124J380D01*
G02X765923Y286323I1357J355D01*
G03X765406Y286644I-395J-60D01*
G02X766367Y288187I-426J1336D01*
G03X766884Y287866I395J60D01*
G02X766875Y285197I426J-1336D01*
G03X766364Y284716I-124J-380D01*
G37*
G36*
G01X765908Y278684D02*
G02X764359Y278669I-763J-1176D01*
G03X764352Y279336I-224J331D01*
G02X765901Y279351I763J1176D01*
G03X765908Y278684I224J-331D01*
G37*
G36*
G01Y246684D02*
G02X764359Y246669I-763J-1176D01*
G03X764352Y247336I-224J331D01*
G02X765901Y247351I763J1176D01*
G03X765908Y246684I224J-331D01*
G37*
G36*
G01X778282Y242932D02*
G02X778000Y244483I-1282J568D01*
G03X778650Y244601I285J281D01*
G02X778932Y243050I1282J-568D01*
G03X778282Y242932I-285J-281D01*
G37*
G36*
G01X765908Y214684D02*
G02X764359Y214669I-763J-1176D01*
G03X764352Y215336I-224J331D01*
G02X765901Y215351I763J1176D01*
G03X765908Y214684I224J-331D01*
G37*
G36*
G01X1069992Y337612D02*
G03X1069392I-300J-265D01*
G02Y339734I-1200J1061D01*
G03X1069992I300J265D01*
G02Y337612I1200J-1061D01*
G37*
G36*
G01X1062792D02*
G03X1062192I-300J-265D01*
G02Y339734I-1200J1061D01*
G03X1062792I300J265D01*
G02Y337612I1200J-1061D01*
G37*
G36*
G01X1079082Y337472D02*
G03X1078482I-300J-265D01*
G02Y339594I-1200J1061D01*
G03X1079082I300J265D01*
G02Y337472I1200J-1061D01*
G37*
G36*
G01X844127Y330490D02*
G03X843573I-277J-288D01*
G02Y332510I-973J1010D01*
G03X844127I277J288D01*
G02X846073I973J-1010D01*
G03X846627I277J288D01*
G02Y330490I973J-1010D01*
G03X846073I-277J-288D01*
G02X844127I-973J1010D01*
G37*
G36*
G01X1017937Y325288D02*
G03X1017717Y324783I156J-368D01*
G02X1015855Y325596I-1318J-479D01*
G03X1016075Y326101I-156J368D01*
G02X1018366Y327590I1318J480D01*
G03X1018920I277J288D01*
G02X1020866I973J-1010D01*
G03X1021420I277J288D01*
G02X1023366I973J-1010D01*
G03X1023920I277J288D01*
G02X1024287Y327844I971J-1011D01*
G03X1024479Y328371I-172J361D01*
G02X1026567Y330094I1276J580D01*
G03X1027153Y330233I232J326D01*
G02X1028642Y328200I1240J-653D01*
G03X1028420Y327534I71J-394D01*
G02X1026420Y325570I-1027J-955D01*
G03X1025866I-277J-288D01*
G02X1023920I-973J1010D01*
G03X1023366I-277J-288D01*
G02X1021420I-973J1010D01*
G03X1020866I-277J-288D01*
G02X1018920I-973J1010D01*
G03X1018366I-277J-288D01*
G02X1017937Y325288I-972J1011D01*
G37*
G36*
G01X1077820Y323113D02*
G03X1077220I-300J-265D01*
G02Y325235I-1200J1061D01*
G03X1077820I300J265D01*
G02Y323113I1200J-1061D01*
G37*
G36*
G01X1017207Y311236D02*
G03X1016654Y311109I-213J-338D01*
G02X1016286Y313212I-1361J846D01*
G03X1016850Y313281I248J314D01*
G02X1018914Y313445I1107J-860D01*
G03X1019458Y313442I274J292D01*
G02X1021395Y313399I946J-1034D01*
G03X1021953Y313391I283J283D01*
G02X1023893Y313377I963J-1019D01*
G03X1024453Y313379I279J286D01*
G02X1026438Y313364I985J-998D01*
G03X1027015Y313371I285J281D01*
G02X1027039Y311431I1024J-957D01*
G03X1026462Y311424I-285J-281D01*
G02X1024460Y311376I-1025J957D01*
G03X1023900Y311374I-279J-286D01*
G02X1021924Y311381I-984J998D01*
G03X1021366Y311389I-283J-283D01*
G02X1019447Y311384I-962J1019D01*
G03X1018903Y311387I-274J-292D01*
G02X1017207Y311236I-947J1034D01*
G37*
G36*
G01X844127Y298890D02*
G03X843573I-277J-288D01*
G02Y300910I-973J1010D01*
G03X844127I277J288D01*
G02X846073I973J-1010D01*
G03X846627I277J288D01*
G02Y298890I973J-1010D01*
G03X846073I-277J-288D01*
G02X844127I-973J1010D01*
G37*
G36*
G01X1055367Y294798D02*
G03X1054767I-300J-265D01*
G02Y296920I-1200J1061D01*
G03X1055367I300J265D01*
G02Y294798I1200J-1061D01*
G37*
G36*
G01X1048167D02*
G03X1047567I-300J-265D01*
G02Y296920I-1200J1061D01*
G03X1048167I300J265D01*
G02Y294798I1200J-1061D01*
G37*
G36*
G01X1040967D02*
G03X1040367I-300J-265D01*
G02Y296920I-1200J1061D01*
G03X1040967I300J265D01*
G02Y294798I1200J-1061D01*
G37*
G36*
G01X1033767D02*
G03X1033167I-300J-265D01*
G02Y296920I-1200J1061D01*
G03X1033767I300J265D01*
G02Y294798I1200J-1061D01*
G37*
G36*
G01X1026567D02*
G03X1025967I-300J-265D01*
G02Y296920I-1200J1061D01*
G03X1026567I300J265D01*
G02Y294798I1200J-1061D01*
G37*
G36*
G01X1019367D02*
G03X1018767I-300J-265D01*
G02Y296920I-1200J1061D01*
G03X1019367I300J265D01*
G02Y294798I1200J-1061D01*
G37*
G36*
G01X1077135Y292127D02*
G03X1076469I-333J-222D01*
G02X1074327Y293911I-1167J777D01*
G03X1074272Y294530I-278J287D01*
G02X1076367Y296920I895J1329D01*
G03X1076967I300J265D01*
G02X1079179Y294617I1200J-1061D01*
G03X1079181Y293996I253J-310D01*
G02X1077135Y292127I-879J-1092D01*
G37*
G36*
G01X1069935D02*
G03X1069269I-333J-222D01*
G02X1067127Y293911I-1167J777D01*
G03X1067072Y294530I-278J287D01*
G02X1069167Y296920I895J1329D01*
G03X1069767I300J265D01*
G02X1071979Y294617I1200J-1061D01*
G03X1071981Y293996I253J-310D01*
G02X1069935Y292127I-879J-1092D01*
G37*
G36*
G01X1062735D02*
G03X1062069I-333J-222D01*
G02X1059927Y293911I-1167J777D01*
G03X1059872Y294530I-278J287D01*
G02X1061967Y296920I895J1329D01*
G03X1062567I300J265D01*
G02X1064779Y294617I1200J-1061D01*
G03X1064781Y293996I253J-310D01*
G02X1062735Y292127I-879J-1092D01*
G37*
G36*
G01X1077102Y277849D02*
G03X1076502I-300J-265D01*
G02Y279971I-1200J1061D01*
G03X1077102I300J265D01*
G02Y277849I1200J-1061D01*
G37*
G36*
G01X1069668Y277918D02*
G03X1069041I-314J-248D01*
G02Y279902I-1258J992D01*
G03X1069668I314J248D01*
G02Y277918I1258J-992D01*
G37*
G36*
G01X1062574Y277725D02*
G03X1062036I-269J-296D01*
G02Y280095I-1078J1185D01*
G03X1062574I269J296D01*
G02Y277725I1078J-1185D01*
G37*
G36*
G01X1026702Y277843D02*
G03X1026102I-300J-265D01*
G02Y279965I-1200J1061D01*
G03X1026702I300J265D01*
G02Y277843I1200J-1061D01*
G37*
G36*
G01X1019502D02*
G03X1018902I-300J-265D01*
G02Y279965I-1200J1061D01*
G03X1019502I300J265D01*
G02Y277843I1200J-1061D01*
G37*
G36*
G01X1031550Y272689D02*
G03Y272089I265J-300D01*
G02X1029428I-1061J-1200D01*
G03Y272689I-265J300D01*
G02X1031550I1061J1200D01*
G37*
G36*
G01X844127Y267190D02*
G03X843573I-277J-288D01*
G02Y269210I-973J1010D01*
G03X844127I277J288D01*
G02X846073I973J-1010D01*
G03X846627I277J288D01*
G02Y267190I973J-1010D01*
G03X846073I-277J-288D01*
G02X844127I-973J1010D01*
G37*
G36*
G01X1080905Y265934D02*
G03X1081449Y265885I298J266D01*
G02X1081125Y263694I983J-1265D01*
G03X1080590Y263804I-326J-231D01*
G02X1080905Y265934I-731J1196D01*
G37*
G36*
G01X848610Y239927D02*
G03Y239373I288J-277D01*
G02X846590I-1010J-973D01*
G03Y239927I-288J277D01*
G02Y241873I1010J973D01*
G03Y242427I-288J277D01*
G02X848610I1010J973D01*
G03Y241873I288J-277D01*
G02Y239927I-1010J-973D01*
G37*
G36*
G01X842410Y239827D02*
G03Y239273I288J-277D01*
G02X840390I-1010J-973D01*
G03Y239827I-288J277D01*
G02Y241773I1010J973D01*
G03Y242327I-288J277D01*
G02X842410I1010J973D01*
G03Y241773I288J-277D01*
G02Y239827I-1010J-973D01*
G37*
G36*
G01X1048923Y337564D02*
G02Y339118I-1167J777D01*
G03X1049589I333J222D01*
G02X1051885Y339173I1167J-777D01*
G03X1052539Y339187I322J237D01*
G02X1054735Y339352I1163J-783D01*
G03X1055382Y339433I295J270D01*
G02X1055534Y337681I1410J-760D01*
G03X1054883Y337649I-314J-248D01*
G02X1052573Y337572I-1181J755D01*
G03X1051919Y337558I-322J-237D01*
G02X1049589Y337564I-1163J783D01*
G03X1048923I-333J-222D01*
G37*
G36*
G01X1036980Y323069D02*
G02Y325279I-1160J1105D01*
G03X1037560I290J275D01*
G02X1039820Y325338I1160J-1105D01*
G03X1040370I275J291D01*
G02X1042570I1100J-1164D01*
G03X1043120I275J291D01*
G02X1045420Y325235I1100J-1164D01*
G03X1046020I300J265D01*
G02X1048420I1200J-1061D01*
G03X1049020I300J265D01*
G02X1051420I1200J-1061D01*
G03X1052020I300J265D01*
G02X1054420I1200J-1061D01*
G03X1055020I300J265D01*
G02X1057420I1200J-1061D01*
G03X1058020I300J265D01*
G02X1060420I1200J-1061D01*
G03X1061020I300J265D01*
G02X1063420I1200J-1061D01*
G03X1064020I300J265D01*
G02X1066660Y324875I1200J-1061D01*
G03X1067380I360J175D01*
G02X1070020Y325235I1440J-701D01*
G03X1070620I300J265D01*
G02Y323113I1200J-1061D01*
G03X1070020I-300J-265D01*
G02X1067380Y323473I-1200J1061D01*
G03X1066660I-360J-175D01*
G02X1064020Y323113I-1440J701D01*
G03X1063420I-300J-265D01*
G02X1061020I-1200J1061D01*
G03X1060420I-300J-265D01*
G02X1058020I-1200J1061D01*
G03X1057420I-300J-265D01*
G02X1055020I-1200J1061D01*
G03X1054420I-300J-265D01*
G02X1052020I-1200J1061D01*
G03X1051420I-300J-265D01*
G02X1049020I-1200J1061D01*
G03X1048420I-300J-265D01*
G02X1046020I-1200J1061D01*
G03X1045420I-300J-265D01*
G02X1043120Y323010I-1200J1061D01*
G03X1042570I-275J-291D01*
G02X1040370I-1100J1164D01*
G03X1039820I-275J-291D01*
G02X1037560Y323069I-1100J1164D01*
G03X1036980I-290J-275D01*
G37*
G36*
G01X1076469Y309127D02*
G02Y310681I-1167J777D01*
G03X1077135I333J222D01*
G02Y309127I1167J-777D01*
G03X1076469I-333J-222D01*
G37*
G36*
G01X1069269D02*
G02Y310681I-1167J777D01*
G03X1069935I333J222D01*
G02Y309127I1167J-777D01*
G03X1069269I-333J-222D01*
G37*
G36*
G01X1062069D02*
G02Y310681I-1167J777D01*
G03X1062735I333J222D01*
G02Y309127I1167J-777D01*
G03X1062069I-333J-222D01*
G37*
G36*
G01X1054717Y277918D02*
G02X1052004Y278239I-1258J992D01*
G03X1051287Y278257I-363J-168D01*
G02X1051322Y279670I-1420J742D01*
G03X1052039Y279652I363J168D01*
G02X1054717Y279902I1420J-742D01*
G03X1055344I314J248D01*
G02Y277918I1258J-992D01*
G03X1054717I-314J-248D01*
G37*
G36*
G01X1037239Y278042D02*
G02X1037181Y279611I-1425J733D01*
G03X1037877Y279637I341J209D01*
G02X1040502Y279965I1425J-733D01*
G03X1041102I300J265D01*
G02Y277843I1200J-1061D01*
G03X1040502I-300J-265D01*
G02X1037935Y278068I-1200J1061D01*
G03X1037239Y278042I-341J-209D01*
G37*
G36*
G01X1113707Y314299D02*
G03X1113702Y313770I298J-267D01*
G02X1111298Y313793I-1212J-1047D01*
G03X1111303Y314322I-298J267D01*
G02X1113707Y314299I1212J1047D01*
G37*
G36*
G01X1109706Y275861D02*
G03X1109146Y275838I-268J-297D01*
G02X1109067Y277837I-1021J961D01*
G03X1109627Y277860I268J297D01*
G02X1109706Y275861I1021J-961D01*
G37*
G36*
G01X1115777Y297174D02*
G02X1114706Y295993I319J-1365D01*
G03X1114219Y296435I-397J52D01*
G02X1115290Y297616I-319J1365D01*
G03X1115777Y297174I397J-52D01*
G37*
G36*
G01X1118706Y287537D02*
G02X1118374Y285590I815J-1141D01*
G03X1117814Y285685I-327J-230D01*
G02X1115684Y287313I-815J1141D01*
G03X1115292Y287851I-375J139D01*
G02X1116545Y288765I-62J1401D01*
G03X1116937Y288227I375J-139D01*
G02X1118146Y287632I62J-1401D01*
G03X1118706Y287537I327J230D01*
G37*
G36*
G01X1106266Y267436D02*
G02X1105569Y268516I-1395J-136D01*
G03X1106166Y268902I199J347D01*
G02X1106724Y270163I1395J137D01*
G03X1106733Y270798I-238J321D01*
G02X1108437Y270775I867J1102D01*
G03X1108428Y270140I238J-321D01*
G02X1106863Y267822I-866J-1102D01*
G03X1106266Y267436I-199J-347D01*
G37*
G36*
G01X1096538Y267024D02*
G02X1094862I-838J-1124D01*
G03Y267666I-239J321D01*
G02X1096538I838J1124D01*
G03Y267024I239J-321D01*
G37*
G36*
G01X1265136Y151576D02*
G03X1265691Y151567I282J284D01*
G02X1265656Y149548I955J-1026D01*
G03X1265101Y149557I-282J-284D01*
G02X1263135Y149613I-955J1027D01*
G03X1262557I-289J-277D01*
G02Y151555I-1011J971D01*
G03X1263135I289J277D01*
G02X1265136Y151576I1011J-971D01*
G37*
G36*
G01X1278933Y147438D02*
G03X1278927Y146832I258J-306D01*
G02X1277097Y146852I-927J-1052D01*
G03X1277103Y147458I-258J306D01*
G02X1278933Y147438I927J1052D01*
G37*
G36*
G01X1263621Y155695D02*
G02X1263522Y154039I1079J-895D01*
G03X1262879Y154078I-336J-217D01*
G02X1262978Y155734I-1079J895D01*
G03X1263621Y155695I336J217D01*
G37*
G36*
G01X1370996Y395697D02*
G03X1370418I-289J-277D01*
G02Y397639I-1011J971D01*
G03X1370996I289J277D01*
G02Y395697I1011J-971D01*
G37*
G36*
G01X1375339Y386481D02*
G03Y385955I302J-263D01*
G02X1373075I-1132J-987D01*
G03Y386481I-302J263D01*
G02X1373105Y388489I1132J987D01*
G03X1373118Y389018I-293J272D01*
G02X1375370Y388964I1150J967D01*
G03X1375357Y388435I293J-272D01*
G02X1375339Y386481I-1150J-966D01*
G37*
G36*
G01X1385364Y578200D02*
G03X1385695Y577683I381J-120D01*
G02X1387825Y576353I-379J-2978D01*
G02X1389002Y575926I161J-1393D01*
G03X1389588Y575931I291J275D01*
G02X1389607Y574020I1035J-945D01*
G03X1389021Y574015I-291J-275D01*
G02X1388092Y573562I-1036J945D01*
G02X1383278Y572501I-2776J1143D01*
G02X1380136Y577250I-778J2899D01*
G02X1379623Y579957I2364J1850D01*
G03X1379198Y580470I-383J115D01*
G02X1379783Y583061I-145J1394D01*
G03X1380354Y583233I209J341D01*
G02X1385359Y580016I2720J-1270D01*
G02X1385364Y578200I-2859J-916D01*
G37*
G36*
G01X1377132Y574469D02*
G03Y573943I302J-263D01*
G02X1374868I-1132J-987D01*
G03Y574469I-302J263D01*
G02X1374859Y576432I1132J987D01*
G03X1374850Y576962I-304J260D01*
G02X1377102Y576997I1111J1011D01*
G03X1377111Y576467I304J-260D01*
G02X1377132Y574469I-1111J-1011D01*
G37*
G36*
G01X1679335Y129709D02*
G02X1678917Y128429I1067J-1057D01*
G03X1678254Y128668I-396J-59D01*
G02X1678660Y129908I-868J971D01*
G03X1679335Y129709I391J83D01*
G37*
G36*
G01X1727611Y123133D02*
G02X1727597Y124391I-1147J616D01*
G03X1728297Y124399I348J197D01*
G02X1728311Y123141I1147J-616D01*
G03X1727611Y123133I-348J-197D01*
G37*
G36*
G01X1939883Y478311D02*
G03Y477689I252J-311D01*
G02X1938117I-883J-1089D01*
G03Y478311I-252J311D01*
G02X1939883I883J1089D01*
G37*
G36*
G01X1915424Y468001D02*
G03X1916048I312J250D01*
G02X1916047Y465998I1250J-1002D01*
G03X1915423I-312J-250D01*
G02X1912903Y466023I-1250J1002D01*
G03X1912269I-317J-243D01*
G02Y467977I-1270J977D01*
G03X1912903I317J243D01*
G02X1915424Y468001I1270J-977D01*
G37*
G36*
G01X1911277Y473167D02*
G02X1909723I-777J-1167D01*
G03Y473833I-222J333D01*
G02X1911277I777J1167D01*
G03Y473167I222J-333D01*
G37*
G36*
G01X1905949Y453741D02*
G02Y455103I-1225J681D01*
G03X1906649I350J194D01*
G02Y453741I1225J-681D01*
G03X1905949I-350J-194D01*
G37*
G54D49*
X388187Y13078D03*
Y608555D03*
Y589679D03*
G54D50*
X401375Y-1743D03*
X404722Y-4536D03*
X414761Y-1743D03*
X394682Y11792D03*
X394683Y-2200D03*
X438187Y-4536D03*
X444880D03*
X460912Y-4100D03*
X458266Y17157D03*
X481691Y-9901D03*
X454533Y-4100D03*
X478344Y-3700D03*
X474998Y17157D03*
Y-9901D03*
X428147Y-1743D03*
X434840D03*
X485037Y-3700D03*
X497723Y-4100D03*
X495077Y-9901D03*
X521848Y-3700D03*
X518502Y-9901D03*
X491344Y-4100D03*
X488384Y-9901D03*
X515155Y-3700D03*
X511809Y-9901D03*
X534534Y-4100D03*
X531888Y-9901D03*
X528155Y-4100D03*
X525195Y-9901D03*
X558659Y-3700D03*
X555313Y17157D03*
Y-9901D03*
X551966Y-3700D03*
X548620Y17157D03*
Y-9901D03*
X571345Y-4100D03*
X568699Y17157D03*
Y-9901D03*
X595470Y-3700D03*
X592124Y17157D03*
Y-9901D03*
X564966Y-4100D03*
X561868Y17019D03*
X562006Y-9901D03*
X588777Y-3700D03*
X585431Y17157D03*
Y-9901D03*
X394682Y588392D03*
X404722Y604499D03*
X401376Y612658D03*
X414761Y607292D03*
X398029Y604499D03*
X404722Y609864D03*
X414761Y612657D03*
X408068Y607292D03*
X394682Y612657D03*
X438187Y609864D03*
X431494Y604499D03*
X444880Y604614D03*
Y609864D03*
X458266Y593757D03*
X460912Y610300D03*
X458266Y604499D03*
X481691D03*
X454533Y610300D03*
X451573Y593757D03*
Y604499D03*
X474998Y593757D03*
Y604499D03*
X428147Y612657D03*
X421454Y607292D03*
X434840Y612657D03*
X424801Y604614D03*
X438187D03*
X485037Y610700D03*
X498092Y611200D03*
X495077Y604499D03*
X521848Y610700D03*
X518502Y604499D03*
X491724Y611668D03*
X488384Y604499D03*
X515155Y610700D03*
X511809Y604499D03*
X534534Y610300D03*
X531888Y604499D03*
X528155Y610300D03*
X525195Y604499D03*
X558659Y610700D03*
X555313Y604499D03*
X551966Y610700D03*
X548620Y604499D03*
X571345Y610300D03*
X568699Y604499D03*
X595470Y610700D03*
X592124Y604499D03*
X564966Y610300D03*
X562006Y604499D03*
X588777Y610700D03*
X585431Y604499D03*
X1709000Y127200D03*
G54D47*
X40132Y499800D03*
X27280Y510420D03*
X60300Y508650D03*
X51607Y511747D03*
X57936Y516012D03*
G54D45*
X251213Y646784D03*
Y652784D03*
X261125Y646784D03*
Y652784D03*
X389473Y646508D03*
Y652508D03*
X379561Y646508D03*
Y652508D03*
X951795Y652234D03*
Y646234D03*
X941883D03*
Y652234D03*
X1196198Y652206D03*
Y646206D03*
X1206110D03*
Y652206D03*
X19800Y257900D03*
X98149Y399769D03*
X102456Y393756D03*
X114084Y399937D03*
X773419Y270414D03*
X753098Y338316D03*
X757500Y374000D03*
X1032102Y278904D03*
X1083220Y324174D03*
X1919230Y483430D03*
G54D52*
X761580Y220160D03*
G54D53*
X1645378Y128378D03*
X1654678Y137530D03*
X1654686Y134389D03*
X1654685Y131239D03*
X1651536Y134388D03*
Y131239D03*
X1651532Y137534D03*
X1674685Y134217D03*
X1657835Y134389D03*
X1667284Y128089D03*
Y137537D03*
X1660986Y137538D03*
X1664136D03*
X1667284Y131239D03*
X1664135Y128089D03*
X1660985Y131239D03*
X1677386Y132788D03*
X1657836Y137538D03*
X1742212Y117451D03*
X1745364Y120600D03*
X1742214Y126900D03*
X1720164Y126800D03*
Y133200D03*
Y120600D03*
X1723314Y117450D03*
X1731903Y133712D03*
X1735989Y133250D03*
X1728789Y136250D03*
X1739064Y126900D03*
X1723314Y130050D03*
Y126900D03*
X1726464Y133200D03*
X1739064Y120600D03*
Y123750D03*
X1726464Y120600D03*
X1742214D03*
X1723314Y120601D03*
X1735912Y123750D03*
X1739064Y117450D03*
X1735914D03*
X1739064Y130050D03*
X1723314Y133200D03*
X1742214Y130050D03*
Y123750D03*
X1745364D03*
X1723314D03*
X1720164D03*
Y117451D03*
X1726464Y117450D03*
X1746189Y131624D03*
X1745364Y117450D03*
X1717014Y133200D03*
G54D44*
X5120Y276058D03*
X2269Y273532D03*
X1500Y295000D03*
X19904Y254162D03*
X37000Y265350D03*
X33490Y267900D03*
X37000Y275000D03*
X110397Y402603D03*
X109640Y376070D03*
X103100Y411800D03*
X118800Y298400D03*
X122361Y342649D03*
X119300Y400900D03*
X118220Y360500D03*
X291519Y285160D03*
Y292959D03*
X284759Y285160D03*
X277999Y300760D03*
Y292959D03*
Y285160D03*
X291519Y308560D03*
X284759Y300760D03*
X291519D03*
X284759Y292959D03*
X321938Y283209D03*
X315178D03*
X318558Y281260D03*
X328698Y283209D03*
X332078Y281260D03*
X325318D03*
X338838D03*
X335458Y283209D03*
X345598Y265660D03*
X348978Y263709D03*
X345598Y273460D03*
Y269560D03*
X342218Y271509D03*
Y267609D03*
Y283209D03*
Y279310D03*
Y275409D03*
X338838Y273460D03*
Y269560D03*
X335458Y275409D03*
X338838Y277360D03*
X332078D03*
X335458Y279310D03*
X311798Y292959D03*
X305039D03*
X318558D03*
X311798Y285160D03*
X328698Y310509D03*
X332078Y300760D03*
Y292959D03*
X298279Y308560D03*
X321938Y310509D03*
X315178D03*
X305039Y308560D03*
X311798D03*
X305039Y300760D03*
X325318D03*
X311798D03*
X298279D03*
X318558D03*
X325318Y292959D03*
X305039Y285160D03*
X298279D03*
Y292959D03*
X318558Y312460D03*
X325318D03*
X315178Y314409D03*
X332078Y312460D03*
X335458Y310509D03*
X338838Y300760D03*
Y292959D03*
X342218Y310509D03*
Y314409D03*
X338838Y312460D03*
Y316360D03*
X345598Y328060D03*
X342218Y322209D03*
Y318309D03*
X355737Y337809D03*
X345598Y320260D03*
Y324160D03*
X328698Y314409D03*
X321938D03*
X335458D03*
X338838Y320260D03*
X419214Y249347D03*
X415634Y247396D03*
X359117Y339760D03*
X362497Y341709D03*
X365877Y343660D03*
X422594Y251296D03*
X441743Y348497D03*
X445123Y346546D03*
X427094Y352696D03*
X352357Y238360D03*
X345598D03*
X355737Y248109D03*
X348978D03*
X355737Y259809D03*
X348978Y236409D03*
Y240309D03*
X352357Y234460D03*
X345598Y242260D03*
Y234460D03*
X342218Y240309D03*
Y236409D03*
X352357Y246160D03*
X345598D03*
X355737Y236409D03*
X352357Y242260D03*
X355737Y240309D03*
X352357Y250060D03*
X345598D03*
X355737Y252009D03*
X348978D03*
X352357Y253960D03*
X345598D03*
X355737Y255909D03*
X348978D03*
X342218Y252009D03*
Y248109D03*
X379397Y238360D03*
Y250060D03*
X386157Y238360D03*
X372637Y250060D03*
X389537Y248109D03*
X376017D03*
X382777D03*
X386157Y250060D03*
X359117Y238360D03*
X365877D03*
X372637D03*
X365877Y253960D03*
X362497Y255909D03*
X359117Y257860D03*
X369257Y252009D03*
X392916Y250060D03*
Y238360D03*
X396296Y248109D03*
X399676Y250060D03*
X407706Y248109D03*
X396296Y244209D03*
Y240309D03*
X365877Y242260D03*
X407706Y236409D03*
X372637Y234460D03*
X365877D03*
X369257Y236409D03*
X362497D03*
X389537D03*
X399676Y234460D03*
X382777Y236409D03*
X376017D03*
X369257Y240309D03*
X376017D03*
X372637Y242260D03*
X379397Y234460D03*
X399676Y238360D03*
X359117Y242260D03*
X362497Y240309D03*
X359117Y234460D03*
Y246160D03*
X386157Y234460D03*
X392916D03*
X396296Y236409D03*
X372637Y253960D03*
X376017Y252009D03*
X368127Y264300D03*
X362497Y259809D03*
X365877Y257860D03*
X369257Y255909D03*
X391787Y254259D03*
X388407Y256500D03*
X374887Y260300D03*
X385027Y254259D03*
X359117Y261760D03*
X371507Y262300D03*
X381647Y256400D03*
X378267Y258400D03*
X395166Y256400D03*
X398546Y254259D03*
X405306Y254500D03*
X401926Y256500D03*
X399676Y242260D03*
X362497Y248109D03*
X359117Y250060D03*
Y253960D03*
X389537Y240309D03*
X382777D03*
X392916Y242260D03*
X386157D03*
X379397D03*
X389537Y244209D03*
X382777D03*
X376017D03*
X392916Y246160D03*
X386157D03*
X379397D03*
X372637D03*
X365877D03*
X369257Y248109D03*
X365877Y250060D03*
X362497Y252009D03*
X407706Y244209D03*
X399676Y246160D03*
X380200Y-1200D03*
X408184Y13200D03*
X404723Y17057D03*
X401376Y9121D03*
X414762Y17058D03*
X398029Y17042D03*
X404722Y9121D03*
X414763Y9122D03*
X408069Y17042D03*
X398029Y-4536D03*
X408068Y-1743D03*
X418108Y-4536D03*
X398029Y9107D03*
X411416Y17057D03*
X401376Y17042D03*
X418108D03*
Y9107D03*
X408069D03*
X411415Y-4536D03*
X411416Y9122D03*
X394682Y17157D03*
X451573Y-1801D03*
Y9114D03*
X433508Y13200D03*
X421368D03*
X458266Y-1751D03*
X474998D03*
X481691D03*
X478344Y-7851D03*
X481691Y9114D03*
X474998D03*
X458116D03*
X421455Y9121D03*
X421454Y-1817D03*
X438187Y9120D03*
X431494Y17042D03*
X444880Y17059D03*
Y9122D03*
X428147Y9120D03*
X421456Y17057D03*
X434840Y9120D03*
X424801Y17042D03*
X438187Y17059D03*
X431494Y-4536D03*
X424801D03*
X441533Y-1843D03*
X434842Y17057D03*
X441533Y17042D03*
X428149Y17057D03*
X441533Y9107D03*
X424801D03*
X431494D03*
X511809Y-1751D03*
X495077D03*
X488384Y-1801D03*
X485037Y-7851D03*
X491344D03*
X497723Y-7700D03*
X488384Y9114D03*
X515155Y-7851D03*
X518502Y-1751D03*
X521848Y-7851D03*
X531888Y-1751D03*
X525195Y-1801D03*
X528155Y-7851D03*
X534534Y-7700D03*
X531738Y9114D03*
X525195D03*
X562006D03*
X568549D03*
X555313D03*
X548620D03*
X571345Y-7700D03*
X551966Y-7851D03*
X564966D03*
X558659D03*
X562006Y-1801D03*
X588777Y-7851D03*
X598817Y-9901D03*
X595470Y-7851D03*
X592124Y-1751D03*
X598817D03*
X585431D03*
X602163Y-9901D03*
X598817Y9157D03*
X592124Y9114D03*
X585431D03*
X602163Y16999D03*
X548620Y-1751D03*
X568699D03*
X555313D03*
X598817Y17057D03*
X602163Y9157D03*
Y-1743D03*
X605510Y-9901D03*
Y16999D03*
Y-1743D03*
Y9157D03*
X620092Y13078D03*
X608856Y16999D03*
X612203D03*
Y9157D03*
X608856D03*
X615549D03*
X608856Y-9901D03*
X612203D03*
X608856Y-1743D03*
X612203D03*
X615549D03*
Y16999D03*
X408184Y589800D03*
X401377Y585722D03*
X404723D03*
X414763D03*
X398029Y585707D03*
X408069D03*
X418108Y585599D03*
X411416Y585722D03*
X374039Y611186D03*
X404723Y593657D03*
X414763D03*
X398029Y593642D03*
X408069D03*
X408068Y612657D03*
X418108Y609864D03*
X398029D03*
X401376Y593642D03*
X401375Y607292D03*
X418108Y593642D03*
X411416Y593657D03*
X411415Y604614D03*
X418108Y604499D03*
X411415Y609864D03*
X394682Y607292D03*
X420634Y589800D03*
X433500D03*
X451573Y585714D03*
X474998D03*
X458116D03*
X421456Y585722D03*
X438189D03*
X444880D03*
X428149D03*
X434842D03*
X441533Y585707D03*
X431494D03*
X424801D03*
X474998Y612649D03*
X458266D03*
X451573Y612599D03*
X447744Y607220D03*
X478344Y606549D03*
X460912Y606700D03*
X454533Y606549D03*
X421454Y612560D03*
X431494Y593642D03*
X444880Y593659D03*
X421456Y593657D03*
X424801Y593642D03*
X438187Y593659D03*
X441533Y612557D03*
Y607292D03*
X434840D03*
X428147D03*
X424801Y609864D03*
X431494D03*
X434842Y593657D03*
X428149D03*
X441533Y593642D03*
X447766Y612659D03*
X525195Y612599D03*
X518502Y612649D03*
X531888D03*
X495077D03*
X488384Y612599D03*
X511809Y612649D03*
X491344Y606549D03*
X497723Y606700D03*
X485037Y607230D03*
X515155Y606549D03*
X521848D03*
X534534Y606700D03*
X528155Y606549D03*
X585431Y612649D03*
X592124D03*
X598817D03*
X555313D03*
X562006Y612599D03*
X568699Y612649D03*
X548620D03*
X571345Y606700D03*
X558659Y606549D03*
X564966D03*
X551966D03*
X598817Y604499D03*
X595470Y606549D03*
X588777D03*
X602163Y604499D03*
Y612657D03*
X605510Y604499D03*
Y612657D03*
X620033Y608878D03*
X608856Y604499D03*
X612203D03*
X608856Y612657D03*
X615549D03*
X612203D03*
X615549Y604499D03*
X631741Y615759D03*
X449633Y251296D03*
X436113Y243496D03*
X432733Y249347D03*
X436113Y251296D03*
X432733Y245447D03*
X439493Y241547D03*
Y253247D03*
X449633Y255196D03*
Y259096D03*
X446253Y257147D03*
X442873Y255196D03*
X453013Y257147D03*
Y261047D03*
X469913Y251296D03*
X476672D03*
X456393D03*
X463153D03*
Y259096D03*
X462023Y271097D03*
X458643Y269146D03*
X456393Y262996D03*
Y259096D03*
X459773Y261047D03*
X469913Y255196D03*
X473292Y257147D03*
X466533D03*
X456393Y255196D03*
X466533Y249347D03*
Y253247D03*
X453013Y249347D03*
Y253247D03*
X463153Y255196D03*
X476672Y247396D03*
Y255196D03*
X473292Y249347D03*
Y253247D03*
X480052Y245447D03*
X459773Y257147D03*
Y249347D03*
X480052D03*
X459773Y253247D03*
X480052D03*
X452865Y270081D03*
X465100Y280300D03*
X448503Y263297D03*
X455263Y267197D03*
X477792Y315647D03*
Y319547D03*
Y327347D03*
X469913Y321496D03*
X463671Y319386D03*
X466734Y287074D03*
X463800Y289500D03*
X466100Y300021D03*
X469913Y309797D03*
Y313696D03*
Y317596D03*
X477792Y331247D03*
X511592Y210346D03*
Y218147D03*
X498072Y222047D03*
X508212Y220096D03*
Y212296D03*
X518352Y218147D03*
X521731Y220096D03*
X538631Y210346D03*
Y214247D03*
Y222047D03*
X528491Y220096D03*
X531871Y222047D03*
X525111Y218147D03*
X528491Y216196D03*
X525111Y222047D03*
Y210346D03*
X521731Y212296D03*
X514972D03*
X508212Y216196D03*
X501452Y220096D03*
X504832Y214247D03*
X498072Y218147D03*
X494692Y220096D03*
X542011Y216196D03*
X538631Y218147D03*
X535251Y212296D03*
X531871Y210346D03*
Y214247D03*
X525111D03*
X518352D03*
Y210345D03*
X514972Y216196D03*
X511592Y214247D03*
X504832Y222047D03*
Y218147D03*
X501452Y216196D03*
X542011Y212296D03*
Y220096D03*
X535251D03*
X528491Y212296D03*
X535251Y216196D03*
X511592Y241547D03*
X486812Y245447D03*
X494692Y247396D03*
X483432Y251296D03*
X508212Y239596D03*
X498072Y233746D03*
X494692Y235696D03*
X504832Y229847D03*
X498072Y225947D03*
X504832Y241547D03*
X494692Y243496D03*
X501452Y223996D03*
X508212Y231797D03*
Y223996D03*
X518352Y229847D03*
X521731Y231797D03*
Y235696D03*
X538631Y225947D03*
Y237647D03*
X535251Y235696D03*
X528491Y227896D03*
Y235696D03*
X542011Y239596D03*
X535251D03*
X525111Y237647D03*
X514972Y227896D03*
Y235696D03*
Y239596D03*
Y223996D03*
Y243496D03*
X486812Y249347D03*
X483432Y247396D03*
X508212Y243496D03*
X518352Y241547D03*
Y237647D03*
X521731Y239596D03*
Y243496D03*
X511592Y229847D03*
Y225947D03*
Y237647D03*
X508212Y235696D03*
X498072Y229847D03*
X504832Y233746D03*
X494692Y227896D03*
X501452Y235696D03*
X498072Y237647D03*
Y241547D03*
X542011Y227896D03*
Y235696D03*
X535251Y231797D03*
Y227896D03*
X531871Y229847D03*
X525111Y233746D03*
X521731Y223996D03*
X525111Y229847D03*
X514972Y231797D03*
X508212Y227896D03*
X511592Y233746D03*
X504832Y237647D03*
X501452Y227896D03*
Y231797D03*
X494692D03*
X501452Y239596D03*
X494692D03*
X501452Y243496D03*
X542011Y231797D03*
X538631Y233746D03*
Y229847D03*
X531871Y225947D03*
Y233746D03*
X528491Y231797D03*
X525111Y225947D03*
X518352D03*
X521731Y227896D03*
X525111Y241547D03*
X528491Y239596D03*
X555531Y216196D03*
X558911Y222047D03*
X548771Y212296D03*
X552151Y214247D03*
X562591Y220096D03*
X545391Y210346D03*
Y222047D03*
X552151Y218147D03*
X555531Y220096D03*
X548771D03*
X545391Y218147D03*
Y214247D03*
X552151Y222047D03*
X548771Y216196D03*
X603273Y198896D03*
X600286Y202921D03*
X599773Y199596D03*
X592300Y220500D03*
X552151Y225947D03*
Y233746D03*
X548771Y235696D03*
X558911Y229847D03*
X552151D03*
X564084Y235685D03*
X545391Y225947D03*
Y233746D03*
X548771Y239596D03*
X545391Y229847D03*
X548771Y231797D03*
X562616Y223996D03*
X562640Y231735D03*
X558911Y225947D03*
X562630Y227896D03*
X558911Y241547D03*
X555531Y227896D03*
Y223996D03*
X548771D03*
X611148Y206994D03*
X618648Y219494D03*
Y214494D03*
X608648Y204494D03*
X613648D03*
X610273Y197496D03*
X613773Y196796D03*
X613082Y200676D03*
X609860Y201356D03*
X632500Y238500D03*
Y235000D03*
X632532Y241717D03*
X624500Y240500D03*
X606148Y229494D03*
X504832Y307847D03*
X511592D03*
X508212Y313696D03*
X514972Y301996D03*
X525111Y300047D03*
X521731Y301996D03*
X511592Y311747D03*
X508212Y309797D03*
X511592Y300047D03*
Y303947D03*
X518352Y300047D03*
X722050Y221150D03*
X720369Y205199D03*
X718300Y227400D03*
X742937Y218574D03*
X742897Y229573D03*
X760304Y235827D03*
X768560Y244055D03*
X769019Y276400D03*
X762616Y270113D03*
X761480Y242720D03*
X771650Y246451D03*
Y278451D03*
X759700Y232000D03*
X756114Y316209D03*
X762842Y302434D03*
X765730Y335064D03*
X771700Y342501D03*
X757956Y328095D03*
X758952Y384100D03*
X765007Y348363D03*
X964786Y283209D03*
X971546D03*
X974926Y281260D03*
X968166D03*
X934367Y285160D03*
Y300760D03*
X927607D03*
Y285160D03*
Y292959D03*
X934367D03*
X961406D03*
Y285160D03*
X954647Y292959D03*
Y285160D03*
X968166Y292959D03*
Y300760D03*
X954647D03*
X961406D03*
X974926D03*
X941127D03*
X947887D03*
X941127Y285160D03*
Y292959D03*
X947887D03*
Y285160D03*
X974926Y292959D03*
X981686Y281260D03*
X995206Y269560D03*
X998586Y263709D03*
X991826Y271509D03*
X995206Y273460D03*
X991826Y283209D03*
Y279310D03*
Y275409D03*
X988446Y281260D03*
X985066Y283209D03*
X978306D03*
X995206Y265660D03*
X991826Y267609D03*
X1001965Y261760D03*
X1012105Y255909D03*
X1015485Y253960D03*
X1018865Y252009D03*
X1005345Y259809D03*
X1008725Y257860D03*
Y253960D03*
X1005345Y255909D03*
X1001965Y257860D03*
X998586Y259809D03*
X988446Y269560D03*
Y273460D03*
X985066Y275409D03*
X988446Y277360D03*
X981686D03*
X985066Y279310D03*
X1012105Y252009D03*
X981686Y292959D03*
Y300760D03*
X988446D03*
X991826Y310509D03*
X988446Y292959D03*
X991826Y314409D03*
X1015485Y343660D03*
X1012105Y341709D03*
X1072202Y251296D03*
X1044256Y338341D03*
X1076435Y343595D03*
X1049284Y351460D03*
X1042524D03*
X1054914Y347000D03*
X1060694Y351460D03*
X1094731Y346546D03*
X1091351Y348497D03*
X995206Y238360D03*
X1029005D03*
X1008725D03*
X1001965D03*
X1035765D03*
Y250060D03*
X1029005D03*
X1032385Y248109D03*
X1025625D03*
X1015485Y238360D03*
X1022245D03*
X998586Y236409D03*
Y240309D03*
X1015485Y242260D03*
X1001965Y234460D03*
X995206Y242260D03*
Y234460D03*
X991826Y240309D03*
Y236409D03*
X1022245Y234460D03*
X1015485D03*
X1018865Y236409D03*
X1012105D03*
X1032385D03*
X1025625D03*
X1018865Y240309D03*
X1025625D03*
X1022245Y242260D03*
X1029005Y234460D03*
X1008725Y242260D03*
X1012105Y240309D03*
X1008725Y234460D03*
X1005345Y236409D03*
X1001965Y242260D03*
X1005345Y240309D03*
X1035765Y234460D03*
X1031255Y256400D03*
X1034635Y254259D03*
X1032385Y240309D03*
X1035765Y242260D03*
X1029005D03*
X1032385Y244209D03*
X1025625D03*
X1035765Y246160D03*
X1029005D03*
X1022245D03*
X1057314Y248109D03*
X1039145D03*
X1042524Y250060D03*
X1049284D03*
X1045904Y248109D03*
X1042524Y238360D03*
X1065242Y247396D03*
Y243496D03*
X1045904Y244209D03*
Y240309D03*
X1057314Y236409D03*
X1039145D03*
X1049284Y234460D03*
Y238360D03*
X1042524Y234460D03*
X1045904Y236409D03*
X1038015Y256500D03*
X1041395Y254259D03*
X1048154D03*
X1051534Y256500D03*
X1044774Y256400D03*
X1054914Y254500D03*
X1049284Y242260D03*
X1039145Y240309D03*
X1042524Y242260D03*
X1039145Y244209D03*
X1042524Y246160D03*
X1057314Y244209D03*
X1049284Y246160D03*
X1085721Y251296D03*
X1099241D03*
X1089101Y253247D03*
X1092481Y255196D03*
X1099241D03*
Y259096D03*
X1095861Y257147D03*
X1094731Y261500D03*
X1098111Y263400D03*
X1112761Y251296D03*
X1106001D03*
X1116141Y264947D03*
X1111631Y271300D03*
X1106001Y262996D03*
Y259096D03*
X1119521Y270796D03*
X1118391Y274997D03*
X1102621Y261047D03*
Y257147D03*
X1109381Y261047D03*
X1116141Y257147D03*
X1112761Y259096D03*
X1100200Y273300D03*
X1151060Y247396D03*
X1154440Y245447D03*
Y241547D03*
X1157820Y239596D03*
X1154440Y229847D03*
X1157820Y223996D03*
Y231797D03*
X1154440Y253247D03*
X1130780Y278596D03*
Y274696D03*
X1151060Y266896D03*
Y282496D03*
Y274696D03*
X1137540D03*
X1151060Y259096D03*
X1134160Y268847D03*
X1144300Y278596D03*
X1137540Y282496D03*
Y278596D03*
X1134160Y272747D03*
Y276646D03*
X1151060Y270796D03*
Y255196D03*
Y251296D03*
X1154440Y280547D03*
X1144300Y282496D03*
X1140920Y280547D03*
X1106001Y255196D03*
X1116141Y253247D03*
X1102621Y249347D03*
Y253247D03*
X1112761Y255196D03*
X1109381Y257147D03*
Y249347D03*
Y253247D03*
X1147680Y280547D03*
X1154440Y268847D03*
X1140920Y272747D03*
X1114340Y280560D03*
X1154440Y276647D03*
X1101491Y265400D03*
X1154440Y257147D03*
X1157820Y251296D03*
X1154440Y249347D03*
X1157820Y247396D03*
X1147680Y276647D03*
X1140920D03*
X1154440Y272747D03*
X1109381Y264947D03*
X1151060Y243496D03*
Y235696D03*
X1154440Y233746D03*
Y237647D03*
X1157820Y227896D03*
X1151060Y239596D03*
Y231797D03*
Y227896D03*
X1157820Y235696D03*
X1130780Y282496D03*
X1119521Y266896D03*
X1157820Y243496D03*
X1151060Y278596D03*
X1137540Y266896D03*
Y270796D03*
X1140920Y268847D03*
Y264947D03*
X1126280Y266896D03*
X1129660Y264947D03*
X1122900Y268847D03*
X1154440Y264947D03*
X1151060Y262996D03*
X1154440Y261047D03*
X1119521Y305896D03*
Y321496D03*
X1130780Y290296D03*
X1127400Y288347D03*
X1130780Y309797D03*
Y301996D03*
X1127400Y303947D03*
Y307847D03*
X1151060Y298096D03*
Y290296D03*
X1144300Y286396D03*
Y294196D03*
X1140920Y300047D03*
X1134160Y292247D03*
Y300047D03*
X1140920Y292247D03*
X1144300Y309797D03*
X1137540D03*
X1147680Y303947D03*
X1130780Y313696D03*
X1127400Y327347D03*
X1134160Y323446D03*
X1137540Y317596D03*
X1127400Y319547D03*
Y315647D03*
X1130780Y321496D03*
X1137540Y313696D03*
X1130780Y325396D03*
X1140920Y315647D03*
X1134160Y319547D03*
X1130780Y317596D03*
X1140920Y288347D03*
Y284447D03*
X1147680D03*
Y288347D03*
X1151060Y286396D03*
X1144300Y290296D03*
X1147680Y292247D03*
X1154440D03*
Y288347D03*
Y284447D03*
X1114839Y320075D03*
X1113132Y291702D03*
X1113500Y323400D03*
X1137540Y286396D03*
X1134160Y284447D03*
X1130780Y286396D03*
X1134160Y311747D03*
Y315647D03*
X1147680Y307847D03*
X1151060Y305896D03*
X1144300Y301996D03*
Y298096D03*
X1137540Y301996D03*
X1134160Y303947D03*
X1137540Y298096D03*
X1140920Y303947D03*
X1137540Y305896D03*
X1140920Y296147D03*
X1137540Y294196D03*
X1119521Y309797D03*
Y313696D03*
Y317596D03*
X1127400Y311747D03*
X1157820Y301996D03*
X1154440Y300047D03*
X1134160Y307847D03*
X1151060Y294196D03*
X1147680Y300047D03*
Y296147D03*
X1140920Y307847D03*
Y311747D03*
X1151060Y301996D03*
X1144300Y305896D03*
X1157820Y298096D03*
X1154440Y296147D03*
X1144300Y313696D03*
X1109200Y325100D03*
X1157820Y337096D03*
Y333196D03*
X1147680Y342947D03*
X1151060Y340996D03*
Y333196D03*
X1157820Y329296D03*
X1154440Y342947D03*
Y335147D03*
X1144300Y340996D03*
Y337096D03*
Y344896D03*
X1157820Y325396D03*
X1151060Y344896D03*
X1154440Y339047D03*
Y331247D03*
X1151060Y337096D03*
Y329296D03*
X1147680Y335147D03*
Y331247D03*
X1144300Y333196D03*
X1151060Y356596D03*
Y360496D03*
X1144300Y356596D03*
X1147680Y346847D03*
Y350747D03*
X1151060Y352696D03*
Y348796D03*
X1147680Y358547D03*
X1157820Y360496D03*
X1154440Y358547D03*
Y354647D03*
X1157820Y352696D03*
X1147680Y354647D03*
X1144300Y348796D03*
X1154440Y346847D03*
X1161200Y362447D03*
Y358547D03*
Y354647D03*
X1174719Y218147D03*
X1178099Y216196D03*
Y220096D03*
X1181479Y222047D03*
X1188239Y210346D03*
Y222047D03*
X1201759Y218147D03*
X1198379Y212296D03*
X1194999Y210346D03*
Y222047D03*
X1188239Y214247D03*
X1181479D03*
X1184859Y220096D03*
X1191619Y216196D03*
X1194999Y214247D03*
Y218147D03*
X1198379Y220096D03*
X1201759Y222047D03*
X1184859Y216196D03*
Y212296D03*
X1188239Y218147D03*
X1191619Y220096D03*
Y212296D03*
X1198379Y216196D03*
X1205139Y220096D03*
X1174719Y214247D03*
Y222047D03*
X1178099Y247396D03*
Y243496D03*
Y227896D03*
Y235696D03*
X1174719Y237647D03*
Y253247D03*
X1171339Y274696D03*
X1174719Y280547D03*
X1178099Y274696D03*
X1191619Y239596D03*
X1188239Y225947D03*
X1184859Y235696D03*
X1188239Y237647D03*
X1184859Y247396D03*
X1188239Y249347D03*
X1201759Y229847D03*
Y225947D03*
Y233746D03*
X1198379Y235696D03*
Y243496D03*
X1201759Y241547D03*
Y249347D03*
X1198379Y239596D03*
X1194999Y225947D03*
Y233746D03*
X1184859Y239596D03*
Y251296D03*
X1208519Y233746D03*
X1194999Y264947D03*
Y268847D03*
Y272747D03*
Y280547D03*
X1188239Y257147D03*
X1181479Y261047D03*
Y268847D03*
Y276646D03*
X1184859Y259096D03*
X1191619Y274696D03*
X1205139D03*
X1198379Y278596D03*
X1201759Y261047D03*
X1198379Y255196D03*
X1201759Y257147D03*
X1171339Y282496D03*
X1174719Y261047D03*
Y272747D03*
X1178099Y266896D03*
X1181479Y257147D03*
X1178099Y255196D03*
X1174719Y241547D03*
X1178099Y239596D03*
X1174719Y249347D03*
Y245447D03*
X1171339Y278596D03*
X1178099Y262996D03*
X1205139Y255196D03*
X1208519Y249347D03*
X1201759Y253247D03*
X1205139Y243496D03*
Y235696D03*
X1208519Y225947D03*
X1201759Y280547D03*
X1198379Y274696D03*
X1201759Y272747D03*
X1205139Y270796D03*
X1201759Y264947D03*
X1205139Y262996D03*
X1208519Y253247D03*
X1205139Y251296D03*
X1208519Y241547D03*
Y237647D03*
X1205139Y239596D03*
Y278596D03*
X1201759Y276646D03*
Y268847D03*
X1205139Y266896D03*
Y259096D03*
Y223996D03*
X1198379D03*
X1205139Y227896D03*
X1178099Y282496D03*
X1184859Y262996D03*
X1191619Y259096D03*
X1194999Y261047D03*
Y257147D03*
X1188239Y253247D03*
X1194999Y249347D03*
X1198379Y247396D03*
X1191619Y243496D03*
X1188239Y241547D03*
X1181479Y245447D03*
X1184859Y278596D03*
X1188239Y276646D03*
Y280547D03*
X1181479Y272747D03*
X1188239Y268847D03*
X1191619Y266896D03*
X1181479Y280547D03*
X1188239Y261047D03*
X1191619Y262996D03*
X1198379Y259096D03*
X1191619Y255196D03*
Y251296D03*
X1194999Y253247D03*
Y245447D03*
Y241547D03*
X1188239Y245447D03*
X1184859Y243496D03*
Y282496D03*
Y274696D03*
X1191619Y282496D03*
Y278596D03*
X1184859Y270796D03*
X1188239Y272747D03*
Y264947D03*
X1174719Y229847D03*
Y233746D03*
X1181479Y229847D03*
X1184859Y227896D03*
Y231797D03*
X1191619Y235696D03*
Y227896D03*
X1198379Y231797D03*
X1174719Y225947D03*
X1178099Y231797D03*
X1181479Y233746D03*
Y225947D03*
X1188239Y229847D03*
Y233746D03*
X1191619Y231797D03*
X1194999Y229847D03*
X1174719Y257147D03*
X1178099Y259096D03*
X1174719Y276646D03*
X1181479Y253247D03*
X1178099Y251296D03*
X1174719Y264947D03*
X1208519Y229847D03*
X1174719Y300047D03*
Y284447D03*
X1178099Y286396D03*
X1171339Y301996D03*
X1161200Y335147D03*
Y339047D03*
X1164580Y329296D03*
Y333196D03*
Y337096D03*
X1167960Y339047D03*
Y327347D03*
X1161200Y331247D03*
Y327347D03*
X1178099Y337096D03*
Y317596D03*
X1164580Y321496D03*
Y317596D03*
X1161200Y323446D03*
Y319547D03*
X1167960Y342947D03*
Y323446D03*
Y315647D03*
Y319547D03*
X1174719Y315647D03*
X1171339Y317596D03*
X1164580Y325396D03*
X1171339D03*
X1174719Y342947D03*
Y335147D03*
X1181479Y288347D03*
X1188239Y284447D03*
X1201759D03*
X1181479Y327347D03*
Y335147D03*
X1178099Y340996D03*
Y344896D03*
X1181479Y331247D03*
X1174719Y323446D03*
X1181479D03*
X1174719Y327347D03*
X1178099Y333196D03*
X1171339Y329296D03*
X1167960Y335147D03*
X1171339Y340996D03*
X1174719Y319547D03*
X1178099Y321496D03*
Y325396D03*
Y329296D03*
X1174719Y331247D03*
X1171339Y333196D03*
Y337096D03*
X1184859Y286396D03*
X1191619D03*
X1194999Y284447D03*
X1181479D03*
X1174719Y303947D03*
X1167960D03*
X1178099Y309797D03*
X1171339Y305896D03*
X1164580Y309797D03*
X1167960Y307847D03*
Y311747D03*
X1171339Y309797D03*
X1178099Y301996D03*
X1174719Y311747D03*
Y307847D03*
X1178099Y305896D03*
Y313696D03*
X1171339D03*
X1164580D03*
X1174719Y292247D03*
Y288347D03*
X1171339Y286396D03*
Y290296D03*
X1178099D03*
X1171339Y298096D03*
Y294196D03*
X1174719Y296147D03*
X1171339Y356596D03*
X1164580D03*
X1171339Y348796D03*
X1174719Y354647D03*
Y346847D03*
X1178099Y348796D03*
Y352696D03*
X1167960Y350747D03*
Y354647D03*
X1164580Y360496D03*
X1167960Y346847D03*
X1171339Y352696D03*
X1269810Y154398D03*
X1267800Y161800D03*
X1271400Y161900D03*
X1240309D03*
X1233902Y173337D03*
X1241381Y172040D03*
X1287790Y156575D03*
X1295500Y159970D03*
X1389138Y58499D03*
X1389068Y78556D03*
X1389100Y74600D03*
X1371200Y402100D03*
X1375201Y396303D03*
X1392500Y592000D03*
X1518700Y406500D03*
X1526525Y404554D03*
X1522625D03*
X1534325D03*
X1538225D03*
X1551875Y414694D03*
X1540700Y410450D03*
X1664135Y131239D03*
X1657835D03*
X1804000Y498176D03*
X1820400Y501100D03*
X1815200Y501500D03*
X1833700Y497300D03*
X1900890Y477200D03*
X1937430Y464785D03*
X1905010Y479410D03*
X1915100Y480050D03*
X1929480Y472880D03*
X1919510Y475100D03*
Y479200D03*
X1928620Y482710D03*
G54D46*
X24400Y519500D03*
G54D41*
X40500Y-42250D03*
Y-52250D03*
X60500Y-42250D03*
Y-52250D03*
X467246Y-52301D03*
Y-42301D03*
X487246Y-52301D03*
Y-42301D03*
X798984Y-52057D03*
Y-42057D03*
X818984Y-52057D03*
Y-42057D03*
X1135583Y-52285D03*
Y-42285D03*
X1155583Y-52285D03*
Y-42285D03*
X1392258Y-52257D03*
Y-42257D03*
X1412258Y-52257D03*
Y-42257D03*
X1432258Y-52257D03*
Y-42257D03*
X1452258Y-52257D03*
Y-42257D03*
G54D51*
X637793Y13078D03*
Y589679D03*
Y608555D03*
G54D42*
X-7874Y216181D03*
Y325315D03*
G54D43*
X18228Y178386D03*
X-1969D03*
G54D40*
X-3937Y-43307D03*
X1956693D03*
X-3937Y646063D03*
X1956693D03*
G54D48*
X224410Y301378D03*
X602362Y214764D03*
X874016Y301378D03*
%LPD*%
G75*
G36*
G01X1903400Y122500D02*
Y135250D01*
X1913800D01*
Y122500D01*
X1903400D01*
G37*
G54D10*
X-17936Y-49379D03*
Y-53779D03*
Y-44979D03*
Y-40579D03*
X-18079Y-35764D03*
Y-58764D03*
X-14186Y196989D03*
Y199989D03*
X-17179Y643156D03*
X-17194Y638753D03*
X-17179Y647556D03*
Y660756D03*
Y651956D03*
Y656356D03*
X-13636Y-40479D03*
Y-44879D03*
Y-53679D03*
X-9079Y-50164D03*
X-4679D03*
X-279D03*
X-9079Y-54264D03*
X-4679D03*
X-279D03*
X22964Y-40379D03*
Y-44779D03*
Y-53579D03*
Y-49179D03*
X18964Y-53579D03*
Y-49179D03*
X13964Y-53579D03*
Y-49179D03*
X8964Y-40379D03*
Y-44779D03*
Y-53579D03*
Y-49179D03*
X3964Y-40379D03*
Y-44779D03*
Y-53579D03*
Y-49179D03*
X25921Y-35764D03*
X30321D03*
X43521D03*
X39121D03*
X34721D03*
X8321D03*
X12721D03*
X21521D03*
X17121D03*
X-13679D03*
X-9279D03*
X3921D03*
X-4879D03*
X-479D03*
X17121Y-58764D03*
X21521D03*
X12721D03*
X8321D03*
X34721D03*
X39121D03*
X43521D03*
X30321D03*
X25921D03*
X-479D03*
X-13679D03*
X-4879D03*
X3921D03*
X-13636Y-49279D03*
X-9279Y-58764D03*
X875Y211336D03*
X6074Y211293D03*
X3474Y211263D03*
X875Y208352D03*
X36200Y208600D03*
X33200D03*
X20700D03*
X17700Y211600D03*
X20700D03*
X17700Y208600D03*
X23700Y211600D03*
Y208600D03*
X33200Y211600D03*
X30200D03*
Y208600D03*
X36200Y211600D03*
X6074Y208321D03*
X3474Y208263D03*
X5500Y218500D03*
X-5300Y200191D03*
X-7900D03*
X-2700Y200202D03*
X-11586Y196989D03*
Y199989D03*
X-2600Y232300D03*
X-5246Y232351D03*
X-7846D03*
X20500Y221000D03*
Y224000D03*
X17500Y221000D03*
Y224000D03*
X23500D03*
Y221000D03*
X33300Y224000D03*
Y221000D03*
X30300D03*
Y224000D03*
X36300D03*
Y221000D03*
X-14129Y235221D03*
X-11484Y235215D03*
Y232215D03*
X-14084D03*
X2678Y221018D03*
X5277Y221110D03*
X5173Y224042D03*
X2574Y223963D03*
X-26Y223982D03*
X22421Y647556D03*
X26821D03*
X31221D03*
X18021D03*
Y643156D03*
X31221D03*
X26821D03*
X22421D03*
X18006Y638753D03*
X9221Y647556D03*
X13621D03*
Y643156D03*
X9221D03*
X4821D03*
Y647556D03*
X22406Y638753D03*
X26806D03*
X31206D03*
X-12794D03*
X-12779Y647556D03*
Y643156D03*
X40006Y638753D03*
X44406D03*
X35606D03*
X35621Y647556D03*
Y643156D03*
X18021Y660756D03*
X35621Y656356D03*
X26821Y660756D03*
X18021Y651956D03*
X31221D03*
X22421Y660756D03*
X26821Y651956D03*
X22421D03*
X4821D03*
X13621D03*
X9221D03*
X-8379Y660756D03*
X4821Y656356D03*
X9221D03*
X13621D03*
X-3979D03*
X421D03*
X13621Y660756D03*
X-3979D03*
X421D03*
X4821D03*
X-12779Y651956D03*
X22421Y656356D03*
X26821D03*
X31221D03*
X18021D03*
X-8379D03*
X-12779D03*
X31221Y660756D03*
X35621Y651956D03*
Y660756D03*
X44421D03*
X40021D03*
X-12779D03*
X9221D03*
X107921Y-58764D03*
X102921D03*
X97921D03*
X92921D03*
X87921D03*
X82921D03*
X77921D03*
X72921D03*
X67921D03*
X62921D03*
X57921D03*
X52921D03*
X47921Y-35764D03*
Y-58764D03*
X107921Y-35764D03*
X102921D03*
X97921D03*
X92921D03*
X87921D03*
X82921D03*
X77921D03*
X72921D03*
X67921D03*
X62921D03*
X57921D03*
X52921D03*
X58200Y230400D03*
Y233400D03*
X55600Y230400D03*
X53000Y230300D03*
Y233300D03*
X55600Y233400D03*
X58200Y227400D03*
X53000Y227300D03*
X55600Y227400D03*
X58200Y239400D03*
X53000Y239300D03*
X55600Y239400D03*
X58200Y236400D03*
X55600D03*
X53000Y236300D03*
X71500Y263300D03*
X68800D03*
X53004Y244632D03*
X55275Y245900D03*
X57875D03*
X57457Y248537D03*
Y251237D03*
X57600Y262800D03*
X57500Y260200D03*
X62800Y265500D03*
X71500Y266000D03*
X65500Y265500D03*
X68800Y266000D03*
X60000Y265500D03*
X103700Y397200D03*
X106400D03*
X101000D03*
X109100D03*
Y399900D03*
X101000D03*
X106400D03*
X103700D03*
X104517Y406279D03*
X105761Y409208D03*
X108010Y411479D03*
X48806Y638753D03*
X75206D03*
X106006D03*
X70806D03*
X53206D03*
X66406D03*
X92806D03*
X97206D03*
X101606D03*
X57606D03*
X62006D03*
X79606D03*
X84006D03*
X88406D03*
X53221Y660756D03*
X101621D03*
X97221D03*
X92821D03*
X106021D03*
X48821D03*
X70821D03*
X66421D03*
X62021D03*
X57621D03*
X75221D03*
X88421D03*
X84021D03*
X79621D03*
X167921Y-58764D03*
X162921D03*
X157921D03*
X152921D03*
X147921D03*
X142921D03*
X137921D03*
X132921D03*
X127921D03*
X122921D03*
X117921D03*
X112921D03*
X162921Y-35764D03*
X157921D03*
X152921D03*
X147921D03*
X142921D03*
X137921D03*
X132921D03*
X127921D03*
X122921D03*
X117921D03*
X112921D03*
X167921D03*
X166000Y212900D03*
X168600D03*
X164300Y207870D03*
X160800Y212900D03*
X163400D03*
X157800Y207300D03*
X161216Y209533D03*
Y206933D03*
X154500Y205500D03*
X150600Y212900D03*
X151000Y205500D03*
X140889Y211972D03*
X137615Y212039D03*
X143900Y204600D03*
X147500Y205500D03*
X140200Y204400D03*
X153200Y212900D03*
X139815Y268974D03*
X137900Y272800D03*
X139800Y237000D03*
X165825Y239543D03*
X168425Y236943D03*
Y239543D03*
X165825Y236943D03*
X163225D03*
X152825D03*
X145025D03*
X147625D03*
X150225D03*
X142425D03*
X122231Y234716D03*
X125564Y237816D03*
X122632D03*
X163225Y239543D03*
X158025Y236943D03*
X155425D03*
X160625D03*
X142371Y244384D03*
X122231Y266716D03*
X122531Y269816D03*
X125463D03*
X142466Y268982D03*
X142700Y276200D03*
X136729Y276386D03*
X139683Y276174D03*
X163225Y242143D03*
X168425Y244743D03*
X165825D03*
X163225D03*
X168425Y242143D03*
X165825D03*
X150700Y276800D03*
X169150Y259470D03*
Y255470D03*
X157633Y268727D03*
X162833D03*
X160233D03*
X165433D03*
X168033Y271327D03*
X162833Y276527D03*
Y273927D03*
Y271327D03*
X165433Y276527D03*
Y273927D03*
Y271327D03*
X159983Y276507D03*
X168033Y276527D03*
Y273927D03*
Y268727D03*
X153300Y276800D03*
X139866Y333016D03*
X160233Y306257D03*
Y308857D03*
Y303657D03*
X157518Y335391D03*
X157745Y332800D03*
X139900Y302400D03*
X142433Y301057D03*
X147633D03*
X150233D03*
X145033D03*
X125500Y333500D03*
X122231Y330716D03*
X122731Y333916D03*
X145200Y341300D03*
X148200D03*
X142465Y332940D03*
X152833Y301057D03*
X163233Y306257D03*
Y308857D03*
X168433Y306257D03*
Y308857D03*
Y301057D03*
X165833D03*
X163233D03*
X160633D03*
X158033D03*
X155433D03*
X169150Y287600D03*
Y291600D03*
X165833Y306257D03*
X163233Y303657D03*
X168433D03*
X165833D03*
Y308857D03*
X151000Y341300D03*
X169150Y323600D03*
Y319600D03*
X160501Y332965D03*
X160274Y335556D03*
X165701Y338165D03*
Y335565D03*
X163101Y332965D03*
X168301D03*
X165701D03*
X163101Y335565D03*
X168301Y340765D03*
Y338165D03*
Y335565D03*
X163101Y338165D03*
Y340765D03*
X165701D03*
X154200Y341100D03*
X125663Y301716D03*
X122231Y298716D03*
X122731Y301716D03*
X139767Y364883D03*
X147833Y364457D03*
X125600Y364900D03*
X122600Y365500D03*
X122331Y362716D03*
X142421Y364908D03*
X145033Y364457D03*
X142863Y402829D03*
X140219Y402894D03*
X137619Y402900D03*
X134992D03*
X142818Y400163D03*
X143073Y397194D03*
X140475Y397310D03*
X140218Y400163D03*
X137529Y400296D03*
X134929D03*
X111561Y398819D03*
X122000Y397600D03*
X125300Y397700D03*
X122231Y394716D03*
X150633Y364457D03*
X167433Y369657D03*
X169150Y355600D03*
Y351600D03*
X167700Y363900D03*
X161833Y364457D03*
X164633D03*
X159033D03*
X156233D03*
X153433D03*
X164633Y369657D03*
X161833D03*
X161933Y372357D03*
X164733D03*
X167533D03*
X166340Y374785D03*
X167670Y383993D03*
Y387993D03*
X110406Y638753D03*
X145606D03*
X141206D03*
X136806D03*
X132406D03*
X158806D03*
X119206D03*
X123606D03*
X114806D03*
X128006D03*
X163206D03*
X154406D03*
X167606D03*
X150006D03*
X132421Y660756D03*
X145621D03*
X141221D03*
X136821D03*
X123621D03*
X114821D03*
X128021D03*
X110421D03*
X119221D03*
X150021D03*
X167621D03*
X163221D03*
X158821D03*
X154421D03*
X182921Y-58764D03*
X177921D03*
X172921D03*
X227921Y-35764D03*
X222921D03*
X217921D03*
X212921D03*
X207921D03*
X202921D03*
X197921D03*
X192921D03*
X187921D03*
X182921D03*
X177921D03*
X227921Y-58764D03*
X222921D03*
X217921D03*
X212921D03*
X207921D03*
X202921D03*
X197921D03*
X192921D03*
X187921D03*
X172921Y-35764D03*
X176300Y211900D03*
X182300Y216108D03*
X179300D03*
Y213208D03*
X176300Y217308D03*
Y214500D03*
X173300Y217700D03*
Y214800D03*
Y211900D03*
X176400Y234300D03*
X176508Y231609D03*
X179400Y234300D03*
X182400D03*
X176400Y239900D03*
X182400D03*
X179400D03*
X173400D03*
Y231400D03*
Y234300D03*
Y237000D03*
X176400D03*
X182400D03*
X179400D03*
X188200Y236800D03*
X188300Y234000D03*
X185250Y239850D03*
X204200Y249500D03*
X201100Y246500D03*
X198200Y249500D03*
Y246500D03*
X201200Y249500D03*
X203900Y246500D03*
X207200Y249500D03*
X185768Y270065D03*
X173835Y277804D03*
X198082Y277995D03*
X203847Y274933D03*
X203947Y277933D03*
X188510Y272666D03*
X176835Y277804D03*
X182935Y278204D03*
Y275604D03*
X191400Y278400D03*
X188475Y270065D03*
X185735Y275604D03*
X188600Y278300D03*
X188535Y275604D03*
X185735Y278204D03*
X195300Y229250D03*
X188100Y239800D03*
X185250Y234250D03*
Y236950D03*
X176835Y275204D03*
X185754Y272689D03*
X179835Y277804D03*
Y275204D03*
X195100Y252000D03*
X201200Y252500D03*
X198200D03*
X204200D03*
X207200D03*
X200947Y277933D03*
X200847Y274933D03*
X200947Y280933D03*
X173835Y275204D03*
X230800Y265200D03*
X224390Y258920D03*
X219500Y254500D03*
X190800Y295500D03*
X196956Y295583D03*
X193800Y295500D03*
X190665Y306877D03*
X198119Y339710D03*
X191792Y327743D03*
X197792Y327643D03*
X194792D03*
X184800Y295500D03*
X187956Y295583D03*
X181800Y295500D03*
X201177Y330728D03*
Y333728D03*
Y336728D03*
X201163Y339476D03*
Y342476D03*
X204177Y336728D03*
X204060Y342527D03*
X204163Y339476D03*
X188654Y330973D03*
Y327973D03*
X197684Y307227D03*
X200251Y306548D03*
X188630Y333923D03*
X190570Y309539D03*
X185630Y333923D03*
X172800Y295500D03*
Y298400D03*
X198182Y280995D03*
X178956Y295583D03*
X175800Y295500D03*
X187900Y306900D03*
X191300Y339800D03*
X172800Y304000D03*
X175800D03*
X178800D03*
X187800D03*
X181800D03*
X184800D03*
X172800Y301100D03*
X175800D03*
X178800D03*
X181800D03*
X187800D03*
X184800D03*
Y298400D03*
X181800D03*
X175800D03*
X178800D03*
X187800D03*
X185300Y336900D03*
X173300Y337000D03*
Y339900D03*
X188300D03*
Y336900D03*
X179300Y337000D03*
X176300Y339900D03*
X179300D03*
X182300D03*
Y337000D03*
X198223Y342430D03*
X176300Y337000D03*
X185300Y339900D03*
X224000Y330900D03*
X229100Y325900D03*
X219000Y335900D03*
X214000Y340900D03*
X197730Y309959D03*
X204060Y345527D03*
X191300Y343248D03*
X173300Y343448D03*
X188300Y343348D03*
X201045Y345449D03*
X198233Y345402D03*
X195233D03*
X176300Y343448D03*
X201045Y348449D03*
X198233Y348402D03*
Y351402D03*
X195233D03*
X173424Y359621D03*
X188424D03*
X182424D03*
X185424D03*
X176424D03*
X179424D03*
X182300Y343448D03*
X173471Y363281D03*
X188471D03*
X182471D03*
X185471D03*
X176471D03*
X179471D03*
X179300Y343448D03*
X185300Y343348D03*
X211606Y638753D03*
X224806D03*
X220406D03*
X216006D03*
X189606D03*
X198406D03*
X202806D03*
X207206D03*
X176406D03*
X172006D03*
X185206D03*
X180806D03*
X194006D03*
X226500Y649900D03*
X229206Y638753D03*
X224821Y660756D03*
X220421D03*
X198421D03*
X211621D03*
X189621D03*
X202821D03*
X207221D03*
X194021D03*
X185221D03*
X172021D03*
X176421D03*
X180821D03*
X229221D03*
X216021D03*
X292921Y-35764D03*
X287921D03*
X282921D03*
X277921D03*
X272921D03*
X267921D03*
X262921D03*
X257921D03*
X252921D03*
X247921D03*
X242921D03*
X237921D03*
X232921D03*
X292921Y-58764D03*
X287921D03*
X282921D03*
X277921D03*
X272921D03*
X267921D03*
X262921D03*
X257921D03*
X252921D03*
X247921D03*
X242921D03*
X237921D03*
X232921D03*
X234501Y270392D03*
X234000Y320900D03*
X290806Y638753D03*
X268806D03*
X273206D03*
X277606D03*
X282006D03*
X260006D03*
X264406D03*
X255606D03*
X251206D03*
X286406D03*
X242406D03*
X246806D03*
X233606D03*
X238006D03*
X286421Y660756D03*
X268821D03*
X282021D03*
X273221D03*
X277621D03*
X264421D03*
X251221D03*
X255621D03*
X260021D03*
X246821D03*
X242421D03*
X238021D03*
X233621D03*
X290821D03*
X352921Y-58764D03*
Y-35764D03*
X347921Y-58764D03*
Y-35764D03*
X342921Y-58764D03*
Y-35764D03*
X337921Y-58764D03*
Y-35764D03*
X332921Y-58764D03*
Y-35764D03*
X327921Y-58764D03*
Y-35764D03*
X322921Y-58764D03*
Y-35764D03*
X317921Y-58764D03*
Y-35764D03*
X312921Y-58764D03*
X307921D03*
Y-35764D03*
X302921Y-58764D03*
Y-35764D03*
X297921D03*
Y-58764D03*
X312921Y-35764D03*
X330406Y638753D03*
X348006D03*
X326006D03*
X312806D03*
X317206D03*
X321606D03*
X352406D03*
X295206D03*
X299606D03*
X308406D03*
X304006D03*
X334806D03*
X339206D03*
X343606D03*
X312821Y660756D03*
X317221D03*
X308421D03*
X304021D03*
X352421D03*
X295221D03*
X326021D03*
X321621D03*
X339221D03*
X299621D03*
X334821D03*
X330421D03*
X343621D03*
X348021D03*
X392921Y-35764D03*
X387921Y-58764D03*
Y-35764D03*
X382921Y-58764D03*
Y-35764D03*
X377921Y-58764D03*
Y-35764D03*
X372921Y-58764D03*
Y-35764D03*
X367921Y-58764D03*
Y-35764D03*
X362921Y-58764D03*
Y-35764D03*
X357921Y-58764D03*
Y-35764D03*
X392921Y-58764D03*
X402921Y-35764D03*
X397921Y-58764D03*
Y-35764D03*
X412921Y-58764D03*
Y-35764D03*
X407921Y-58764D03*
Y-35764D03*
X402921Y-58764D03*
X404594Y264899D03*
X407594D03*
X411188D03*
X414188D03*
X417190D03*
X385494Y309904D03*
X367914Y309910D03*
X371237Y309846D03*
X389502Y309910D03*
X389528Y292910D03*
X392694Y292904D03*
X368116Y293087D03*
X371094Y292904D03*
X373736Y293068D03*
X382625Y293207D03*
X378294Y292904D03*
X385494D03*
X392694Y309904D03*
X374994Y309910D03*
X382497D03*
X378577Y309795D03*
X407094Y292904D03*
X396897Y293058D03*
X399894Y292904D03*
X404266Y293030D03*
X407094Y309904D03*
X396709Y309910D03*
X399894Y309904D03*
X404117Y309910D03*
X383206Y638753D03*
X387606D03*
X392006D03*
X396406D03*
X400806D03*
X405206D03*
X409606D03*
X414006D03*
X370006D03*
X365606D03*
X374406D03*
X378806D03*
X356806D03*
X361206D03*
X374421Y660756D03*
X387621D03*
X383221D03*
X400821D03*
X396421D03*
X392021D03*
X405221D03*
X409621D03*
X414021D03*
X361221D03*
X365621D03*
X356821D03*
X370021D03*
X378821D03*
X477921Y-58764D03*
Y-35764D03*
X472921Y-58764D03*
Y-35764D03*
X467921Y-58764D03*
Y-35764D03*
X462921Y-58764D03*
Y-35764D03*
X457921Y-58764D03*
Y-35764D03*
X452921Y-58764D03*
Y-35764D03*
X447921Y-58764D03*
Y-35764D03*
X442921Y-58764D03*
Y-35764D03*
X437921Y-58764D03*
Y-35764D03*
X432921Y-58764D03*
X422921Y-35764D03*
X417921Y-58764D03*
Y-35764D03*
X432921D03*
X427921Y-58764D03*
Y-35764D03*
X422921Y-58764D03*
X425911Y264710D03*
X420188Y264899D03*
X423092Y264697D03*
X436519Y262232D03*
X436329Y264826D03*
X438681Y646514D03*
X466806Y638753D03*
X462406D03*
X475606D03*
X471206D03*
X418406D03*
X422806D03*
X427206D03*
X440406D03*
X436006D03*
X431606D03*
X449206D03*
X458006D03*
X453606D03*
X444806D03*
X458021Y660756D03*
X449221D03*
X462421D03*
X466821D03*
X471221D03*
X418421D03*
X438681Y652514D03*
X475621Y660756D03*
X453621D03*
X422821D03*
X427221D03*
X440421D03*
X431621D03*
X436021D03*
X444821D03*
X537921Y-58764D03*
Y-35764D03*
X532921Y-58764D03*
Y-35764D03*
X527921Y-58764D03*
Y-35764D03*
X522921Y-58764D03*
Y-35764D03*
X517921Y-58764D03*
Y-35764D03*
X512921Y-58764D03*
Y-35764D03*
X507921Y-58764D03*
Y-35764D03*
X502921Y-58764D03*
Y-35764D03*
X497921Y-58764D03*
Y-35764D03*
X492921Y-58764D03*
Y-35764D03*
X487921Y-58764D03*
Y-35764D03*
X482921Y-58764D03*
Y-35764D03*
X480006Y638753D03*
X484406D03*
X488806D03*
X493206D03*
X497606D03*
X510806D03*
X537206D03*
X519606D03*
X524006D03*
X532806D03*
X528406D03*
X515206D03*
X502006D03*
X506406D03*
X524021Y660756D03*
X480021D03*
X484421D03*
X497621D03*
X493221D03*
X488821D03*
X519621D03*
X532821D03*
X537221D03*
X528421D03*
X515221D03*
X510821D03*
X506421D03*
X502021D03*
X597921Y-35764D03*
Y-58764D03*
X592921Y-35764D03*
Y-58764D03*
X587921Y-35764D03*
Y-58764D03*
X582921Y-35764D03*
Y-58764D03*
X577921Y-35764D03*
Y-58764D03*
X572921Y-35764D03*
Y-58764D03*
X567921Y-35764D03*
Y-58764D03*
X562921Y-35764D03*
Y-58764D03*
X557921Y-35764D03*
Y-58764D03*
X552921Y-35764D03*
Y-58764D03*
X547921D03*
Y-35764D03*
X542921Y-58764D03*
Y-35764D03*
X576941Y646238D03*
X590006Y638753D03*
X572406D03*
X559206D03*
X568006D03*
X563606D03*
X550406D03*
X581206D03*
X585606D03*
X576806D03*
X598806D03*
X594406D03*
X601500Y649500D03*
X554806Y638753D03*
X541606D03*
X546006D03*
X576941Y652238D03*
X559221Y660756D03*
X546021D03*
X554821D03*
X598821D03*
X572421D03*
X568021D03*
X563621D03*
X585621D03*
X541621D03*
X594421D03*
X576821D03*
X590021D03*
X581221D03*
X550421D03*
X637921Y-58764D03*
X632921Y-35764D03*
Y-58764D03*
X627921Y-35764D03*
Y-58764D03*
X622921Y-35764D03*
Y-58764D03*
X617921Y-35764D03*
Y-58764D03*
X612921Y-35764D03*
Y-58764D03*
X607921Y-35764D03*
Y-58764D03*
X602921Y-35764D03*
Y-58764D03*
X652921Y-35764D03*
Y-58764D03*
X647921Y-35764D03*
Y-58764D03*
X642921Y-35764D03*
Y-58764D03*
X637921Y-35764D03*
X662921D03*
Y-58764D03*
X657921Y-35764D03*
Y-58764D03*
X653750Y225500D03*
X641600Y221400D03*
Y226600D03*
Y224000D03*
Y229200D03*
X644500D03*
Y224000D03*
Y226600D03*
X641600Y231800D03*
X644500D03*
X650700Y224000D03*
X647600D03*
X650700Y226600D03*
X647600D03*
X650700Y231800D03*
X647600D03*
Y229200D03*
X650700D03*
X641541Y236028D03*
Y238628D03*
X637001Y227337D03*
Y222137D03*
Y224737D03*
Y229937D03*
X641541Y243828D03*
Y241228D03*
X638406Y638753D03*
X634006D03*
X642806D03*
X629606D03*
X616406D03*
X612006D03*
X603206D03*
X625206D03*
X651606D03*
X647206D03*
X660406D03*
X620806D03*
X656006D03*
X607606D03*
X607621Y660756D03*
X638421D03*
X647221D03*
X616421D03*
X634021D03*
X612021D03*
X620821D03*
X625221D03*
X629621D03*
X642821D03*
X603221D03*
X656021D03*
X660421D03*
X651621D03*
X692921Y-58764D03*
X687921Y-35764D03*
Y-58764D03*
X682921Y-35764D03*
Y-58764D03*
X677921Y-35764D03*
Y-58764D03*
X672921Y-35764D03*
Y-58764D03*
X667921Y-35764D03*
Y-58764D03*
X697921Y-35764D03*
Y-58764D03*
X692921Y-35764D03*
X722921D03*
Y-58764D03*
X717921Y-35764D03*
Y-58764D03*
X712921Y-35764D03*
Y-58764D03*
X707921Y-35764D03*
Y-58764D03*
X702921Y-35764D03*
Y-58764D03*
X695790Y351300D03*
X695606Y638753D03*
X673606D03*
X708806D03*
X704406D03*
X700006D03*
X722006D03*
X717606D03*
X713206D03*
X664806D03*
X669206D03*
X686806D03*
X682406D03*
X678006D03*
X691206D03*
X664821Y660756D03*
X695621D03*
X708821D03*
X700021D03*
X704421D03*
X669221D03*
X686821D03*
X691221D03*
X678021D03*
X673621D03*
X682421D03*
X722021D03*
X717621D03*
X713221D03*
X777921Y-58764D03*
X772921Y-35764D03*
Y-58764D03*
X767921Y-35764D03*
Y-58764D03*
X762921Y-35764D03*
Y-58764D03*
X757921Y-35764D03*
Y-58764D03*
X752921Y-35764D03*
Y-58764D03*
X787921Y-35764D03*
Y-58764D03*
X782921Y-35764D03*
Y-58764D03*
X777921Y-35764D03*
X747921D03*
Y-58764D03*
X742921Y-35764D03*
Y-58764D03*
X737921Y-35764D03*
Y-58764D03*
X732921Y-35764D03*
Y-58764D03*
X727921Y-35764D03*
Y-58764D03*
X786674Y211463D03*
X785920Y204763D03*
X786300Y207400D03*
X787200Y244200D03*
Y271900D03*
X787100Y241100D03*
X770632Y234833D03*
X770965Y237519D03*
X773800Y237700D03*
X768382Y237861D03*
X769637Y266647D03*
X770485Y269489D03*
X772630Y266810D03*
X787200Y276400D03*
X787100Y303900D03*
X775200Y301200D03*
X770900Y301800D03*
X768290Y301780D03*
X747498Y335516D03*
X750298Y338316D03*
Y335516D03*
X744698Y338316D03*
Y335516D03*
X747498Y338316D03*
X769440Y298735D03*
X772400Y299400D03*
X787000Y308300D03*
X771730Y330665D03*
X775732Y332989D03*
X770278Y333272D03*
X772949Y333009D03*
X787400Y340400D03*
X747000Y386000D03*
X743500D03*
X750500D03*
X754000D03*
X750298Y344833D03*
X744698Y347833D03*
X747498D03*
X750298D03*
X747673Y364009D03*
X745073D03*
X750273D03*
X747573Y366909D03*
X744973D03*
X750173D03*
X744698Y344833D03*
X747498D03*
X747000Y380000D03*
X743500D03*
X753874Y379863D03*
X750500Y380000D03*
Y374000D03*
X754000D03*
X747000D03*
X743500D03*
X769380Y366440D03*
X775070Y365070D03*
X772290Y365020D03*
X769440Y363810D03*
X785400Y372400D03*
X775420Y397110D03*
X772742Y397209D03*
X766860Y396240D03*
X769770Y396070D03*
X770406Y638753D03*
X779206D03*
X774806D03*
X730806D03*
X726406D03*
X739606D03*
X735206D03*
X748406D03*
X744006D03*
X766006D03*
X761606D03*
X757206D03*
X752806D03*
X783606D03*
X744021Y660756D03*
X735221D03*
X779221D03*
X770421D03*
X774821D03*
X726421D03*
X730821D03*
X739621D03*
X748421D03*
X783621D03*
X757221D03*
X761621D03*
X752821D03*
X766021D03*
X842921Y-35764D03*
X837921Y-58764D03*
Y-35764D03*
X832921Y-58764D03*
X847921D03*
Y-35764D03*
X842921Y-58764D03*
X832921Y-35764D03*
X827921Y-58764D03*
Y-35764D03*
X822921Y-58764D03*
Y-35764D03*
X817921Y-58764D03*
Y-35764D03*
X812921Y-58764D03*
Y-35764D03*
X807921Y-58764D03*
Y-35764D03*
X802921Y-58764D03*
Y-35764D03*
X797921D03*
Y-58764D03*
X792921Y-35764D03*
Y-58764D03*
X816900Y216300D03*
X816874Y212863D03*
X814274D03*
X811674D03*
X808818Y211179D03*
X808618Y208579D03*
X803200Y213100D03*
X800600D03*
X794474Y211463D03*
X791874D03*
X789274D03*
X788522Y204343D03*
X791122Y204339D03*
X829327Y214740D03*
X832276Y214754D03*
X827322Y217430D03*
X826700Y214802D03*
X824072Y214865D03*
X824446Y217476D03*
X821775Y217617D03*
X821466Y214925D03*
X789432Y236947D03*
X789400Y273700D03*
X811983Y244843D03*
Y242243D03*
X814583Y239643D03*
X815432Y237000D03*
X814583Y244843D03*
Y242243D03*
X812832Y237000D03*
X811983Y239643D03*
X802432Y237000D03*
X799832D03*
X792032D03*
X794632D03*
X810232D03*
X797232D03*
X805032D03*
X807632D03*
X791000Y244400D03*
X793600D03*
X816800Y234300D03*
X816900Y230900D03*
X817000Y252500D03*
X789800Y276400D03*
X792400D03*
X801991Y276557D03*
X804591D03*
X792191Y269101D03*
X789591D03*
X814891Y271657D03*
Y274257D03*
Y276857D03*
Y269057D03*
X812291D03*
Y274257D03*
Y276857D03*
Y271657D03*
X817000Y255100D03*
Y257700D03*
X848282Y251727D03*
X828180Y231748D03*
X828682Y237027D03*
X831682D03*
X828682Y234327D03*
X837500Y239500D03*
X845050Y229400D03*
X837500Y234050D03*
Y236650D03*
X834682Y236877D03*
X840155Y234245D03*
X834700Y234200D03*
X831682Y234327D03*
X834682Y239627D03*
X831682D03*
X828682D03*
X848282Y246427D03*
Y249027D03*
X825682Y239627D03*
Y234327D03*
Y237027D03*
X825313Y231753D03*
X848382Y279727D03*
Y277027D03*
Y274427D03*
X825464Y277510D03*
Y274910D03*
Y280110D03*
X822464D03*
Y277510D03*
Y274910D03*
X834464Y280110D03*
X831464D03*
X828464Y277510D03*
Y274910D03*
Y280110D03*
X834464Y277510D03*
X831464D03*
X834464Y274910D03*
X845050Y252250D03*
X817491Y276857D03*
Y274257D03*
Y271657D03*
Y269057D03*
X837264Y274910D03*
Y280110D03*
Y277510D03*
X840064D03*
Y280110D03*
X817183Y242243D03*
Y239643D03*
Y244843D03*
X818032Y237000D03*
X822682Y234327D03*
Y231727D03*
Y237027D03*
Y239627D03*
X831464Y274910D03*
X844400Y280500D03*
X848282Y254327D03*
X788600Y306100D03*
X789500Y301200D03*
X797300D03*
X799900D03*
X810300D03*
X802500D03*
X812900D03*
X807700D03*
X805100D03*
X815500D03*
X811991Y308957D03*
Y306357D03*
Y303757D03*
X814591Y306357D03*
Y308957D03*
Y303757D03*
X792900Y308400D03*
X789900D03*
X794700Y301200D03*
X792100D03*
X793000Y340400D03*
X790300Y340300D03*
X816991Y337357D03*
Y334757D03*
Y339957D03*
X814391D03*
Y337357D03*
Y334757D03*
X811791Y337357D03*
Y339957D03*
Y334757D03*
X791879Y332798D03*
X794600Y332600D03*
X816938Y319888D03*
Y323888D03*
X817100Y317000D03*
X848382Y282327D03*
X834682Y298527D03*
X828682D03*
X825682D03*
Y295527D03*
Y301227D03*
Y303927D03*
X822682D03*
Y301227D03*
Y295527D03*
Y298527D03*
X844300Y312450D03*
X831682Y298527D03*
X837782Y298127D03*
Y301027D03*
Y303927D03*
X818100Y301200D03*
X817191Y303757D03*
Y306357D03*
Y308957D03*
X834682Y301227D03*
X831682D03*
X828682D03*
X831682Y303927D03*
X834682D03*
X822482Y339827D03*
Y337027D03*
X831482D03*
X834482D03*
X828482Y339827D03*
X831482D03*
X834482D03*
X840282Y340227D03*
X840382Y337427D03*
X837382Y339877D03*
Y337077D03*
X847682Y314627D03*
X847982Y338327D03*
Y341327D03*
X828482Y337027D03*
X828682Y303927D03*
X847682Y309327D03*
Y312027D03*
Y306727D03*
X825482Y339827D03*
Y337027D03*
X789860Y364947D03*
X816591Y369857D03*
Y372457D03*
X811391Y369857D03*
X813991D03*
Y372457D03*
X811391D03*
X790900Y372300D03*
X788300Y372400D03*
X802759Y364575D03*
X816672Y358809D03*
X795310Y364721D03*
X816593Y356210D03*
X807959Y364575D03*
X805359D03*
X810559D03*
X815759D03*
X813159D03*
X816900Y361400D03*
X792610Y364821D03*
X816591Y375057D03*
X792238Y396753D03*
X789600Y396809D03*
X811515Y397289D03*
X808915D03*
X813648Y395557D03*
X815472Y390442D03*
X814877Y393138D03*
X792000Y399409D03*
X789400D03*
X822089Y362782D03*
Y359782D03*
X822482Y342827D03*
X828482D03*
X831482D03*
X834482D03*
X828089Y359841D03*
X834089D03*
X831089D03*
X844350Y344000D03*
X840262Y343011D03*
X837382Y342877D03*
X847982Y344327D03*
X834089Y362782D03*
X831089D03*
X828089D03*
X825482Y342827D03*
X825089Y359841D03*
Y362782D03*
X849606Y638753D03*
X836406D03*
X832006D03*
X796806D03*
X801206D03*
X792406D03*
X827606D03*
X818806D03*
X823206D03*
X810006D03*
X788006D03*
X845206D03*
X814406D03*
X805606D03*
X840806D03*
X849621Y660756D03*
X832021D03*
X810021D03*
X818821D03*
X836421D03*
X788021D03*
X814421D03*
X801221D03*
X805621D03*
X823221D03*
X827621D03*
X840821D03*
X796821D03*
X792421D03*
X845221D03*
X907921Y-58764D03*
Y-35764D03*
X902921Y-58764D03*
Y-35764D03*
X897921Y-58764D03*
Y-35764D03*
X892921Y-58764D03*
Y-35764D03*
X887921Y-58764D03*
Y-35764D03*
X882921Y-58764D03*
Y-35764D03*
X877921Y-58764D03*
Y-35764D03*
X872921Y-58764D03*
Y-35764D03*
X867921Y-58764D03*
Y-35764D03*
X862921Y-58764D03*
Y-35764D03*
X857921Y-58764D03*
Y-35764D03*
X852921Y-58764D03*
Y-35764D03*
X854282Y251727D03*
X857282D03*
X851282D03*
X857282Y249027D03*
Y246427D03*
X851282D03*
Y249027D03*
X854282D03*
Y246427D03*
X851382Y277027D03*
Y274427D03*
X857382Y277027D03*
X854382Y279727D03*
X857382D03*
X854382Y274427D03*
X857382D03*
X854382Y277027D03*
X874586Y259278D03*
X854282Y254327D03*
X857282D03*
X869586Y254278D03*
X851282Y254327D03*
X851382Y279727D03*
X884586Y269278D03*
X879586Y264278D03*
X889586Y274278D03*
X851382Y282327D03*
X854382D03*
X857382D03*
X851075Y335405D03*
X857075D03*
X856982Y338327D03*
X853982D03*
X856682Y314627D03*
X853682D03*
X850682D03*
X856982Y341327D03*
X853982D03*
X862008Y341100D03*
X850982Y338327D03*
Y341327D03*
X872008Y331100D03*
X867008Y336100D03*
X850682Y306727D03*
Y309327D03*
Y312027D03*
X856682Y309327D03*
X853682D03*
X856682Y306727D03*
X853682D03*
X856682Y312027D03*
X853682D03*
X877008Y326100D03*
X854075Y335405D03*
X856982Y344327D03*
X853982D03*
X850982D03*
X858406Y638753D03*
X854006D03*
X884806D03*
X880406D03*
X876006D03*
X871606D03*
X867206D03*
X911206D03*
X906806D03*
X889206D03*
X898006D03*
X902406D03*
X893606D03*
X862806D03*
X854021Y660756D03*
X858421D03*
X862821D03*
X898021D03*
X902421D03*
X871621D03*
X884821D03*
X893621D03*
X867221D03*
X889221D03*
X911221D03*
X906821D03*
X880421D03*
X876021D03*
X937921Y-35764D03*
X932921Y-58764D03*
Y-35764D03*
X927921Y-58764D03*
Y-35764D03*
X922921Y-58764D03*
Y-35764D03*
X917921Y-58764D03*
Y-35764D03*
X912921Y-58764D03*
Y-35764D03*
X942921D03*
X967921D03*
X962921Y-58764D03*
Y-35764D03*
X957921Y-58764D03*
Y-35764D03*
X952921Y-58764D03*
Y-35764D03*
X947921Y-58764D03*
Y-35764D03*
X942921Y-58764D03*
X972921D03*
Y-35764D03*
X967921Y-58764D03*
X937921D03*
X924406Y638753D03*
X920006D03*
X915606D03*
X972806D03*
X968406D03*
X964006D03*
X917100Y649300D03*
X942006Y638753D03*
X937606D03*
X933206D03*
X928806D03*
X959606D03*
X955206D03*
X950806D03*
X946406D03*
X959621Y660756D03*
X964021D03*
X968421D03*
X972821D03*
X920021D03*
X915621D03*
X924421D03*
X946421D03*
X942021D03*
X937621D03*
X933221D03*
X928821D03*
X955221D03*
X950821D03*
X1002921Y-58764D03*
Y-35764D03*
X997921Y-58764D03*
Y-35764D03*
X992921Y-58764D03*
Y-35764D03*
X987921Y-58764D03*
Y-35764D03*
X982921Y-58764D03*
Y-35764D03*
X977921Y-58764D03*
Y-35764D03*
X1032921Y-58764D03*
Y-35764D03*
X1027921Y-58764D03*
Y-35764D03*
X1022921Y-58764D03*
Y-35764D03*
X1017921Y-58764D03*
Y-35764D03*
X1012921Y-58764D03*
Y-35764D03*
X1007921Y-58764D03*
Y-35764D03*
X1024994Y292918D03*
X1017630Y292910D03*
X1020702Y292904D03*
X1027902D03*
X1031953Y292910D03*
X1024140Y309910D03*
X1021065Y309759D03*
X1017083Y309910D03*
X1032042D03*
X1028136Y309815D03*
X1003606Y638753D03*
X1012406D03*
X977206D03*
X990406D03*
X986006D03*
X994806D03*
X1016806D03*
X1021206D03*
X981606D03*
X999206D03*
X1025606D03*
X1008006D03*
X1030006D03*
X1034406D03*
X999221Y660756D03*
X1034421D03*
X1030021D03*
X1008021D03*
X1012421D03*
X1003621D03*
X1016821D03*
X977221D03*
X981621D03*
X1021221D03*
X1025621D03*
X994821D03*
X986021D03*
X990421D03*
X1067921Y-58764D03*
Y-35764D03*
X1062921Y-58764D03*
Y-35764D03*
X1057921Y-58764D03*
Y-35764D03*
X1052921Y-58764D03*
Y-35764D03*
X1047921Y-58764D03*
Y-35764D03*
X1042921Y-58764D03*
Y-35764D03*
X1037921Y-58764D03*
Y-35764D03*
X1092921Y-58764D03*
Y-35764D03*
X1087921Y-58764D03*
Y-35764D03*
X1082921Y-58764D03*
Y-35764D03*
X1077921Y-58764D03*
Y-35764D03*
X1072921Y-58764D03*
Y-35764D03*
X1075865Y264766D03*
X1070300Y264900D03*
X1073200Y264991D03*
X1057202Y264899D03*
X1060402Y264799D03*
X1066300Y264700D03*
X1063402Y264799D03*
X1054202Y264899D03*
X1086061Y262300D03*
X1086000Y264900D03*
X1046276Y292910D03*
X1049502Y292904D03*
X1053684Y292910D03*
X1056702Y292904D03*
X1039182Y292919D03*
X1042302Y292904D03*
X1035102D03*
X1049547Y309904D03*
X1046612Y309910D03*
X1056747Y309904D03*
X1053594Y309910D03*
X1042347Y309904D03*
X1039383Y309910D03*
X1035147Y309904D03*
X1086126Y338758D03*
X1083301Y338841D03*
X1096006Y638753D03*
X1078406D03*
X1082806D03*
X1074006D03*
X1069606D03*
X1091606D03*
X1052006D03*
X1038806D03*
X1087206D03*
X1060806D03*
X1056406D03*
X1065206D03*
X1043206D03*
X1047606D03*
X1078421Y660756D03*
X1060821D03*
X1087221D03*
X1038821D03*
X1091621D03*
X1052021D03*
X1074021D03*
X1065221D03*
X1096021D03*
X1056421D03*
X1043221D03*
X1047621D03*
X1082821D03*
X1069621D03*
X1157921Y-58764D03*
Y-35764D03*
X1152921Y-58764D03*
Y-35764D03*
X1147921Y-58764D03*
Y-35764D03*
X1142921Y-58764D03*
Y-35764D03*
X1137921Y-58764D03*
Y-35764D03*
X1132921Y-58764D03*
Y-35764D03*
X1127921Y-58764D03*
Y-35764D03*
X1122921Y-58764D03*
Y-35764D03*
X1117921Y-58764D03*
Y-35764D03*
X1112921Y-58764D03*
Y-35764D03*
X1107921Y-58764D03*
Y-35764D03*
X1102921Y-58764D03*
Y-35764D03*
X1097921Y-58764D03*
Y-35764D03*
X1135606Y638753D03*
X1126806D03*
X1144406D03*
X1140006D03*
X1118006D03*
X1122406D03*
X1153206D03*
X1157606D03*
X1104806D03*
X1100406D03*
X1131206D03*
X1148806D03*
X1109206D03*
X1113606D03*
X1157621Y660756D03*
X1148821D03*
X1122421D03*
X1126821D03*
X1100421D03*
X1118021D03*
X1140021D03*
X1113621D03*
X1109221D03*
X1153221D03*
X1144421D03*
X1104821D03*
X1131221D03*
X1135621D03*
X1217921Y-58764D03*
Y-35764D03*
X1212921Y-58764D03*
Y-35764D03*
X1207921Y-58764D03*
Y-35764D03*
X1202921Y-58764D03*
Y-35764D03*
X1197921Y-58764D03*
Y-35764D03*
X1192921Y-58764D03*
Y-35764D03*
X1187921Y-58764D03*
Y-35764D03*
X1182921Y-58764D03*
Y-35764D03*
X1177921Y-58764D03*
Y-35764D03*
X1172921Y-58764D03*
Y-35764D03*
X1167921Y-58764D03*
Y-35764D03*
X1162921Y-58764D03*
Y-35764D03*
X1188406Y638753D03*
X1214806D03*
X1197206D03*
X1201606D03*
X1192806D03*
X1170806D03*
X1162006D03*
X1166406D03*
X1206006D03*
X1219206D03*
X1179606D03*
X1175206D03*
X1210406D03*
X1184006D03*
X1184021Y660756D03*
X1219221D03*
X1192821D03*
X1188421D03*
X1201621D03*
X1179621D03*
X1214821D03*
X1206021D03*
X1166421D03*
X1210421D03*
X1170821D03*
X1162021D03*
X1175221D03*
X1197221D03*
X1232921Y-58764D03*
Y-35764D03*
X1227921Y-58764D03*
Y-35764D03*
X1222921Y-58764D03*
Y-35764D03*
X1252921Y-58764D03*
Y-35764D03*
X1247921Y-58764D03*
Y-35764D03*
X1242921Y-58764D03*
Y-35764D03*
X1237921Y-58764D03*
Y-35764D03*
X1257921D03*
X1272921Y-58764D03*
Y-35764D03*
X1267921Y-58764D03*
Y-35764D03*
X1262921Y-58764D03*
Y-35764D03*
X1257921Y-58764D03*
X1277921D03*
Y-35764D03*
X1255381Y646264D03*
X1263206Y638753D03*
X1223606D03*
X1228006D03*
X1258806D03*
X1241206D03*
X1236806D03*
X1250006D03*
X1245606D03*
X1276406D03*
X1254406D03*
X1280806D03*
X1272006D03*
X1267606D03*
X1232406D03*
X1255381Y652264D03*
X1228021Y660756D03*
X1232421D03*
X1280821D03*
X1245621D03*
X1236821D03*
X1223621D03*
X1276421D03*
X1241221D03*
X1272021D03*
X1258821D03*
X1250021D03*
X1254421D03*
X1263221D03*
X1267621D03*
X1342921Y-35764D03*
Y-58764D03*
X1317921D03*
X1312921Y-35764D03*
Y-58764D03*
X1307921Y-35764D03*
Y-58764D03*
X1302921Y-35764D03*
Y-58764D03*
X1297921D03*
Y-35764D03*
X1292921Y-58764D03*
Y-35764D03*
X1287921Y-58764D03*
Y-35764D03*
X1282921Y-58764D03*
Y-35764D03*
X1322921D03*
Y-58764D03*
X1317921Y-35764D03*
X1337921D03*
Y-58764D03*
X1332921Y-35764D03*
Y-58764D03*
X1327921Y-35764D03*
Y-58764D03*
X1324806Y638753D03*
X1298406D03*
X1285206D03*
X1294006D03*
X1302806D03*
X1333606D03*
X1338006D03*
X1320406D03*
X1311606D03*
X1329206D03*
X1307206D03*
X1342406D03*
X1289606D03*
X1316006D03*
X1329221Y660756D03*
X1311621D03*
X1316021D03*
X1333621D03*
X1342421D03*
X1285221D03*
X1324821D03*
X1338021D03*
X1298421D03*
X1289621D03*
X1294021D03*
X1320421D03*
X1302821D03*
X1307221D03*
X1402921Y-58764D03*
X1397921D03*
X1402921Y-35764D03*
X1392921Y-58764D03*
X1397921Y-35764D03*
X1387921Y-58764D03*
X1392921Y-35764D03*
X1382921Y-58764D03*
X1387921Y-35764D03*
X1377921Y-58764D03*
X1382921Y-35764D03*
X1372921Y-58764D03*
X1377921Y-35764D03*
X1367921Y-58764D03*
X1362921Y-35764D03*
Y-58764D03*
X1357921Y-35764D03*
Y-58764D03*
X1352921Y-35764D03*
Y-58764D03*
X1347921Y-35764D03*
Y-58764D03*
X1351206Y638753D03*
X1360006D03*
X1404506Y638853D03*
X1355606Y638753D03*
X1386906Y638853D03*
X1364406Y638753D03*
X1391306Y638853D03*
X1346806Y638753D03*
X1400106Y638853D03*
X1382006Y638753D03*
X1377606D03*
X1373206D03*
X1395706Y638853D03*
X1368806Y638753D03*
X1368821Y660756D03*
X1346821D03*
X1355621D03*
X1360021D03*
X1364421D03*
X1351221D03*
X1404521Y660856D03*
X1400121D03*
X1395721D03*
X1386921D03*
X1377621Y660756D03*
X1382021D03*
X1373221D03*
X1391321Y660856D03*
X1407921Y-58764D03*
X1412921Y-35764D03*
X1407921D03*
X1442921Y-58764D03*
X1447921Y-35764D03*
X1437921Y-58764D03*
X1442921Y-35764D03*
X1432921Y-58764D03*
X1437921Y-35764D03*
X1427921Y-58764D03*
X1432921Y-35764D03*
X1422921Y-58764D03*
X1427921Y-35764D03*
X1417921Y-58764D03*
X1422921Y-35764D03*
X1412921Y-58764D03*
X1417921Y-35764D03*
X1462921Y-58764D03*
X1457921D03*
X1462921Y-35764D03*
X1452921Y-58764D03*
X1457921Y-35764D03*
X1447921Y-58764D03*
X1452921Y-35764D03*
X1431664Y190213D03*
X1422106Y638853D03*
X1466106D03*
X1448506D03*
X1457306D03*
X1417706D03*
X1413306D03*
X1461706D03*
X1452906D03*
X1408906D03*
X1444106D03*
X1435306D03*
X1426506D03*
X1430906D03*
X1439706D03*
X1457321Y660856D03*
X1417721D03*
X1413321D03*
X1408921D03*
X1422121D03*
X1426521D03*
X1435321D03*
X1444121D03*
X1439721D03*
X1430921D03*
X1448521D03*
X1452921D03*
X1466121D03*
X1461721D03*
X1502921Y-58764D03*
X1507921Y-35764D03*
X1497921Y-58764D03*
X1502921Y-35764D03*
X1492921Y-58764D03*
X1497921Y-35764D03*
X1487921Y-58764D03*
X1492921Y-35764D03*
X1482921Y-58764D03*
X1487921Y-35764D03*
X1477921Y-58764D03*
X1482921Y-35764D03*
X1472921Y-58764D03*
X1477921Y-35764D03*
X1467921Y-58764D03*
X1472921Y-35764D03*
X1467921D03*
X1527921Y-58764D03*
X1522921D03*
X1527921Y-35764D03*
X1517921Y-58764D03*
X1522921Y-35764D03*
X1512921Y-58764D03*
X1517921Y-35764D03*
X1507921Y-58764D03*
X1512921Y-35764D03*
X1519608Y646236D03*
X1496906Y638853D03*
X1492506D03*
X1501706Y638753D03*
X1506106D03*
X1514906D03*
X1483706Y638853D03*
X1523706Y638753D03*
X1510506D03*
X1488106Y638853D03*
X1474906D03*
X1519306Y638753D03*
X1479306Y638853D03*
X1528106Y638753D03*
X1470506Y638853D03*
X1519608Y652236D03*
X1496921Y660856D03*
X1483721D03*
X1488121D03*
X1492521D03*
X1479321D03*
X1510521Y660756D03*
X1528121D03*
X1523721D03*
X1501721D03*
X1506121D03*
X1514921D03*
X1519321D03*
X1474921Y660856D03*
X1470521D03*
X1587921Y-58764D03*
X1582921D03*
X1587921Y-35764D03*
X1532921D03*
X1542921D03*
X1532921Y-58764D03*
X1537921Y-35764D03*
X1577921Y-58764D03*
X1582921Y-35764D03*
X1572921Y-58764D03*
X1577921Y-35764D03*
X1567921Y-58764D03*
X1572921Y-35764D03*
X1562921Y-58764D03*
X1567921Y-35764D03*
X1557921Y-58764D03*
X1562921Y-35764D03*
X1552921Y-58764D03*
X1557921Y-35764D03*
X1547921Y-58764D03*
X1552921Y-35764D03*
X1542921Y-58764D03*
X1547921Y-35764D03*
X1537921Y-58764D03*
X1580121Y647556D03*
X1555106Y638753D03*
X1555121Y647556D03*
X1590121D03*
X1590106Y638753D03*
X1590121Y643156D03*
X1585121Y647556D03*
X1585106Y638753D03*
X1585121Y643156D03*
X1565121Y647556D03*
X1570121Y643156D03*
X1570106Y638753D03*
X1565106D03*
X1565121Y643156D03*
X1570121Y647556D03*
X1560121D03*
X1560106Y638753D03*
X1560121Y643156D03*
X1575121D03*
X1575106Y638753D03*
X1575121Y647556D03*
X1555121Y643156D03*
X1580106Y638753D03*
X1580121Y643156D03*
X1550121Y647556D03*
X1541306Y638753D03*
X1545706D03*
X1550106D03*
X1550121Y643156D03*
X1536906Y638753D03*
X1532506D03*
X1565121Y651956D03*
X1570121Y660756D03*
Y656356D03*
X1565121Y660756D03*
X1555121Y651956D03*
X1590121Y660756D03*
Y656356D03*
Y651956D03*
X1585121Y660756D03*
Y656356D03*
Y651956D03*
X1580121Y660756D03*
Y656356D03*
Y651956D03*
X1560121Y660756D03*
Y656356D03*
Y651956D03*
X1555121Y660756D03*
Y656356D03*
X1570121Y651956D03*
X1575121D03*
Y656356D03*
Y660756D03*
X1565121Y656356D03*
X1550121Y651956D03*
Y656356D03*
X1541321Y660756D03*
X1550121D03*
X1545721D03*
X1532521D03*
X1536921D03*
X1642921Y-35764D03*
Y-58764D03*
X1637921Y-35764D03*
Y-58764D03*
X1632921Y-35764D03*
Y-58764D03*
X1627921D03*
X1622921D03*
X1627921Y-35764D03*
X1617921Y-58764D03*
X1622921Y-35764D03*
X1612921Y-58764D03*
X1617921Y-35764D03*
X1607921Y-58764D03*
X1612921Y-35764D03*
X1602921Y-58764D03*
X1607921Y-35764D03*
X1597921Y-58764D03*
X1602921Y-35764D03*
X1592921Y-58764D03*
X1597921Y-35764D03*
X1592921D03*
X1647921D03*
Y-58764D03*
X1625106Y638753D03*
X1625121Y647556D03*
X1630121Y643156D03*
X1630106Y638753D03*
X1630121Y647556D03*
X1635121Y643156D03*
X1635106Y638753D03*
X1635121Y647556D03*
X1640121Y643156D03*
Y647556D03*
X1640106Y638753D03*
X1650121Y647556D03*
X1650106Y638753D03*
X1650121Y643156D03*
X1645121Y647556D03*
X1645106Y638753D03*
X1645121Y643156D03*
X1625121D03*
X1620121Y647556D03*
X1620106Y638753D03*
X1620121Y643156D03*
X1615121Y647556D03*
X1615106Y638753D03*
X1615121Y643156D03*
X1610121Y647556D03*
X1610106Y638753D03*
X1610121Y643156D03*
X1605121Y647556D03*
X1605106Y638753D03*
X1605121Y643156D03*
X1600121Y647556D03*
X1600106Y638753D03*
X1600121Y643156D03*
X1595121Y647556D03*
X1595106Y638753D03*
X1595121Y643156D03*
X1625121Y651956D03*
Y660756D03*
X1630121Y651956D03*
Y656356D03*
Y660756D03*
X1635121Y651956D03*
Y656356D03*
Y660756D03*
X1625121Y656356D03*
X1640121D03*
Y651956D03*
X1650121Y660756D03*
Y656356D03*
Y651956D03*
X1645121Y660756D03*
Y656356D03*
Y651956D03*
X1640121Y660756D03*
X1620121D03*
Y656356D03*
Y651956D03*
X1615121Y660756D03*
Y656356D03*
Y651956D03*
X1610121Y660756D03*
Y656356D03*
Y651956D03*
X1605121Y660756D03*
Y656356D03*
Y651956D03*
X1600121Y660756D03*
Y656356D03*
Y651956D03*
X1595121Y660756D03*
Y656356D03*
Y651956D03*
X1692921Y-40764D03*
X1702921Y-54764D03*
X1687921D03*
X1682921D03*
X1677921D03*
X1672921D03*
X1692921D03*
X1697921D03*
X1707921D03*
X1712921D03*
X1697921Y-40764D03*
X1692921Y-50764D03*
X1687921D03*
X1682921D03*
X1677921D03*
X1672921D03*
X1712921D03*
X1707921D03*
X1702921D03*
X1697921Y-45764D03*
X1707921D03*
X1702921D03*
X1712921D03*
X1697921Y-50764D03*
X1667921Y-35764D03*
X1712921D03*
Y-58764D03*
X1707921Y-35764D03*
Y-58764D03*
X1702921Y-35764D03*
Y-58764D03*
X1697921Y-35764D03*
Y-58764D03*
X1687921Y-40764D03*
X1672921Y-45764D03*
X1677921D03*
X1682921D03*
Y-40764D03*
X1687921Y-45764D03*
X1692921D03*
X1667921Y-58764D03*
X1662921Y-35764D03*
Y-58764D03*
X1657921Y-35764D03*
Y-58764D03*
X1652921Y-35764D03*
Y-58764D03*
X1712921Y-40764D03*
X1707921D03*
X1702921D03*
X1677921D03*
X1672921D03*
X1677921Y-35764D03*
Y-58764D03*
X1672921Y-35764D03*
Y-58764D03*
X1682921Y-35764D03*
Y-58764D03*
X1692921Y-35764D03*
Y-58764D03*
X1687921Y-35764D03*
Y-58764D03*
X1690121Y647556D03*
X1710121D03*
X1710106Y638753D03*
X1710121Y643156D03*
X1705121Y647556D03*
X1705106Y638753D03*
X1695121Y643156D03*
X1695106Y638753D03*
X1695121Y647556D03*
X1700121Y643156D03*
X1700106Y638753D03*
X1685121Y647556D03*
X1685106Y638753D03*
X1685121Y643156D03*
X1680121Y647556D03*
X1680106Y638753D03*
X1680121Y643156D03*
X1675121Y647556D03*
X1675106Y638753D03*
X1675121Y643156D03*
X1670121Y647556D03*
X1670106Y638753D03*
X1670121Y643156D03*
X1665121Y647556D03*
X1665106Y638753D03*
X1665121Y643156D03*
X1660121Y647556D03*
X1660106Y638753D03*
X1660121Y643156D03*
X1655121Y647556D03*
X1655106Y638753D03*
X1655121Y643156D03*
X1690121D03*
X1690106Y638753D03*
X1700121Y647556D03*
X1705121Y643156D03*
X1690121Y656356D03*
Y651956D03*
X1710121Y660756D03*
Y656356D03*
Y651956D03*
X1705121Y660756D03*
Y656356D03*
Y651956D03*
X1690121Y660756D03*
X1695121Y651956D03*
Y656356D03*
Y660756D03*
X1685121Y651956D03*
X1680121Y660756D03*
Y656356D03*
Y651956D03*
X1675121Y660756D03*
Y656356D03*
Y651956D03*
X1670121Y660756D03*
Y656356D03*
Y651956D03*
X1665121Y660756D03*
Y656356D03*
Y651956D03*
X1660121Y660756D03*
Y656356D03*
Y651956D03*
X1655121Y660756D03*
Y656356D03*
Y651956D03*
X1685121Y660756D03*
Y656356D03*
X1700121Y651956D03*
Y656356D03*
Y660756D03*
X1737921Y-50764D03*
X1722921Y-45764D03*
X1727921D03*
X1732921D03*
X1747921D03*
X1752921D03*
X1727921Y-54764D03*
X1757921D03*
X1717921D03*
X1722921D03*
X1767921Y-40764D03*
Y-50764D03*
X1762921D03*
X1757921D03*
X1762921Y-54764D03*
X1752921D03*
X1747921D03*
X1742921D03*
X1737921D03*
X1732921D03*
X1772921D03*
X1767921D03*
X1762921Y-40764D03*
X1772921D03*
X1722921Y-50764D03*
X1717921D03*
X1732921D03*
X1757921Y-40764D03*
X1717921Y-45764D03*
Y-58764D03*
X1742921Y-50764D03*
X1747921D03*
X1752921D03*
X1742921Y-58764D03*
X1737921Y-35764D03*
Y-58764D03*
X1732921Y-35764D03*
Y-58764D03*
X1727921Y-35764D03*
Y-58764D03*
X1722921Y-35764D03*
Y-58764D03*
X1717921Y-35764D03*
X1757921Y-45764D03*
X1762921D03*
X1742921D03*
X1752921Y-40764D03*
X1747921D03*
X1742921D03*
X1737921D03*
X1732921D03*
X1727921D03*
X1722921D03*
X1717921D03*
X1727921Y-50764D03*
X1767921Y-45764D03*
X1772921D03*
X1737921D03*
X1772921Y-35764D03*
Y-58764D03*
X1767921Y-35764D03*
Y-58764D03*
X1762921Y-35764D03*
Y-58764D03*
X1757921Y-35764D03*
Y-58764D03*
X1752921Y-35764D03*
Y-58764D03*
X1747921Y-35764D03*
Y-58764D03*
X1742921Y-35764D03*
X1772921Y-50764D03*
X1728139Y496807D03*
X1725566Y497186D03*
X1723591Y499135D03*
X1725600Y501000D03*
X1775121Y643156D03*
Y647556D03*
X1775106Y638753D03*
X1730121Y647556D03*
X1730106Y638753D03*
X1730121Y643156D03*
X1725121Y647556D03*
X1725106Y638753D03*
X1725121Y643156D03*
X1720121Y647556D03*
X1720106Y638753D03*
X1720121Y643156D03*
X1715121Y647556D03*
X1715106Y638753D03*
X1715121Y643156D03*
X1770121Y647556D03*
X1770106Y638753D03*
X1770121Y643156D03*
X1765121Y647556D03*
X1765106Y638753D03*
X1765121Y643156D03*
X1760121Y647556D03*
X1760106Y638753D03*
X1760121Y643156D03*
X1755121Y647556D03*
X1755106Y638753D03*
X1755121Y643156D03*
X1750121Y647556D03*
X1750106Y638753D03*
X1750121Y643156D03*
X1745121Y647556D03*
X1745106Y638753D03*
X1745121Y643156D03*
X1740121Y647556D03*
X1740106Y638753D03*
X1740121Y643156D03*
X1735121Y647556D03*
X1735106Y638753D03*
X1735121Y643156D03*
X1770121Y660756D03*
X1775121D03*
Y656356D03*
Y651956D03*
X1725121Y660756D03*
Y656356D03*
Y651956D03*
X1720121Y660756D03*
Y656356D03*
Y651956D03*
X1715121Y660756D03*
Y656356D03*
Y651956D03*
X1770121D03*
X1765121Y660756D03*
Y656356D03*
Y651956D03*
X1760121Y660756D03*
Y656356D03*
Y651956D03*
X1755121Y660756D03*
Y656356D03*
Y651956D03*
X1750121Y660756D03*
Y656356D03*
Y651956D03*
X1745121Y660756D03*
Y656356D03*
Y651956D03*
X1740121Y660756D03*
Y656356D03*
Y651956D03*
X1735121Y660756D03*
Y656356D03*
Y651956D03*
X1730121Y660756D03*
Y656356D03*
X1770121D03*
X1730121Y651956D03*
X1817921Y-40764D03*
X1832921Y-45764D03*
Y-54764D03*
X1827921D03*
X1822921D03*
X1817921D03*
X1812921D03*
X1807921D03*
X1802921D03*
X1797921D03*
X1792921D03*
X1787921D03*
X1782921D03*
X1777921D03*
X1832921Y-50764D03*
X1827921D03*
X1822921D03*
X1817921D03*
X1812921D03*
X1807921D03*
X1802921D03*
X1797921D03*
X1792921D03*
X1787921D03*
X1782921Y-40764D03*
X1792921D03*
X1802921D03*
X1807921D03*
X1822921D03*
X1827921D03*
X1832921D03*
X1812921D03*
X1797921D03*
X1777921Y-45764D03*
X1782921D03*
X1787921D03*
X1792921D03*
X1797921D03*
X1802921D03*
X1807921D03*
X1812921D03*
X1817921D03*
X1822921D03*
X1787921Y-40764D03*
X1832921Y-35764D03*
Y-58764D03*
X1827921Y-35764D03*
Y-58764D03*
X1822921Y-35764D03*
Y-58764D03*
X1817921Y-35764D03*
Y-58764D03*
X1812921Y-35764D03*
Y-58764D03*
X1807921Y-35764D03*
Y-58764D03*
X1802921Y-35764D03*
Y-58764D03*
X1797921Y-35764D03*
Y-58764D03*
X1792921Y-35764D03*
Y-58764D03*
X1787921Y-35764D03*
Y-58764D03*
X1782921Y-35764D03*
Y-58764D03*
X1777921Y-35764D03*
Y-58764D03*
X1782921Y-50764D03*
X1777921D03*
Y-40764D03*
X1827921Y-45764D03*
X1780121Y643156D03*
X1780106Y638753D03*
X1780121Y647556D03*
X1785121Y643156D03*
X1790121D03*
X1835121Y647556D03*
X1835106Y638753D03*
X1835121Y643156D03*
X1830121Y647556D03*
X1830106Y638753D03*
X1830121Y643156D03*
X1825121Y647556D03*
X1825106Y638753D03*
X1825121Y643156D03*
X1820121Y647556D03*
X1820106Y638753D03*
X1820121Y643156D03*
X1815121Y647556D03*
X1815106Y638753D03*
X1815121Y643156D03*
X1810121Y647556D03*
X1810106Y638753D03*
X1810121Y643156D03*
X1805121Y647556D03*
X1805106Y638753D03*
X1805121Y643156D03*
X1800121Y647556D03*
X1800106Y638753D03*
X1800121Y643156D03*
X1795121Y647556D03*
X1795106Y638753D03*
X1795121Y643156D03*
X1790121Y647556D03*
X1790106Y638753D03*
X1785121Y647556D03*
X1785106Y638753D03*
X1800121Y656356D03*
X1780121Y651956D03*
Y656356D03*
Y660756D03*
X1835121D03*
Y656356D03*
Y651956D03*
X1830121Y660756D03*
Y656356D03*
Y651956D03*
X1825121Y660756D03*
Y656356D03*
Y651956D03*
X1820121Y660756D03*
Y656356D03*
Y651956D03*
X1815121Y660756D03*
Y656356D03*
Y651956D03*
X1810121Y660756D03*
Y656356D03*
Y651956D03*
X1805121Y660756D03*
Y656356D03*
Y651956D03*
X1800121Y660756D03*
Y651956D03*
X1795121Y660756D03*
Y656356D03*
Y651956D03*
X1790121Y660756D03*
Y656356D03*
Y651956D03*
X1785121Y660756D03*
Y656356D03*
Y651956D03*
X1857921Y-45764D03*
X1837921D03*
X1897921D03*
X1892921D03*
X1887921D03*
X1882921D03*
X1877921D03*
X1872921D03*
X1867921D03*
X1862921D03*
X1842921Y-54764D03*
X1852921Y-45764D03*
X1847921D03*
X1842921D03*
X1897921Y-54764D03*
X1892921D03*
X1887921D03*
X1882921D03*
X1877921D03*
X1872921D03*
X1867921D03*
X1862921D03*
X1857921D03*
X1852921D03*
X1847921D03*
X1837921D03*
X1897921Y-50764D03*
X1892921D03*
X1887921D03*
X1882921D03*
X1877921D03*
X1872921D03*
X1867921D03*
X1862921D03*
X1857921D03*
X1852921D03*
X1847921D03*
X1842921D03*
X1837921D03*
X1892921Y-40764D03*
X1897921D03*
X1877921D03*
X1882921D03*
X1887921D03*
X1857921D03*
X1862921D03*
X1867921D03*
X1872921D03*
X1837921D03*
X1842921D03*
X1847921D03*
X1852921D03*
Y-35764D03*
Y-58764D03*
X1847921Y-35764D03*
Y-58764D03*
X1842921Y-35764D03*
Y-58764D03*
X1837921Y-35764D03*
Y-58764D03*
X1862921D03*
X1857921Y-35764D03*
Y-58764D03*
X1882921D03*
X1877921Y-35764D03*
Y-58764D03*
X1872921Y-35764D03*
Y-58764D03*
X1867921Y-35764D03*
Y-58764D03*
X1862921Y-35764D03*
X1897921D03*
Y-58764D03*
X1892921Y-35764D03*
Y-58764D03*
X1887921Y-35764D03*
Y-58764D03*
X1882921Y-35764D03*
X1895121Y647556D03*
X1895106Y638753D03*
X1895121Y643156D03*
X1890121Y647556D03*
X1890106Y638753D03*
X1890121Y643156D03*
X1885121Y647556D03*
X1885106Y638753D03*
X1885121Y643156D03*
X1880121Y647556D03*
X1880106Y638753D03*
X1880121Y643156D03*
X1875121Y647556D03*
X1875106Y638753D03*
X1875121Y643156D03*
X1870121Y647556D03*
X1870106Y638753D03*
X1870121Y643156D03*
X1865121Y647556D03*
X1865106Y638753D03*
X1865121Y643156D03*
X1860121Y647556D03*
X1860106Y638753D03*
X1860121Y643156D03*
X1855121Y647556D03*
X1855106Y638753D03*
X1855121Y643156D03*
X1850121Y647556D03*
X1850106Y638753D03*
X1850121Y643156D03*
X1845121Y647556D03*
X1845106Y638753D03*
X1845121Y643156D03*
X1840121Y647556D03*
X1840106Y638753D03*
X1840121Y643156D03*
X1895121Y660756D03*
Y656356D03*
Y651956D03*
X1890121Y660756D03*
Y656356D03*
Y651956D03*
X1885121Y660756D03*
Y656356D03*
Y651956D03*
X1880121Y660756D03*
Y656356D03*
Y651956D03*
X1875121Y660756D03*
Y656356D03*
Y651956D03*
X1870121Y660756D03*
Y656356D03*
Y651956D03*
X1865121Y660756D03*
Y656356D03*
Y651956D03*
X1860121Y660756D03*
Y656356D03*
Y651956D03*
X1855121Y660756D03*
Y656356D03*
Y651956D03*
X1850121Y660756D03*
Y656356D03*
Y651956D03*
X1845121Y660756D03*
Y656356D03*
Y651956D03*
X1840121Y660756D03*
Y656356D03*
Y651956D03*
X1927921Y-40764D03*
X1947921Y-45764D03*
X1942921D03*
X1937921D03*
X1932921D03*
X1927921D03*
X1922921D03*
X1917921D03*
X1912921D03*
X1907921D03*
X1902921D03*
X1927921Y-50764D03*
X1932921D03*
Y-40764D03*
X1937921D03*
X1942921D03*
X1947921D03*
X1907921Y-50764D03*
X1902921D03*
X1922921Y-40764D03*
X1917921D03*
X1912921D03*
X1907921D03*
X1902921D03*
X1922921Y-54764D03*
X1917921D03*
X1912921D03*
X1907921D03*
X1902921D03*
X1927921D03*
X1932921D03*
X1937921D03*
X1942921D03*
X1947921D03*
X1952921D03*
X1957921D03*
Y-50764D03*
X1952921D03*
X1947921D03*
X1942921D03*
X1937921D03*
X1922921D03*
X1917921D03*
X1912921D03*
X1957921Y-35764D03*
Y-58764D03*
X1952921Y-35764D03*
Y-58764D03*
X1947921Y-35764D03*
Y-58764D03*
X1942921Y-35764D03*
Y-58764D03*
X1937921Y-35764D03*
Y-58764D03*
X1932921Y-35764D03*
Y-58764D03*
X1927921Y-35764D03*
Y-58764D03*
X1922921Y-35764D03*
Y-58764D03*
X1917921Y-35764D03*
Y-58764D03*
X1912921Y-35764D03*
Y-58764D03*
X1907921Y-35764D03*
Y-58764D03*
X1902921Y-35764D03*
Y-58764D03*
X1937100Y146900D03*
X1914037Y243646D03*
X1960106Y638753D03*
X1955106D03*
X1950106D03*
X1945121Y647556D03*
Y643156D03*
X1945106Y638753D03*
X1940121Y647556D03*
Y643156D03*
X1940106Y638753D03*
X1935121Y647556D03*
Y643156D03*
X1935106Y638753D03*
X1930106D03*
X1925106D03*
X1920121Y647556D03*
X1910121Y643156D03*
X1910106Y638753D03*
X1905121Y647556D03*
Y643156D03*
X1905106Y638753D03*
X1900121Y647556D03*
X1900106Y638753D03*
X1900121Y643156D03*
X1920106Y638753D03*
X1915121Y647556D03*
X1920121Y643156D03*
X1910121Y647556D03*
X1915106Y638753D03*
X1915121Y643156D03*
X1960121Y656356D03*
Y660756D03*
X1955121Y656356D03*
Y660756D03*
X1950121Y651956D03*
Y656356D03*
Y660756D03*
X1945121Y651956D03*
Y656356D03*
Y660756D03*
X1940121Y651956D03*
Y656356D03*
Y660756D03*
X1935121Y651956D03*
Y656356D03*
Y660756D03*
X1930121Y651956D03*
Y656356D03*
Y660756D03*
X1925121Y651956D03*
Y656356D03*
Y660756D03*
X1920121Y651956D03*
Y656356D03*
X1905121Y651956D03*
Y656356D03*
Y660756D03*
X1900121D03*
Y656356D03*
Y651956D03*
X1915121D03*
Y656356D03*
Y660756D03*
X1920121D03*
X1910121D03*
Y656356D03*
Y651956D03*
X1967921Y-45764D03*
X1962921D03*
Y-40764D03*
X1967921D03*
Y-54764D03*
X1962921D03*
X1967921Y-50764D03*
X1962921D03*
X1967921Y-35764D03*
Y-58764D03*
X1962921Y-35764D03*
Y-58764D03*
X1970121Y647556D03*
Y643156D03*
X1970106Y638753D03*
X1965121Y647556D03*
Y643156D03*
X1965106Y638753D03*
X1970121Y651956D03*
Y656356D03*
Y660756D03*
X1965121Y651956D03*
Y656356D03*
Y660756D03*
G54D20*
X72074Y243282D03*
X65180Y243368D03*
X61800Y243400D03*
X68498Y243368D03*
X49560Y649770D03*
Y644670D03*
X54360D03*
X49560Y649570D03*
Y644670D03*
X54360D03*
X49560Y654670D03*
X54360D03*
X49560D03*
X54360D03*
X214820Y649570D03*
Y644670D03*
X210020D03*
X214820Y649770D03*
Y644670D03*
X210020D03*
X214820Y654670D03*
X210020D03*
X214820D03*
X210020D03*
X238282Y649670D03*
Y644770D03*
X243082D03*
X238282Y649870D03*
Y644770D03*
X243082D03*
X238282Y654770D03*
X243082D03*
X238282D03*
X243082D03*
X402404Y649650D03*
Y644550D03*
X397604D03*
X402404Y649450D03*
Y644550D03*
X397604D03*
X402404Y654550D03*
X397604D03*
X402404D03*
X397604D03*
X425750Y649400D03*
Y644500D03*
Y649600D03*
Y644500D03*
Y654500D03*
D03*
X589871Y649379D03*
Y644279D03*
X589872Y649180D03*
Y644280D03*
X589871Y654279D03*
X589872Y654280D03*
X613298Y649331D03*
Y644231D03*
X618098D03*
X613298Y649131D03*
Y644231D03*
X618098D03*
X613298Y654231D03*
X618098D03*
X613298D03*
X618098D03*
X905515Y649159D03*
Y644259D03*
X900715D03*
X905515Y649359D03*
Y644259D03*
X900715D03*
X905515Y654259D03*
X900715D03*
X905515D03*
X900715D03*
X928952Y649120D03*
Y644220D03*
X933752D03*
X928952Y649320D03*
Y644220D03*
X933752D03*
X928952Y654220D03*
X933752D03*
X928952D03*
X933752D03*
X1219041Y649348D03*
Y644248D03*
X1214241D03*
X1219041Y649148D03*
Y644248D03*
X1214241D03*
X1219041Y654248D03*
X1214241D03*
X1219041D03*
X1214241D03*
X1242450Y649150D03*
Y644250D03*
Y649350D03*
Y644250D03*
Y654250D03*
D03*
X1532539Y649378D03*
Y644278D03*
Y649178D03*
Y644278D03*
Y654278D03*
D03*
G54D11*
X-15748Y116969D03*
Y132717D03*
G54D30*
G01X1400616Y13795D02*
X1396800Y9979D01*
Y8899D01*
X1385070Y-2831D01*
X1380982D01*
X1380008Y-3805D01*
G01X1366789Y5776D02*
Y5112D01*
X1368801Y3100D01*
X1370755D01*
X1373850Y5D01*
Y-1250D01*
X1377145Y-4545D01*
X1379268D01*
X1380008Y-3805D01*
G54D21*
X321061Y28014D03*
X324407D03*
X314368D03*
X354525Y28022D03*
X351179D03*
X344486D03*
X341140D03*
X321061Y54857D03*
X327754Y35957D03*
Y46914D03*
X324407Y54857D03*
X314368D03*
X311021Y46914D03*
X354526Y54857D03*
X354525Y46922D03*
X354526Y35957D03*
X351179Y54857D03*
X347833Y46922D03*
X344486D03*
Y35957D03*
Y54857D03*
X337793Y46914D03*
Y35957D03*
X341140Y54857D03*
X311021Y35957D03*
X347833D03*
X341140Y555857D03*
X337793Y547914D03*
X344486Y555857D03*
Y547922D03*
X347833D03*
X351179Y555857D03*
X354525Y547922D03*
X354526Y555857D03*
X311021Y547914D03*
X314368Y555857D03*
X324407D03*
X327754Y547914D03*
X321061Y555857D03*
X311021Y574757D03*
X324407Y566814D03*
X327754Y574757D03*
X341140Y566822D03*
X337793Y574757D03*
X344486D03*
X347833D03*
X351179Y566822D03*
X354526Y574757D03*
X354525Y566822D03*
X314368Y566814D03*
X321061D03*
X344486Y566822D03*
X361218Y28014D03*
X404723Y28022D03*
X364565Y28014D03*
X414762Y28021D03*
X364265Y46914D03*
X361518D03*
X404723Y54857D03*
X414763D03*
X398029Y54842D03*
X414763Y35957D03*
Y46922D03*
X408069Y54842D03*
X394684Y35957D03*
X408069Y555842D03*
X414763Y547922D03*
X398029Y555842D03*
X414763Y555857D03*
X404723D03*
Y566822D03*
X394684Y574757D03*
X414763D03*
Y566822D03*
X444880Y28022D03*
X438189D03*
X431494Y54842D03*
X444880Y54859D03*
Y46922D03*
X424801Y54842D03*
X438187Y54859D03*
X444882Y35957D03*
X438187Y555859D03*
X424801Y555842D03*
X444880Y547922D03*
Y555859D03*
X431494Y555842D03*
X438189Y566822D03*
X444882Y574757D03*
X444880Y566822D03*
X970669Y28014D03*
X963976D03*
X970669Y54857D03*
X960629Y35957D03*
X963976Y54857D03*
X960629Y46914D03*
Y547914D03*
X970669Y555857D03*
Y566814D03*
X963976Y555857D03*
Y566814D03*
X960629Y574757D03*
X974015Y28014D03*
X994094Y28022D03*
X990748D03*
X1004133D03*
X1000787D03*
X977362Y35957D03*
Y46914D03*
X974015Y54857D03*
X997441Y46922D03*
Y35957D03*
X994094Y46922D03*
Y35957D03*
Y54857D03*
X987401Y46914D03*
Y35957D03*
X990748Y54857D03*
X1004134D03*
Y35957D03*
X1004133Y46922D03*
X1000787Y54857D03*
X977362Y547914D03*
X997441Y547922D03*
X994094D03*
X987401Y547914D03*
X977362Y574757D03*
X974015Y555857D03*
Y566814D03*
X994094Y574757D03*
Y555857D03*
Y566822D03*
X990748Y555857D03*
Y566822D03*
X1004133Y547922D03*
X1004134Y555857D03*
X1004133Y566822D03*
X1004134Y574757D03*
X1000787Y555857D03*
Y566822D03*
X997441Y574757D03*
X987401D03*
X1054331Y28022D03*
X1064371D03*
X1094488D03*
X1087797D03*
X1054331Y54857D03*
X1047637Y54842D03*
X1057677D03*
X1044292Y35957D03*
X1094490D03*
X1064371Y54857D03*
X1081102Y54842D03*
X1094488Y54859D03*
Y46922D03*
X1064371Y35957D03*
Y46922D03*
X1074409Y54842D03*
X1087795Y54859D03*
X1054331Y555857D03*
Y566822D03*
X1047637Y555842D03*
X1057677D03*
X1044292Y574757D03*
X1064371Y547922D03*
X1094488D03*
X1064371Y574757D03*
X1074409Y555842D03*
X1087795Y555859D03*
X1064371Y566822D03*
X1094488D03*
X1064371Y555857D03*
X1081102Y555842D03*
X1094488Y555859D03*
X1087797Y566822D03*
X1094490Y574757D03*
X1458102Y270402D03*
X1458052Y273603D03*
X1448603Y279902D03*
X1461202Y273603D03*
X1461300Y270400D03*
X1445454Y279902D03*
X1448603Y276753D03*
X1442304Y273603D03*
X1458052Y308247D03*
X1451753Y298798D03*
X1454902Y295649D03*
X1445454Y311397D03*
X1464351Y305098D03*
X1442304Y308247D03*
Y305098D03*
X1445454Y308247D03*
X1454928Y317723D03*
X1458052Y298798D03*
X1451753Y317696D03*
X1458052Y305098D03*
X1458400Y318500D03*
X1445454Y305098D03*
X1448603D03*
Y283053D03*
X1461202Y283052D03*
X1445454Y289351D03*
X1442304Y289350D03*
X1454902Y289351D03*
Y286202D03*
X1464351Y283052D03*
X1470649Y273603D03*
X1489546Y279902D03*
X1486397Y270454D03*
X1483247Y267304D03*
X1476948Y276753D03*
X1473798Y273603D03*
X1470649Y314546D03*
X1473798Y305098D03*
X1480098Y298798D03*
X1486397Y305098D03*
X1473798Y308247D03*
X1489546Y317696D03*
X1486396D03*
X1495699Y314546D03*
X1492700Y311376D03*
X1473798Y311397D03*
X1483247Y289351D03*
X1480098Y286202D03*
X1476948Y289351D03*
X1604000Y93925D03*
X1590569Y152464D03*
X1648387Y115491D03*
X1651536D03*
X1645237D03*
X1641770Y112340D03*
X1645237Y112341D03*
X1651536D03*
Y128089D03*
X1648387Y109191D03*
X1651536D03*
X1613741Y118640D03*
X1598190Y110711D03*
X1607441Y121790D03*
X1623200Y153100D03*
X1607441Y106042D03*
Y143837D03*
X1608000Y99400D03*
X1613690Y124990D03*
X1610591Y150137D03*
Y124939D03*
X1607441Y134389D03*
X1635788Y162735D03*
X1595042Y172184D03*
X1648387Y159585D03*
X1651536D03*
Y162735D03*
X1642087Y159585D03*
X1629489D03*
X1613650Y173750D03*
X1609222Y173389D03*
X1620041Y165885D03*
X1620006Y168956D03*
X1608731Y180819D03*
X1597642Y172184D03*
X1610591Y159585D03*
X1654686Y109191D03*
X1657835Y118640D03*
X1664135D03*
X1654685Y162735D03*
X1746189Y134777D03*
G54D12*
G01X38645Y172740D02*
X44291Y178386D01*
G01D02*
X49937Y184032D01*
G01X38645D02*
X44291Y178386D01*
G01X-7615Y172740D02*
X-1969Y178386D01*
G01D02*
X3677Y184032D01*
G01X-7615D02*
X-1969Y178386D01*
G01D02*
X3677Y172740D01*
G01X12582D02*
X18228Y178386D01*
G01D02*
X23874Y184032D01*
G01X12582D02*
X18228Y178386D01*
G01D02*
X23874Y172740D01*
G01X430749Y-124922D02*
G02I-12000J0D01*
G01X425599D02*
G02I-6850J0D01*
G01X434749D02*
X402749D01*
G01X434749Y-140922D02*
Y-220922D01*
G01D02*
X1729349D01*
G01X434749Y-176422D02*
X1729349D01*
G01X418749Y-140922D02*
Y-108922D01*
G01X434749Y-140922D02*
X1729349D01*
G01X661494Y32946D02*
X659840Y34600D01*
X651368D01*
X646540Y39428D01*
X630166D01*
X624424Y45170D01*
Y87876D01*
X615800Y96500D01*
X607664D01*
X603163Y101001D01*
Y103971D01*
G01X822400Y212400D02*
Y199488D01*
X814912Y192000D01*
X791229D01*
X771232Y211997D01*
Y214033D01*
G01X941849Y-140922D02*
Y-220922D01*
G01X1079349Y-140922D02*
Y-220922D01*
G01X1194349Y-140922D02*
Y-220922D01*
G01X1321452Y31803D02*
X1329749Y40100D01*
X1340841D01*
G01X1293700Y121800D02*
Y142450D01*
X1295700Y144450D01*
G01X1296468Y437500D02*
Y367210D01*
X1322306Y341372D01*
Y335794D01*
X1331650Y326450D01*
Y317250D01*
G01X1361849Y-140922D02*
Y-220922D01*
G01X1531849Y-140922D02*
Y-220922D01*
G01X1573121Y120649D02*
X1575460Y122988D01*
X1585462D01*
X1586923Y124449D01*
X1596086D01*
X1596661Y125024D01*
X1600826D01*
X1604060Y121790D01*
X1607441D01*
G01X1630000Y381400D02*
X1623800Y375200D01*
Y370109D01*
X1621533Y367830D01*
X1606192D01*
X1602343Y363981D01*
X1602215D01*
G01X1630000Y381400D02*
X1643181D01*
X1657300Y395519D01*
Y399410D01*
X1659301Y401411D01*
X1660936D01*
X1660972Y401447D01*
G01X1729349Y-140922D02*
Y-220922D01*
G01X1757349Y-124922D02*
G02I-12000J0D01*
G01X1752199D02*
G02I-6850J0D01*
G01X1745349Y-140922D02*
Y-108922D01*
G01X1761349Y-124922D02*
X1729349D01*
G01X1967580Y104721D02*
X1966455D01*
X1961623Y99889D01*
Y79848D01*
X1958033Y76258D01*
X1952661D01*
X1948557Y80362D01*
X1948472D01*
G01X1914037Y243646D02*
X1914074Y243683D01*
X1919282D01*
X1929532Y233433D01*
Y215968D01*
X1932900Y212600D01*
Y207605D01*
X1936205Y204300D01*
X1939300D01*
G01D02*
X1942599D01*
X1945630Y201269D01*
X1957334D01*
G01X1950981Y191218D02*
X1954455D01*
X1958325Y187348D01*
X1971342D01*
X1972598Y186092D01*
Y165236D01*
G01X1935600Y198700D02*
X1937700Y200800D01*
X1940395D01*
X1942726Y198469D01*
X1946702D01*
X1950981Y194190D01*
Y191218D01*
X-19210Y162529D03*
X-15768Y161922D03*
X-18000Y247400D03*
X-15000D03*
X-18000Y262700D03*
X-15000D03*
X-16700Y497400D03*
X-17200Y510800D03*
X-17302Y506798D03*
X-16766Y500106D03*
X25827Y-16958D03*
X602Y30502D03*
X34719Y19455D03*
X-1470Y63910D03*
X1382Y68100D03*
X39109Y154901D03*
X37037Y138425D03*
X-12861Y163165D03*
X7995Y285385D03*
X37550Y425400D03*
X40965Y429434D03*
X12025Y424850D03*
X17025D03*
X2025D03*
X7025D03*
X24447Y439354D03*
Y444354D03*
X10786Y441785D03*
X15786D03*
X-9900Y486400D03*
X-13500D03*
X10932Y523601D03*
X-10947Y544117D03*
X-4100Y554400D03*
X-4300Y558400D03*
X1400Y556500D03*
X-1200D03*
X1439Y546583D03*
Y553783D03*
X1539Y550183D03*
Y586183D03*
X1439Y582583D03*
X-900Y592500D03*
X1600D03*
X-4500Y594000D03*
X1439Y589783D03*
X52744Y-4368D03*
X104500Y-1850D03*
X82300Y-16600D03*
X54307Y-8051D03*
X82046Y90043D03*
X91913Y121318D03*
X77790Y121030D03*
X104424Y110833D03*
X87200Y152374D03*
X75660Y152380D03*
X78950Y152810D03*
X91306Y157194D03*
X97900Y194500D03*
X104820Y198800D03*
X97800Y197600D03*
X104820Y202100D03*
X86952Y181721D03*
X87151Y184872D03*
X99250Y160370D03*
X104820Y195700D03*
X97800Y200800D03*
X98538Y341139D03*
X75626Y310418D03*
X74887Y321780D03*
X53100Y315000D03*
X59452Y338800D03*
X70700Y330349D03*
X98680Y338080D03*
X62900Y339000D03*
X64725Y391645D03*
Y396645D03*
X65384Y403258D03*
X58271Y363669D03*
X49091Y351509D03*
X49017Y346509D03*
X49117Y349009D03*
X49017Y344009D03*
X60400Y355750D03*
X101880Y346300D03*
X102060Y351759D03*
X101750Y360120D03*
X101965Y368296D03*
X102040Y348960D03*
X101828Y371096D03*
X51923Y346164D03*
X55500Y371700D03*
X102160Y354780D03*
X101770Y363150D03*
X54244Y405624D03*
X56383Y408163D03*
X63024Y405636D03*
X61005Y429305D03*
Y424305D03*
X49265Y423995D03*
Y418995D03*
X65450Y475610D03*
X67477Y477940D03*
X47800Y487600D03*
X55500Y521800D03*
X53000Y524300D03*
Y521800D03*
X58000D03*
X55500Y519300D03*
X52992Y516846D03*
X58000Y524300D03*
X57936Y519212D03*
X53900Y505450D03*
X57100D03*
X60300D03*
X55500Y524300D03*
X53000Y519300D03*
X53900Y502250D03*
X60300D03*
X57100D03*
X94998Y481612D03*
X86230Y620250D03*
X89360Y620310D03*
X114000Y3500D03*
X114100Y6120D03*
X132959Y33700D03*
X130313Y27899D03*
X126580Y33700D03*
X123620Y27899D03*
X147045D03*
X141880Y30540D03*
X136806Y30750D03*
X141880Y33149D03*
X136780Y33399D03*
X163391Y33700D03*
X160431Y27899D03*
X153738D03*
X169770Y33700D03*
X167124Y27899D03*
X130313Y54957D03*
X132959Y49914D03*
X123620Y54957D03*
X126666Y49914D03*
X147045Y54957D03*
X141880Y52314D03*
X136780Y52100D03*
X141880Y49714D03*
X136780Y49500D03*
X160431Y54957D03*
X163477Y49914D03*
X157084Y34100D03*
X153738Y54957D03*
X157084Y49914D03*
X150391Y34100D03*
Y49914D03*
X167124Y54957D03*
X169770Y49914D03*
X115508Y216512D03*
X117600Y193805D03*
X141263Y215216D03*
X137763Y217716D03*
X141263D03*
X137763Y215216D03*
X115536Y213508D03*
X169150Y223600D03*
Y227600D03*
X115497Y248376D03*
X115508Y280512D03*
X141263Y234216D03*
X141200Y229600D03*
X141211Y225615D03*
X141300Y221700D03*
X139763Y231700D03*
Y227600D03*
Y223700D03*
X139582Y219800D03*
X125563Y234316D03*
X125663Y230716D03*
X125563Y227116D03*
X141263Y249716D03*
Y247216D03*
X137763D03*
Y249716D03*
X125563Y259116D03*
X125663Y262716D03*
X125563Y266316D03*
X141300Y253700D03*
X139631Y251900D03*
X137763Y279216D03*
X141263Y266216D03*
X139763Y255700D03*
Y259600D03*
X139800Y263700D03*
X141313Y257533D03*
X141263Y279216D03*
X141200Y261600D03*
X115525Y245372D03*
X115536Y277508D03*
X137300Y337200D03*
X115508Y312512D03*
X125663Y294716D03*
X125563Y298316D03*
Y291116D03*
X141263Y311216D03*
X137763D03*
X141263Y281716D03*
X139730Y284200D03*
X139763Y288200D03*
Y292000D03*
Y296000D03*
X141200Y286100D03*
X141261Y290076D03*
X141300Y294000D03*
X141263Y298216D03*
X137763Y281716D03*
X141211Y325515D03*
X141263Y330216D03*
X139763Y327800D03*
X141300Y317500D03*
Y321500D03*
X139582Y315800D03*
X139763Y319400D03*
X125563Y323116D03*
X125663Y326716D03*
X125563Y330316D03*
X141263Y313716D03*
X137763D03*
X139763Y323600D03*
X115536Y309508D03*
Y341508D03*
X115508Y344512D03*
X141289Y349488D03*
X141300Y353300D03*
X141200Y357200D03*
X137763Y345716D03*
X141263D03*
Y343216D03*
X137763D03*
X125563Y362316D03*
Y355116D03*
X125663Y358716D03*
X141263Y362216D03*
X139582Y347800D03*
X139763Y351400D03*
Y355200D03*
Y359500D03*
X141300Y381800D03*
X139763Y384000D03*
X141263Y394216D03*
Y390416D03*
X141261Y385876D03*
X139736Y392300D03*
X125663Y390716D03*
X125563Y387116D03*
Y394316D03*
X137763Y375216D03*
X141263D03*
Y377716D03*
X137763D03*
X139631Y379900D03*
X139900Y388000D03*
X109500Y370000D03*
X148666Y417397D03*
X148300Y414600D03*
X148409Y422239D03*
X122242Y419199D03*
X123441Y421795D03*
X151909Y413267D03*
X167680Y408440D03*
X167640Y404842D03*
X119892Y510100D03*
Y536983D03*
Y547900D03*
Y574700D03*
Y585700D03*
X136780Y550500D03*
X141880Y553314D03*
X136780Y553100D03*
X141880Y550714D03*
X169770Y550914D03*
X167124Y555957D03*
X150391Y550914D03*
X147045Y555957D03*
X126666Y550914D03*
X123620Y555957D03*
X157084Y550914D03*
X153738Y555957D03*
X132959Y550914D03*
X163477D03*
X160431Y555957D03*
X130313D03*
X136780Y572199D03*
X136806Y569550D03*
X141880Y571949D03*
X167124Y566699D03*
X169770Y572500D03*
X147045Y566699D03*
X150391Y572900D03*
X123620Y566699D03*
X126580Y572500D03*
X153738Y566699D03*
X157084Y572900D03*
X130313Y566699D03*
X160431D03*
X163391Y572500D03*
X132959D03*
X141880Y569340D03*
X119892Y612583D03*
X190549Y27899D03*
X183856D03*
X206581Y33700D03*
X203935Y27899D03*
X200202Y33700D03*
X197242Y27899D03*
X173617Y30750D03*
X210428D03*
X178691Y30540D03*
X173591Y33399D03*
X210402D03*
X178691Y33149D03*
X227360Y27899D03*
X220667D03*
X215502Y30540D03*
Y33149D03*
X190549Y54957D03*
X193895Y34100D03*
Y49914D03*
X183856Y54957D03*
X187202Y34100D03*
Y49914D03*
X203935Y54957D03*
X206581Y49914D03*
X197242Y54957D03*
X200288Y49914D03*
X173591Y52100D03*
X210402D03*
X178691Y52314D03*
X173591Y49500D03*
X210402D03*
X178691Y49714D03*
X227360Y54957D03*
X230706Y34100D03*
Y49914D03*
X220667Y54957D03*
X224013Y34100D03*
Y49914D03*
X215502Y52314D03*
Y49714D03*
X206800Y246500D03*
X203947Y280933D03*
X195233Y348402D03*
X173591Y553100D03*
X173617Y569550D03*
X173591Y550500D03*
X215502Y550714D03*
X178691D03*
X210402Y553100D03*
X224013Y550914D03*
X220667Y555961D03*
X200288Y550914D03*
X197242Y555957D03*
X230706Y550914D03*
X227360Y555957D03*
X206581Y550914D03*
X203935Y555957D03*
X187202Y550914D03*
X183856Y555957D03*
X193895Y550914D03*
X190549Y555957D03*
X215502Y553314D03*
X178691D03*
X210402Y550500D03*
X220667Y566699D03*
X224013Y572900D03*
X197242Y566699D03*
X200202Y572500D03*
X227360Y566699D03*
X230706Y572900D03*
X203935Y566699D03*
X206581Y572500D03*
X183856Y566699D03*
X187202Y572900D03*
X190549Y566699D03*
X193895Y572900D03*
X215502Y569340D03*
X178691D03*
X210402Y572199D03*
X173591D03*
X210428Y569550D03*
X215502Y571949D03*
X178691D03*
X243392Y33700D03*
X240746Y27899D03*
X264171D03*
X237013Y33700D03*
X234053Y27899D03*
X257478D03*
X247239Y30750D03*
X252313Y33149D03*
X247213Y33399D03*
X252313Y30540D03*
X270864Y17157D03*
X284024Y14300D03*
X289124Y14514D03*
X284024Y11700D03*
X289124Y11914D03*
X277557Y17157D03*
X280203Y12114D03*
X273910D03*
X240746Y54957D03*
X243392Y49914D03*
X264171Y54957D03*
X267517Y34100D03*
Y49914D03*
X234053Y54957D03*
X237099Y49914D03*
X257478Y54957D03*
X260824Y34100D03*
Y49914D03*
X247213Y52100D03*
X252313Y49714D03*
X247213Y49500D03*
X252313Y52314D03*
X240746Y112327D03*
X243392Y106934D03*
X264171Y112327D03*
X267517Y107284D03*
X234053Y112327D03*
X237099Y107284D03*
X257478Y112327D03*
X260824Y107284D03*
X247213Y110514D03*
X252313Y107655D03*
X247239Y107865D03*
X252339Y110264D03*
X281379Y209109D03*
X288139Y201309D03*
Y209109D03*
X284759Y203260D03*
Y211060D03*
X281379Y205210D03*
X291519Y203260D03*
Y211060D03*
X288139Y213009D03*
Y205210D03*
X281379Y236409D03*
X284759Y250060D03*
X288139Y240309D03*
X281379Y244209D03*
X277999Y257860D03*
X288139Y267609D03*
Y259809D03*
X277999Y265660D03*
X271239Y277360D03*
X267392Y276000D03*
X267359Y279310D03*
X277999Y238360D03*
X288139Y248109D03*
X277999Y242260D03*
X284759Y238360D03*
X281379Y248109D03*
X288139Y244209D03*
X277999Y246160D03*
X284759Y242260D03*
X281379Y267609D03*
Y255909D03*
X284759Y269560D03*
X277999Y261760D03*
X284759Y257860D03*
Y261760D03*
X281379Y263709D03*
X288139Y279310D03*
X274619D03*
X281379D03*
X288139Y263709D03*
X239778Y274478D03*
X284759Y335860D03*
X277999D03*
X288139Y330009D03*
X281379Y341709D03*
Y330009D03*
X270892Y304660D03*
Y300760D03*
Y292959D03*
Y289060D03*
X271239Y281260D03*
X270892Y285500D03*
Y296860D03*
X267359Y283209D03*
X281379Y302709D03*
X288139D03*
X291519Y304660D03*
X281379Y306609D03*
Y310509D03*
X288139Y306609D03*
Y310509D03*
X284759Y304660D03*
X281379Y287109D03*
X288139Y291009D03*
X284759Y289060D03*
Y281260D03*
X291519Y289060D03*
Y281260D03*
Y296860D03*
X288139Y298809D03*
X274619Y306609D03*
X277999Y304660D03*
X274619Y302709D03*
Y298809D03*
Y294909D03*
X277999Y289060D03*
Y281260D03*
X274619Y283209D03*
Y287109D03*
Y291009D03*
X277999Y296860D03*
X288139Y283209D03*
Y287109D03*
X281379Y298809D03*
Y294909D03*
X288139D03*
X284759Y296860D03*
X281379Y291009D03*
Y283209D03*
X291519Y312460D03*
X288139Y337809D03*
X281379Y333909D03*
X277999Y331960D03*
X284759Y339760D03*
Y328060D03*
X277999Y339760D03*
X288139Y333909D03*
X284759Y355360D03*
X288139Y388509D03*
X291519Y394359D03*
X281379Y388509D03*
X284759Y394359D03*
X277999Y355360D03*
X284759Y347560D03*
X281379Y361209D03*
X288139Y392410D03*
X281379Y353409D03*
X288139Y384609D03*
Y357309D03*
Y396309D03*
X277999Y351460D03*
X281379Y349509D03*
X288139Y353409D03*
X291519Y386560D03*
X281379Y392410D03*
X284759Y386560D03*
X277999Y359260D03*
X288139Y349509D03*
X284759Y359260D03*
X247228Y495909D03*
X252313Y493214D03*
X260824Y493744D03*
X257478Y498487D03*
X236892Y490800D03*
X233292Y498500D03*
X267584Y493919D03*
X264171Y498487D03*
X243392Y495694D03*
X239592Y495900D03*
X252313Y495814D03*
X247228Y493209D03*
X284024Y588300D03*
X247213Y553100D03*
X247239Y569550D03*
X252313Y550714D03*
X260824Y550914D03*
X257478Y555957D03*
X237099Y550914D03*
X234053Y555957D03*
X267517Y550914D03*
X264171Y555957D03*
X243392Y550914D03*
X240746Y555957D03*
X252313Y553314D03*
X247213Y550500D03*
X264171Y566699D03*
X267517Y572900D03*
X240746Y566699D03*
X243392Y572500D03*
X280203Y588714D03*
X289124Y588514D03*
X252313Y571949D03*
X257478Y566699D03*
X260824Y572900D03*
X234053Y566699D03*
X237013Y572500D03*
X273910Y588714D03*
X252313Y569340D03*
X247213Y572199D03*
X277557Y593757D03*
X289124Y591114D03*
X284024Y590900D03*
X270864Y593757D03*
X300982Y17157D03*
X304328Y12114D03*
X294289Y17157D03*
X297635Y12114D03*
X307675Y92657D03*
X294899Y205210D03*
X345598Y218860D03*
X338838Y214960D03*
X294899Y209109D03*
X348978Y216909D03*
X342218Y213009D03*
X355737Y216909D03*
X315178Y271509D03*
X311798Y265660D03*
X321938Y271509D03*
X308418D03*
X318558Y265660D03*
X342218Y224709D03*
X345598Y230559D03*
X355737Y224709D03*
X352357Y230559D03*
X338838Y230560D03*
X315178Y263709D03*
Y275409D03*
Y267609D03*
X311798Y273460D03*
X321938Y267609D03*
X308418D03*
X318558Y273460D03*
X301659Y279310D03*
X308418D03*
X294899D03*
X338838Y222760D03*
X348978Y228610D03*
X342218Y244209D03*
Y232509D03*
X355737Y244209D03*
X348978D03*
Y232509D03*
X355737D03*
X348978Y267609D03*
X345598Y277360D03*
X348978Y279310D03*
Y275409D03*
Y271509D03*
X352357Y265660D03*
X298279Y320260D03*
X355737Y341709D03*
X321938Y326110D03*
X311798Y331960D03*
X325318D03*
X315178Y326110D03*
X318558Y331960D03*
X298279Y324160D03*
X308418Y306609D03*
X301659Y310509D03*
Y306609D03*
X311798Y304660D03*
X305039D03*
X321938Y306609D03*
X325318Y304660D03*
Y308560D03*
X298279Y304660D03*
X294899Y302709D03*
X308418D03*
X301659D03*
X315178D03*
X321938D03*
X294899Y310509D03*
Y306609D03*
X318558Y304660D03*
Y308560D03*
X321938Y291009D03*
X318558Y296860D03*
X315178Y294909D03*
X321938D03*
X301659D03*
X325318Y285160D03*
Y289060D03*
Y296860D03*
X298279D03*
Y289060D03*
Y281260D03*
X308418Y298809D03*
X301659D03*
X308418Y283209D03*
X305039Y281260D03*
Y289060D03*
X308418Y291009D03*
Y287109D03*
X311798Y281260D03*
Y289060D03*
X308418Y294909D03*
X311798Y296860D03*
X305039D03*
X315178Y287109D03*
X318558Y285160D03*
X321938Y287109D03*
X301659Y283209D03*
Y287109D03*
Y291009D03*
X294899Y298809D03*
Y294909D03*
Y291009D03*
Y283209D03*
Y287109D03*
X315178Y298809D03*
X321938D03*
X318558Y289060D03*
X315178Y291009D03*
X332078Y308560D03*
Y304660D03*
X328698Y302709D03*
Y306609D03*
Y287109D03*
Y291009D03*
Y294909D03*
Y298809D03*
X332078Y296860D03*
Y285160D03*
Y289060D03*
X315178Y306609D03*
X308418Y310509D03*
X318558Y324160D03*
X311798Y312460D03*
X305039D03*
X298279D03*
X294899Y314409D03*
X308418D03*
X301659D03*
X335458Y298809D03*
X348978Y287109D03*
X345598Y285160D03*
Y281260D03*
X348978Y283209D03*
Y298809D03*
Y291009D03*
X345598Y289060D03*
Y292959D03*
Y296860D03*
X348978Y294909D03*
X345598Y300760D03*
X348978Y302709D03*
Y306609D03*
X345598Y304660D03*
Y308560D03*
X348978Y310509D03*
X342218Y302709D03*
Y306609D03*
Y291009D03*
Y287109D03*
Y294909D03*
Y298809D03*
X338838Y308560D03*
X335458Y302709D03*
X338838Y304660D03*
X335458Y306609D03*
Y287109D03*
X338838Y289060D03*
Y285160D03*
X335458Y291009D03*
X338838Y296860D03*
X335458Y294909D03*
X348978Y314409D03*
X345598Y312460D03*
X348978Y322209D03*
X355737Y333909D03*
X345598Y316360D03*
X348978Y318309D03*
Y330009D03*
X352357Y331960D03*
X348978Y326110D03*
X321938Y333909D03*
X311798Y328060D03*
X325318D03*
X315178Y333909D03*
X318558Y335860D03*
Y328060D03*
X348978Y369010D03*
X355737Y380709D03*
X294899Y388509D03*
X338838Y374860D03*
X348978Y380709D03*
X352357Y367060D03*
X355737Y372909D03*
X294899Y392410D03*
X338838Y378760D03*
Y370959D03*
X342218Y372909D03*
X345598Y367060D03*
Y378760D03*
X297635Y588714D03*
X304328D03*
X294289Y593757D03*
X300982D03*
X371258Y-1858D03*
Y-9800D03*
X376700Y-1300D03*
X373670Y17580D03*
X374773Y19819D03*
X398029Y28007D03*
X408069D03*
X364565Y54842D03*
X361218D03*
Y35942D03*
X394682Y49592D03*
X364565Y35942D03*
X365877Y218860D03*
X372637D03*
X386157Y211060D03*
X379397Y207159D03*
X359117Y211060D03*
Y218860D03*
X386157D03*
X399676D03*
X407706Y216909D03*
X376017D03*
X362497D03*
X382777Y213009D03*
X362497D03*
X389537Y216909D03*
X376017Y213009D03*
X415634Y216196D03*
X376017Y224709D03*
X369257D03*
X362497D03*
X389537D03*
X382777D03*
X396296D03*
X415634Y231797D03*
X372637Y222760D03*
X365877D03*
X386157D03*
X379397D03*
X359117D03*
X389537Y232509D03*
X369257Y244209D03*
X362497D03*
X369257Y232509D03*
X362497D03*
X382777D03*
X376017D03*
X357057Y277360D03*
X357092Y270700D03*
X359648Y269777D03*
X357057Y273460D03*
X390894Y264899D03*
X392916Y222760D03*
X407706Y240309D03*
Y232509D03*
X396296Y228610D03*
X399676Y222760D03*
X415634Y220096D03*
Y227896D03*
X396296Y232509D03*
X397394Y264899D03*
X400394D03*
X393894D03*
X357057Y281260D03*
Y296860D03*
Y285160D03*
Y292959D03*
Y300760D03*
Y308560D03*
Y304660D03*
Y289060D03*
Y312460D03*
X364747Y331509D03*
X361367Y329560D03*
X357987Y327609D03*
X371507Y335409D03*
X362497Y337809D03*
X369257Y341709D03*
X368127Y333460D03*
X365877Y339760D03*
X374887Y337360D03*
X381647Y341260D03*
X378267Y339309D03*
X359117Y335860D03*
X357057Y320260D03*
Y324160D03*
Y316360D03*
X389537Y380709D03*
X392916Y374860D03*
X359117D03*
Y386560D03*
X379397Y374860D03*
Y386560D03*
X399676Y374860D03*
X403056Y380709D03*
X386157Y386560D03*
X396296Y369010D03*
X386157Y374860D03*
X376017Y380709D03*
X365877Y374860D03*
X372637D03*
X362497Y380709D03*
X359117Y347560D03*
X372637Y343660D03*
X403056Y353409D03*
X411431Y359351D03*
X411086Y355360D03*
X376017Y384609D03*
X396296Y372909D03*
X386157Y378760D03*
X359117D03*
X362497Y384609D03*
X382777Y372909D03*
X389537D03*
X399676Y378760D03*
X382777Y384609D03*
X365877Y378760D03*
X372637D03*
X362497Y372909D03*
X369257D03*
X376017D03*
X370596Y585614D03*
X394682Y550592D03*
X361518Y547914D03*
X361320Y555842D03*
X364265Y547914D03*
X364565Y555842D03*
X361218Y566814D03*
X408069Y566807D03*
X398029D03*
X361218Y574742D03*
X364565D03*
Y566814D03*
X378600Y606200D03*
X371134Y612453D03*
X370659Y593691D03*
X371312Y604709D03*
X451573Y27899D03*
X424801Y28007D03*
X460912Y33700D03*
X458266Y27899D03*
X454533Y33700D03*
X474998Y27899D03*
X464758Y30750D03*
X469832Y33149D03*
X464732Y33399D03*
X469832Y30540D03*
X431494Y28007D03*
X451573Y54957D03*
X458266D03*
X460912Y49914D03*
X454619Y49564D03*
X474998Y54957D03*
X478344Y34100D03*
Y49914D03*
X464732Y52100D03*
X469832Y49714D03*
X464732Y49500D03*
X469832Y52314D03*
X419214Y218147D03*
X425974Y222047D03*
X419214Y225947D03*
X442873Y235696D03*
X449633Y231797D03*
Y239596D03*
X466533Y241547D03*
X463153Y235696D03*
X473292Y241547D03*
X469913Y235696D03*
X456393D03*
X469913Y266896D03*
X425974Y225947D03*
X422594Y220096D03*
Y227896D03*
X419214Y222047D03*
Y229847D03*
X446253Y233746D03*
Y241547D03*
X442873Y239596D03*
X453013Y233746D03*
Y241547D03*
X449633Y243496D03*
Y235696D03*
X436113Y247396D03*
X446253Y249347D03*
X442873Y251296D03*
X439493Y249347D03*
X442873Y247396D03*
X439493Y245447D03*
X418084Y253546D03*
X421464Y255497D03*
X431604Y257446D03*
X446253Y253247D03*
X447148Y278841D03*
X449848D03*
X450800Y275600D03*
X466533Y233746D03*
X476672Y239596D03*
X463153D03*
X473292Y233746D03*
X469913Y231797D03*
Y243496D03*
Y239596D03*
X456393D03*
X466533Y261047D03*
X463153Y262996D03*
X453400Y275600D03*
X469913Y278596D03*
X466533Y268847D03*
X469913Y262996D03*
X459773Y264947D03*
X442020Y339220D03*
X438240Y339380D03*
X449500Y309800D03*
X451648Y308341D03*
X447000Y309800D03*
X454148Y310341D03*
Y307841D03*
X469913Y298096D03*
Y301996D03*
X453400Y293686D03*
X469913Y282496D03*
Y294196D03*
Y290296D03*
X474413Y329296D03*
X468783Y332897D03*
X474413Y333196D03*
Y325396D03*
X477792Y323446D03*
X460893Y368296D03*
X450753Y374146D03*
X464273D03*
X454133Y368296D03*
X477792Y374146D03*
X427094Y387796D03*
X471033Y374146D03*
X474413Y368296D03*
X430474Y381947D03*
X423714Y378047D03*
X433854Y387796D03*
X423714Y393647D03*
X457513Y374146D03*
X474413Y344896D03*
X448503Y344597D03*
X421464Y348497D03*
X438363Y346546D03*
X424844D03*
X434983Y348497D03*
X428224D03*
X431604Y346546D03*
X423714Y381947D03*
X477792Y346847D03*
Y350747D03*
X471033Y346847D03*
X460893Y376096D03*
X450753Y370247D03*
X464273D03*
X454133Y376096D03*
X477792Y366347D03*
X427094Y379996D03*
X477792Y378047D03*
X427094Y391696D03*
X477792Y370247D03*
X427094Y383896D03*
X471033Y370247D03*
X474413Y376096D03*
X430474Y389747D03*
X433854Y383896D03*
X423714Y389747D03*
X457513Y366347D03*
Y378047D03*
Y370247D03*
X451573Y566699D03*
X454619Y550914D03*
X469832Y553314D03*
X464732Y550500D03*
X469832Y550714D03*
X464732Y553100D03*
X478344Y550914D03*
X474998Y555957D03*
X451573D03*
X460912Y550914D03*
X458266Y555957D03*
X469832Y569340D03*
Y571949D03*
X464758Y569550D03*
X474998Y566699D03*
X478344Y572900D03*
X454533Y572500D03*
X458266Y566699D03*
X460912Y572500D03*
X431494Y566807D03*
X424801D03*
X464732Y572199D03*
X453250Y623320D03*
X456910D03*
X481691Y27899D03*
X495077Y17157D03*
X497723Y12114D03*
X488384Y17157D03*
X491430Y12114D03*
X511809Y17157D03*
X501544Y14300D03*
X506644Y14514D03*
X501544Y11700D03*
X506644Y11914D03*
X534534Y33700D03*
X531888Y27899D03*
X528155Y33700D03*
X525195Y27899D03*
X538381Y30750D03*
X538355Y33399D03*
X518502Y17157D03*
X521848Y12114D03*
X515155D03*
X485037Y34100D03*
X481691Y54957D03*
X485037Y49914D03*
X531888Y54957D03*
X534534Y49914D03*
X525195Y54957D03*
X528241Y49914D03*
X538355Y52100D03*
Y49500D03*
X531888Y112357D03*
X534534Y106964D03*
X525134Y112357D03*
X528241Y107314D03*
X538355Y110514D03*
X538381Y107865D03*
X521731Y216196D03*
X531871Y218147D03*
X494692Y266896D03*
X528491Y259096D03*
X501452Y262996D03*
X498072Y261047D03*
X494692Y259096D03*
X484552Y276646D03*
X498072Y245447D03*
X494692Y223996D03*
X504832Y225947D03*
X511592Y222047D03*
X504832Y261047D03*
X514972Y220096D03*
X518352Y233746D03*
Y222047D03*
X531871Y241547D03*
X528491Y223996D03*
X531871Y237647D03*
X535251Y223996D03*
X484552Y272747D03*
X518352Y261047D03*
X525111Y257147D03*
Y261047D03*
X518352Y311747D03*
X528491Y305896D03*
X484552Y311747D03*
X481172Y286396D03*
X504832Y300045D03*
Y303947D03*
Y311747D03*
X508212Y301996D03*
Y305896D03*
X514972D03*
Y309797D03*
X528491Y301996D03*
Y309797D03*
X525111Y311747D03*
Y307847D03*
Y303947D03*
X521731Y305896D03*
Y309797D03*
X518352Y307847D03*
X514972Y313696D03*
X528491D03*
X521731D03*
X484552Y315647D03*
X481172Y282496D03*
X518352Y303947D03*
X484552Y284447D03*
X481172Y364396D03*
Y348796D03*
Y376096D03*
Y368296D03*
X538370Y495909D03*
Y493209D03*
X528191Y493544D03*
X524595Y498387D03*
X534534Y493394D03*
X530792Y498387D03*
X538355Y553100D03*
Y550500D03*
X528241Y550914D03*
X525195Y555957D03*
X534534Y550914D03*
X531888Y555957D03*
X485037Y550914D03*
X481691Y555957D03*
X497723Y588714D03*
X481691Y566699D03*
X485037Y572900D03*
X501544Y588300D03*
X506644Y588514D03*
X515155Y588714D03*
X491430D03*
X521848D03*
X495077Y593757D03*
X506644Y591114D03*
X501544Y590900D03*
X511809Y593757D03*
X488384D03*
X518502D03*
X555313Y27899D03*
X548620D03*
X571345Y33700D03*
X568699Y27899D03*
X564966Y33700D03*
X562006Y27899D03*
X543455Y33149D03*
Y30540D03*
X592124Y27899D03*
X585431D03*
X575192Y30750D03*
X575166Y33399D03*
X580266Y33149D03*
Y30540D03*
X558659Y34100D03*
X555313Y54957D03*
X558659Y49914D03*
X551966Y34100D03*
X548620Y54957D03*
X551966Y49914D03*
X568699Y54957D03*
X571345Y49914D03*
X562006Y54957D03*
X565052Y49914D03*
X543455Y49714D03*
Y52314D03*
X592124Y54957D03*
X595470Y34100D03*
Y49914D03*
X585431Y54957D03*
X588777Y34100D03*
Y49914D03*
X575166Y52100D03*
X580266Y52314D03*
X575166Y49500D03*
X580266Y49714D03*
X555313Y112357D03*
X558659Y107314D03*
X548620Y112357D03*
X551966Y107314D03*
X543455Y107655D03*
X543481Y110264D03*
X558911Y218147D03*
X542011Y208396D03*
X552151Y237647D03*
X570400Y243500D03*
X555531Y231797D03*
X548771Y227896D03*
X542011Y223996D03*
X545391Y237647D03*
X592216Y445152D03*
X595070Y447970D03*
X543455Y496209D03*
Y493509D03*
X551366Y493344D03*
X548492Y498400D03*
X558659Y496144D03*
X554792Y498487D03*
X580266Y553314D03*
X543455D03*
X575166Y550500D03*
X580266Y550714D03*
X543455D03*
X575166Y553100D03*
X588777Y550914D03*
X585431Y555957D03*
X565266Y550574D03*
X562006Y555957D03*
X595470Y550914D03*
X592124Y555957D03*
X571345Y550914D03*
X568699Y555957D03*
X551966Y550914D03*
X548620Y555957D03*
X558659Y550914D03*
X555313Y555957D03*
X580266Y569340D03*
X575166Y572199D03*
X580266Y571949D03*
X585431Y566699D03*
X588777Y572900D03*
X562006Y566699D03*
X564966Y572500D03*
X592124Y566699D03*
X595470Y572900D03*
X568699Y566699D03*
X571345Y572500D03*
X575192Y569550D03*
X623000Y-3000D03*
X624770Y-640D03*
X656807Y-20652D03*
X648550Y8550D03*
X651100Y8650D03*
X661494Y32946D03*
X651100Y11700D03*
X648500Y11600D03*
X647600Y84200D03*
X603163Y103971D03*
X609482Y124568D03*
X626040Y98281D03*
X613602Y118047D03*
Y109247D03*
X644750Y175650D03*
X617235Y247735D03*
X614456Y244956D03*
X647469Y277639D03*
X642800Y264000D03*
X658500Y284500D03*
X636100Y329800D03*
X637143Y322000D03*
X637561Y312000D03*
X637600Y307000D03*
X631250Y289650D03*
X628525Y287832D03*
X636799Y285670D03*
X636985Y288264D03*
X634407Y287915D03*
X641665Y281139D03*
X637561Y317000D03*
X637600Y302000D03*
X637681Y332390D03*
Y337390D03*
X637143Y327000D03*
X664194Y351206D03*
X654194D03*
X659694D03*
X649194D03*
X608800Y463475D03*
X618430Y491550D03*
X623400Y476300D03*
X619260Y466610D03*
X629300Y490000D03*
X623600Y521700D03*
X648500Y477400D03*
X608800Y468475D03*
Y473475D03*
X652140Y577011D03*
Y574511D03*
X660217Y576734D03*
X649700Y574400D03*
X647350Y568623D03*
X649700Y577000D03*
X670400Y26100D03*
X712796Y-16011D03*
X701100Y8100D03*
X704450Y4950D03*
X705250Y8600D03*
X711791Y23716D03*
X670227Y34277D03*
X690100Y93200D03*
X693000Y92500D03*
X697200Y79500D03*
X670600Y144900D03*
Y150000D03*
X670503Y115884D03*
X709182Y203948D03*
X709200Y201300D03*
X711800Y203100D03*
X706600Y201300D03*
X706500Y207800D03*
X706561Y211417D03*
Y204217D03*
X690130Y277380D03*
X720450Y249950D03*
X710900Y231660D03*
X700000Y233700D03*
X704500Y252500D03*
X723400Y250000D03*
X713970Y308360D03*
X687300Y325200D03*
X670800Y298400D03*
X690048Y284053D03*
Y281053D03*
X668000Y298400D03*
X695700Y357300D03*
X695644Y354644D03*
X695700Y346300D03*
X679523Y385808D03*
X676900Y381800D03*
X679385Y388705D03*
X687427Y384926D03*
X693604Y494303D03*
X669300Y504000D03*
X691000Y498200D03*
X688202Y497736D03*
X712100Y512700D03*
X711339Y499478D03*
X707850Y505700D03*
X693200Y575900D03*
X713500Y618000D03*
X711500Y616274D03*
X755000Y17255D03*
X754600Y300D03*
X751900Y400D03*
X782567Y33700D03*
X779921Y27899D03*
X776188Y33700D03*
X773228Y27899D03*
X786414Y30750D03*
X786388Y33399D03*
X756714Y23130D03*
X753675Y23239D03*
X779921Y54957D03*
X782567Y49914D03*
X773228Y54957D03*
X776274Y49914D03*
X786388Y52100D03*
Y49500D03*
X771232Y214033D03*
X787371Y215216D03*
Y217716D03*
X737837Y222364D03*
Y224964D03*
X740300Y228100D03*
X731662Y247716D03*
X742937Y221174D03*
Y223774D03*
X740437Y224964D03*
Y222364D03*
X726328Y249979D03*
X775200Y230500D03*
X775171Y227116D03*
Y234316D03*
X787371Y247216D03*
Y249716D03*
X775271Y262716D03*
X775171Y259116D03*
Y266316D03*
X787371Y279216D03*
X749126Y220843D03*
X742897Y226773D03*
X736000Y303400D03*
X741512Y315538D03*
X775271Y294716D03*
X775171Y291116D03*
Y298316D03*
X787371Y281716D03*
Y311216D03*
X775271Y326716D03*
X775171Y323116D03*
Y330316D03*
X787371Y313716D03*
X737912Y315500D03*
X775171Y362316D03*
X775271Y358716D03*
X775171Y355116D03*
X787371Y343216D03*
Y345716D03*
X787321Y374916D03*
Y377316D03*
X775121Y394316D03*
X775221Y390716D03*
X775121Y387116D03*
X766200Y417005D03*
X762989Y411728D03*
X763069Y414441D03*
X768080Y418780D03*
X766394Y414397D03*
X763706Y514250D03*
X752900Y521121D03*
Y518621D03*
X763544Y522236D03*
X732600Y573950D03*
X782567Y550914D03*
X776274D03*
X786388Y553100D03*
Y550500D03*
X786414Y569550D03*
X786388Y572199D03*
X763450Y585200D03*
X765900Y587300D03*
X779921Y555957D03*
X782567Y572500D03*
X779921Y566699D03*
X773228Y555957D03*
X776188Y572500D03*
X773228Y566699D03*
X755900Y593650D03*
X812999Y33700D03*
X810039Y27899D03*
X803346D03*
X796653D03*
X816732D03*
X791488Y30540D03*
Y33149D03*
X833464Y27899D03*
X846850D03*
X819378Y33700D03*
X823225Y30750D03*
X828299Y30540D03*
X823199Y33399D03*
X828299Y33149D03*
X840157Y27899D03*
X810039Y54957D03*
X813085Y49914D03*
X806692Y34100D03*
X803346Y54957D03*
X806692Y49914D03*
X799999Y34100D03*
X796653Y54957D03*
X799999Y49914D03*
X816732Y54957D03*
X791488Y52314D03*
Y49714D03*
X843503Y34100D03*
X833464Y54957D03*
X836810Y34100D03*
Y49914D03*
X846850Y54957D03*
X819378Y49914D03*
X823199Y52100D03*
X828299Y52314D03*
X823199Y49500D03*
X828299Y49714D03*
X840157Y54957D03*
X843503Y49914D03*
X822400Y212400D03*
X790871Y215216D03*
Y217716D03*
X789500Y231800D03*
X790900Y234000D03*
Y229700D03*
X790846Y225774D03*
X790882Y221723D03*
X790871Y247216D03*
Y249716D03*
X789471Y227742D03*
X789576Y223737D03*
X789554Y219723D03*
X790900Y253900D03*
X789432Y252000D03*
X790871Y266216D03*
X789432Y255800D03*
X790867Y257724D03*
X789432Y259800D03*
X789500Y263900D03*
X790885Y261711D03*
X790871Y279216D03*
Y311216D03*
X789432Y284200D03*
Y288300D03*
Y292400D03*
X789400Y296200D03*
X790871Y298216D03*
X790937Y294270D03*
X790900Y290300D03*
Y286200D03*
X790871Y281716D03*
Y313716D03*
X789432Y319900D03*
Y323900D03*
X790900Y322000D03*
Y326000D03*
X790871Y330216D03*
X789500Y328000D03*
X789478Y315671D03*
X790800Y317700D03*
X805600Y403900D03*
X789432Y348100D03*
Y352100D03*
X789597Y356105D03*
X789500Y360200D03*
X790900Y358200D03*
X790835Y354048D03*
X790867Y350024D03*
X790871Y345716D03*
Y343216D03*
Y362216D03*
X790821Y374916D03*
X790900Y389300D03*
X789500Y391300D03*
X790900Y393400D03*
Y381100D03*
X789582Y383200D03*
X790900Y385300D03*
X789500Y387300D03*
X790821Y377316D03*
X789282Y379200D03*
X805367Y407400D03*
X797780Y423484D03*
X813085Y550914D03*
X806692D03*
X799999D03*
X791488Y550714D03*
Y553314D03*
X816732Y555957D03*
Y566699D03*
X791488Y571949D03*
X810039Y555957D03*
X812999Y572500D03*
X810039Y566699D03*
X803346Y555957D03*
X806692Y572900D03*
X803346Y566699D03*
X796653Y555957D03*
X799999Y572900D03*
X796653Y566699D03*
X843503Y550914D03*
X836810D03*
X819378D03*
X823199Y553100D03*
X828299Y550714D03*
X823199Y550500D03*
X828299Y553314D03*
X840157Y555957D03*
X843503Y572900D03*
X840157Y566699D03*
X833464Y555957D03*
Y566699D03*
X846850Y555957D03*
Y566699D03*
X823225Y569550D03*
X828299Y571949D03*
X823199Y572199D03*
X828299Y569340D03*
X791488D03*
X836810Y572900D03*
X819378Y572500D03*
X856189Y33700D03*
X853543Y27899D03*
X876968D03*
X849810Y33700D03*
X870275Y27899D03*
X860036Y30750D03*
X865110Y30540D03*
X860010Y33399D03*
X865110Y33149D03*
X886621Y33700D03*
X883661Y27899D03*
X907086D03*
X896847Y30750D03*
X901921Y33149D03*
X896821Y33399D03*
X901921Y30540D03*
X893000Y33700D03*
X890354Y27899D03*
X853543Y54957D03*
X856189Y49914D03*
X876968Y54957D03*
X849896Y49914D03*
X873621Y34100D03*
X870275Y54957D03*
X873621Y49914D03*
X860010Y52100D03*
X865110Y52314D03*
X860010Y49500D03*
X865110Y49714D03*
X883661Y54957D03*
X886707Y49914D03*
X910432Y34100D03*
X907086Y54957D03*
X910432Y49914D03*
X896821Y52100D03*
X901921Y49714D03*
X896821Y49500D03*
X901921Y52314D03*
X880314Y34100D03*
Y49914D03*
X890354Y54957D03*
X893000Y49914D03*
X890354Y112327D03*
X893000Y106934D03*
X883661Y112327D03*
X886707Y107284D03*
X907086Y112327D03*
X910432Y107284D03*
X896821Y110514D03*
X901921Y107655D03*
X896847Y107865D03*
X901947Y110264D03*
X882008Y321100D03*
X886500Y490800D03*
X882900Y498500D03*
X896836Y493209D03*
X901921Y493214D03*
X910432Y493744D03*
X901921Y495814D03*
X896836Y495909D03*
X907086Y498487D03*
X893000Y495694D03*
X889200Y495900D03*
X856189Y550914D03*
X849896D03*
X873621D03*
X860010Y553100D03*
X865110Y550714D03*
X860010Y550500D03*
X865110Y553314D03*
X853543Y555957D03*
X856189Y572500D03*
X853543Y566699D03*
X876968Y555957D03*
Y566699D03*
X870275Y555961D03*
X873621Y572900D03*
X870275Y566699D03*
X860036Y569550D03*
X865110Y571949D03*
Y569340D03*
X880314Y550914D03*
Y572900D03*
X886707Y550914D03*
X883661Y566699D03*
Y555957D03*
X901921Y553314D03*
X896821Y550500D03*
X901921Y550714D03*
X896821Y553100D03*
X910432Y550914D03*
X893000D03*
X901921Y571949D03*
X896847Y569550D03*
X907086Y566699D03*
X910432Y572900D03*
X907086Y555957D03*
X890354Y566699D03*
X893000Y572500D03*
X890354Y555957D03*
X849810Y572500D03*
X860010Y572199D03*
X886621Y572500D03*
X901921Y569340D03*
X896821Y572199D03*
X933632Y14300D03*
Y11700D03*
X927165Y17157D03*
X929811Y12114D03*
X920472Y17157D03*
X923518Y12114D03*
X913779Y27899D03*
X938732Y14514D03*
Y11914D03*
X950590Y17157D03*
X953936Y12114D03*
X943897Y17157D03*
X947243Y12114D03*
X913779Y54957D03*
X917125Y34100D03*
Y49914D03*
X957283Y92657D03*
X913779Y112327D03*
X917125Y107284D03*
X930987Y209109D03*
X937747Y201309D03*
Y209109D03*
X934367Y203260D03*
Y211060D03*
X944507Y205210D03*
Y209109D03*
X937747Y213009D03*
Y205210D03*
X930987D03*
X941127Y203260D03*
Y211060D03*
X930987Y248109D03*
X937747Y244209D03*
X927607Y246160D03*
X934367Y242260D03*
X927607Y238360D03*
X934367Y250060D03*
Y238360D03*
X930987Y255909D03*
X934367Y269560D03*
X937747Y267609D03*
X927607Y261760D03*
X937747Y259809D03*
X934367Y261760D03*
X930987Y263709D03*
X964786D03*
Y275409D03*
X961406Y265660D03*
X971546Y271509D03*
X958026D03*
X968166Y265660D03*
Y273460D03*
X937747Y240309D03*
X930987Y244209D03*
Y236409D03*
X937747Y248109D03*
X927607Y242260D03*
X937747Y279310D03*
X917000Y276000D03*
X920847Y277360D03*
X924227Y279310D03*
X930987Y267609D03*
X937747Y263709D03*
X927607Y257860D03*
X934367D03*
X927607Y265660D03*
X916967Y279310D03*
X930987D03*
X944507D03*
X964786Y267609D03*
Y271509D03*
X961406Y273460D03*
X971546Y267609D03*
X958026D03*
Y279310D03*
X951267D03*
X930987Y330009D03*
Y341709D03*
X937747Y330009D03*
X927607Y335860D03*
X934367D03*
X968166Y331960D03*
X964786Y326110D03*
X961406Y331960D03*
X971546Y326110D03*
X937747Y287109D03*
X920500Y300760D03*
X930987Y302709D03*
X924227D03*
X920500Y289060D03*
X934367Y296860D03*
X930987Y294909D03*
X920500Y296860D03*
Y292959D03*
X927607Y296860D03*
X924227Y298809D03*
X930987D03*
X924227Y283209D03*
X927607Y281260D03*
X920500Y285500D03*
X924227Y287109D03*
X920847Y281260D03*
X930987Y287109D03*
X934367Y289060D03*
Y281260D03*
X930987Y283209D03*
X924227Y291009D03*
X930987D03*
X927607Y289060D03*
X937747Y302709D03*
Y283209D03*
Y291009D03*
Y294909D03*
Y298809D03*
Y333909D03*
X927607Y339760D03*
X934367Y328060D03*
Y339760D03*
X927607Y331960D03*
X930987Y333909D03*
X937747Y337809D03*
X971546Y294909D03*
X944507Y283209D03*
X964786Y291009D03*
X954647Y281260D03*
X958026Y283209D03*
X951267Y287109D03*
X958026D03*
X951267Y283209D03*
X961406Y281260D03*
Y296860D03*
X964786Y298809D03*
Y302709D03*
X971546D03*
X958026D03*
X951267D03*
X944507D03*
Y294909D03*
Y287109D03*
X971546Y298809D03*
X968166Y285160D03*
X964786Y287109D03*
X944507Y291009D03*
X941127Y281260D03*
Y289060D03*
Y296860D03*
X944507Y298809D03*
X947887Y289060D03*
Y296860D03*
Y281260D03*
X968166Y296860D03*
X964786Y294909D03*
X971546Y291009D03*
Y287109D03*
X968166Y289060D03*
X961406D03*
X958026Y298809D03*
X951267D03*
Y291009D03*
X958026D03*
X954647Y289060D03*
Y296860D03*
X958026Y294909D03*
X951267D03*
X968166Y335860D03*
Y328060D03*
Y324160D03*
X964786Y333909D03*
X961406Y328060D03*
X971546Y333909D03*
X934367Y347560D03*
X927607Y359260D03*
X934367Y355360D03*
X927607Y351460D03*
X934367Y386560D03*
X930987Y392410D03*
X937747Y396309D03*
X944507Y392410D03*
X941127Y386560D03*
X934367Y359260D03*
X930987Y361209D03*
X937747Y349509D03*
X927607Y355360D03*
X937747Y353409D03*
X930987Y349509D03*
X937747Y357309D03*
X930987Y353409D03*
X934367Y394359D03*
X930987Y388509D03*
X937747D03*
Y384609D03*
Y392410D03*
X944507Y388509D03*
X941127Y394359D03*
X917192Y493919D03*
X913779Y498487D03*
X953936Y588714D03*
X938732Y588514D03*
X933632Y588300D03*
X929811Y588714D03*
X923518D03*
X947243D03*
X917125Y550914D03*
X913779Y555957D03*
Y566699D03*
X917125Y572900D03*
X927165Y593757D03*
X938732Y591114D03*
X950590Y593757D03*
X933632Y590900D03*
X920472Y593757D03*
X943897D03*
X1028639Y-6615D03*
X1014173Y28014D03*
X1010826D03*
X1026700Y1700D03*
X1014173Y54842D03*
Y35942D03*
X1013873Y46914D03*
X1010826Y54842D03*
Y35942D03*
X1011126Y46914D03*
X991826Y213009D03*
X988446Y214960D03*
X1025625Y216909D03*
X1015485Y218860D03*
X1022245D03*
X1032385Y213009D03*
X1029005Y207159D03*
X1012105Y213009D03*
X1008725Y218860D03*
X1005345Y216909D03*
X1025625Y213009D03*
X995206Y218860D03*
X998586Y216909D03*
X1012105D03*
X1008725Y211060D03*
X991826Y224709D03*
X988446Y222760D03*
X998586Y228610D03*
X1025625Y224709D03*
X1022245Y222760D03*
X1018865Y224709D03*
X1012105D03*
X1032385D03*
X1029005Y222760D03*
X1005345Y224709D03*
X1001965Y230559D03*
X988446Y230560D03*
X995206Y230559D03*
X998586Y244209D03*
Y232509D03*
X991826Y244209D03*
Y232509D03*
X995206Y277360D03*
X998586Y267609D03*
Y271509D03*
Y275409D03*
Y279310D03*
X1015485Y222760D03*
X1008725D03*
X1032385Y232509D03*
X1018865Y244209D03*
X1012105D03*
X1018865Y232509D03*
X1012105D03*
X1025625D03*
X1005345Y244209D03*
Y232509D03*
X1022245Y253960D03*
X1017735Y264300D03*
X1014355Y266300D03*
X1021115Y262300D03*
X1024495Y260300D03*
X1027875Y258400D03*
X1005345Y263709D03*
X1001965Y265660D03*
X1009256Y269777D03*
X1008725Y261760D03*
X1006665Y277360D03*
X1006700Y270700D03*
X1006665Y273460D03*
X1011100Y268100D03*
X1015485Y257860D03*
X1018865Y255909D03*
X1012105Y259809D03*
X974926Y331960D03*
X1005345Y341709D03*
X995206Y296860D03*
X985066Y294909D03*
Y287109D03*
X988446Y285160D03*
X991826Y287109D03*
X995206Y281260D03*
X978306Y298809D03*
Y287109D03*
X981686Y285160D03*
X978306Y294909D03*
X981686Y296860D03*
Y289060D03*
X978306Y291009D03*
X998586Y302709D03*
Y306609D03*
Y310509D03*
Y287109D03*
Y294909D03*
Y291009D03*
Y298809D03*
Y283209D03*
X985066Y302709D03*
X978306D03*
X988446Y304660D03*
Y308560D03*
X985066Y306609D03*
X995206Y304660D03*
Y308560D03*
X991826Y306609D03*
X981686Y304660D03*
X995206Y300760D03*
X991826Y302709D03*
X974926Y285160D03*
Y296860D03*
Y289060D03*
X995206Y292959D03*
X988446Y296860D03*
X991826Y294909D03*
X995206Y289060D03*
X988446D03*
X991826Y291009D03*
X985066D03*
X995206Y285160D03*
X985066Y298809D03*
X991826D03*
X974926Y328060D03*
X998586Y314409D03*
X995206Y312460D03*
X998586Y318309D03*
Y322209D03*
X995206Y316360D03*
X1006665Y300760D03*
Y304660D03*
Y308560D03*
Y285160D03*
Y296860D03*
Y289060D03*
Y281260D03*
Y292959D03*
X1008725Y335860D03*
X1005345Y333909D03*
X1001965Y331960D03*
X1007595Y327609D03*
X1021115Y335409D03*
X1018865Y341709D03*
X1017735Y333460D03*
X1015485Y339760D03*
X1024495Y337360D03*
X1012105Y337809D03*
X1006665Y312460D03*
X1014355Y331509D03*
X1010975Y329560D03*
X1027875Y339309D03*
X1031255Y341260D03*
X1006665Y324160D03*
Y316360D03*
Y320260D03*
X995206Y367060D03*
X988446Y370959D03*
X995206Y378760D03*
X988446D03*
X1012105Y345609D03*
X1015485Y347560D03*
X1008725D03*
X1001965Y367060D03*
X1025625Y372909D03*
X1018865D03*
X1012105D03*
X1022245Y378760D03*
X1032385Y384609D03*
Y372909D03*
X1012105Y384609D03*
X1008725Y378760D03*
X1005345Y372909D03*
X1025625Y384609D03*
X1015485Y378760D03*
X998586Y369010D03*
Y380709D03*
X991826Y372909D03*
X988446Y374860D03*
X1022245Y343660D03*
X1008725D03*
X1012105Y380709D03*
X1022245Y374860D03*
X1015485D03*
X1025625Y380709D03*
X1029005Y386560D03*
Y374860D03*
X1008725Y386560D03*
X1005345Y380709D03*
X1008725Y374860D03*
X1013873Y547914D03*
X1014173Y566814D03*
Y555842D03*
Y574742D03*
X1010928Y555842D03*
X1011126Y547914D03*
X1010826Y566814D03*
Y574742D03*
X1047637Y28007D03*
X1057677D03*
X1081102D03*
X1074409D03*
X1044290Y49592D03*
X1049284Y218860D03*
X1057314Y216909D03*
X1035765Y218860D03*
X1065242Y216196D03*
X1035765Y211060D03*
X1039145Y216909D03*
X1068822Y218147D03*
X1035765Y222760D03*
X1039145Y224709D03*
X1042524Y222760D03*
X1045904Y224709D03*
X1075582Y222047D03*
X1065242Y227896D03*
Y231797D03*
X1072202Y220096D03*
Y227896D03*
X1068822Y225947D03*
Y222047D03*
X1095861Y241547D03*
X1092481Y235696D03*
Y239596D03*
X1045904Y228610D03*
X1049284Y222760D03*
X1039145Y232509D03*
X1057314Y240309D03*
X1045904Y232509D03*
X1057314D03*
X1050002Y264899D03*
X1047002D03*
X1043502D03*
X1040502D03*
X1065242Y220096D03*
X1075582Y225947D03*
X1068822Y229847D03*
X1095861Y233746D03*
X1092481Y247396D03*
X1089101Y245447D03*
X1085721Y247396D03*
X1089101Y249347D03*
X1092481Y251296D03*
X1095861Y249347D03*
X1071072Y255728D03*
X1084591Y255497D03*
X1081212Y257600D03*
X1095861Y253247D03*
X1095702Y309904D03*
X1049284Y378760D03*
X1039145Y372909D03*
X1035765Y378760D03*
X1045904Y372909D03*
X1073322Y393647D03*
X1083462Y383896D03*
X1073322Y378047D03*
X1080082Y389747D03*
X1061055Y363160D03*
X1060963Y370959D03*
X1064371Y367060D03*
X1076702Y383896D03*
X1045904Y369010D03*
X1034635Y343209D03*
X1038015Y345160D03*
X1041395Y347109D03*
X1048154D03*
X1044774Y345160D03*
X1051534D03*
X1035765Y374860D03*
Y386560D03*
X1052664Y380709D03*
X1049284Y374860D03*
X1042524D03*
X1039145Y380709D03*
X1071072Y348497D03*
X1087971Y346546D03*
X1074452D03*
X1081212D03*
X1077832Y348497D03*
X1084591D03*
X1073322Y389747D03*
X1083462Y387796D03*
X1073322Y381947D03*
X1080082D03*
X1076702Y391696D03*
Y387796D03*
Y379996D03*
X1044290Y550592D03*
X1047637Y566807D03*
X1057677D03*
X1074409D03*
X1081102D03*
X1110520Y33700D03*
X1107874Y27899D03*
X1104141Y33700D03*
X1101181Y27899D03*
X1114366Y30750D03*
X1119440Y33149D03*
X1114340Y33399D03*
X1119440Y30540D03*
X1124606Y27899D03*
X1144685Y17157D03*
X1147331Y12114D03*
X1137992Y17157D03*
X1141038Y12114D03*
X1151152Y14300D03*
X1156252Y14514D03*
X1151152Y11700D03*
X1156252Y11914D03*
X1131299Y27899D03*
X1107874Y54957D03*
X1110520Y49914D03*
X1101181Y54957D03*
X1104227Y49564D03*
X1114340Y52100D03*
X1119440Y49714D03*
X1114340Y49500D03*
X1119440Y52314D03*
X1127952Y34100D03*
X1124606Y54957D03*
X1127952Y49914D03*
X1131299Y54957D03*
X1134645Y34100D03*
Y49914D03*
X1116141Y241547D03*
X1112761Y235696D03*
X1119521Y243496D03*
Y235696D03*
X1106001D03*
X1102621Y241547D03*
X1099241Y231797D03*
Y243496D03*
Y235696D03*
X1126280D03*
X1122900Y241547D03*
X1133040Y239596D03*
X1144300Y274696D03*
X1116141Y233746D03*
X1112761Y239596D03*
X1119521Y231797D03*
Y239596D03*
X1106001D03*
X1102621Y233746D03*
X1099241Y239596D03*
X1096756Y278941D03*
X1099186Y278938D03*
X1102336Y274819D03*
X1116141Y268847D03*
X1112761Y262996D03*
X1116141Y261047D03*
X1119521Y278596D03*
X1126280Y239596D03*
X1122900Y233746D03*
X1154440Y225947D03*
X1147680Y245447D03*
X1127400Y280547D03*
Y276646D03*
X1134160Y280547D03*
X1122900Y261047D03*
X1119521Y259096D03*
Y282496D03*
Y301996D03*
X1101256Y308841D03*
X1103756Y307841D03*
Y310341D03*
X1098756Y309841D03*
X1119521Y298096D03*
Y294196D03*
Y290296D03*
X1118391Y332897D03*
X1127400Y284447D03*
Y300047D03*
X1130780Y294196D03*
X1127400Y296147D03*
Y292247D03*
X1130780Y298096D03*
Y305896D03*
X1137540Y290296D03*
X1134160Y296147D03*
Y288347D03*
X1124021Y325396D03*
X1127400Y323446D03*
X1124021Y329296D03*
Y333196D03*
X1154440Y327347D03*
X1147680Y339047D03*
X1157820Y321496D03*
X1113881Y370247D03*
X1100361D03*
X1107121Y366347D03*
X1103741Y376096D03*
X1110501D03*
X1124021Y368296D03*
X1130780Y364396D03*
X1134160Y374146D03*
X1120641D03*
X1127400D03*
Y370247D03*
X1103741Y368296D03*
X1110501D03*
X1107121Y370247D03*
X1101491Y342646D03*
X1098111Y344597D03*
X1113881Y374146D03*
X1100361D03*
X1107121Y378047D03*
Y374146D03*
X1120641Y370247D03*
X1130780Y368296D03*
X1127400Y366347D03*
X1157820Y356596D03*
X1144300Y352696D03*
X1154440Y350747D03*
Y362447D03*
X1124021Y376096D03*
X1130780D03*
X1127400Y378047D03*
X1154440Y397546D03*
Y385847D03*
X1157820Y391696D03*
X1154440Y389747D03*
X1157820Y395597D03*
X1151060Y387796D03*
X1154440Y393647D03*
X1119440Y550714D03*
Y553314D03*
X1110520Y550914D03*
X1104227D03*
X1119440Y571949D03*
X1107874Y555957D03*
X1110520Y572500D03*
X1107874Y566699D03*
X1101181Y555957D03*
X1104141Y572500D03*
X1101181Y566699D03*
X1134645Y550914D03*
X1127952D03*
X1147331Y588714D03*
X1141038D03*
X1156252Y588514D03*
X1151152Y588300D03*
X1131299Y555957D03*
X1134645Y572900D03*
X1131299Y566699D03*
X1124606Y555957D03*
X1127952Y572900D03*
X1124606Y566699D03*
X1114340Y553100D03*
Y550500D03*
X1114366Y569550D03*
X1119440Y569340D03*
X1114340Y572199D03*
X1144685Y593757D03*
X1137992D03*
X1151152Y590900D03*
X1156252Y591114D03*
X1177763Y33700D03*
X1174803Y27899D03*
X1168110Y17157D03*
X1171456Y12114D03*
X1161417Y17157D03*
X1164763Y12114D03*
X1204921Y27899D03*
X1198228D03*
X1218307D03*
X1214574Y33700D03*
X1211614Y27899D03*
X1187989Y30750D03*
X1193063Y33149D03*
X1187963Y33399D03*
X1193063Y30540D03*
X1184142Y33700D03*
X1181496Y27899D03*
X1174803Y54957D03*
X1177849Y49914D03*
X1204921Y54957D03*
X1208267Y34100D03*
Y49914D03*
X1198228Y54957D03*
X1201574Y34100D03*
Y49914D03*
X1218307Y54957D03*
X1211614D03*
X1214660Y49914D03*
X1187963Y52100D03*
X1193063Y49714D03*
X1187963Y49500D03*
X1193063Y52314D03*
X1181496Y54957D03*
X1184142Y49914D03*
X1174742Y112357D03*
X1177849Y107314D03*
X1181496Y112357D03*
X1184142Y106964D03*
X1204921Y112357D03*
X1208267Y107314D03*
X1198228Y112357D03*
X1201574Y107314D03*
X1187963Y110514D03*
X1193063Y107655D03*
X1187989Y107865D03*
X1193089Y110264D03*
X1208519Y218147D03*
X1171339Y216196D03*
X1181479Y218147D03*
X1191619Y208397D03*
X1178099Y223996D03*
X1191619D03*
X1161200Y222047D03*
X1159410Y259720D03*
X1178099Y270796D03*
Y278596D03*
X1174719Y268847D03*
X1167960Y264947D03*
X1181479Y249347D03*
Y237647D03*
Y241547D03*
X1184859Y223996D03*
X1201759Y237647D03*
X1198379Y227896D03*
X1205139Y231797D03*
X1201759Y245447D03*
X1194999Y237647D03*
X1198379Y251296D03*
X1181479Y264947D03*
X1184859Y255196D03*
X1191619Y270796D03*
X1198379Y262996D03*
X1194999Y276646D03*
X1198379Y270796D03*
X1191619Y337096D03*
X1184859Y298096D03*
X1191619Y313696D03*
X1188239Y300047D03*
X1191619Y340996D03*
X1188239Y331247D03*
Y327347D03*
X1194999Y311747D03*
X1184859Y305896D03*
X1188239Y296147D03*
X1181479D03*
X1191619Y325396D03*
X1188239Y307847D03*
X1161200Y288347D03*
Y292247D03*
X1174719Y339047D03*
X1164580Y340996D03*
X1167960Y331247D03*
X1171339Y321496D03*
X1198379Y282496D03*
X1184859Y325396D03*
Y333196D03*
X1191619Y309797D03*
X1188239Y303947D03*
X1194999Y327347D03*
X1184859Y317596D03*
X1191619D03*
Y305896D03*
Y301996D03*
X1184859Y340996D03*
X1194999Y339047D03*
X1191619Y333196D03*
Y329296D03*
X1188239Y323446D03*
X1184859Y313696D03*
X1188239Y315647D03*
X1191619Y344896D03*
X1167960Y358547D03*
X1171339Y344896D03*
X1174719Y350747D03*
X1181479Y393647D03*
X1184859Y399496D03*
X1178099Y395596D03*
X1174719Y401447D03*
X1191619Y383896D03*
X1167960Y381947D03*
X1184859Y387796D03*
X1188239Y385847D03*
Y389747D03*
X1184859Y391696D03*
Y395596D03*
X1181479Y397546D03*
X1178099Y399496D03*
X1171339Y403396D03*
X1167960Y401447D03*
Y374146D03*
X1171339Y379996D03*
X1164580Y383896D03*
X1161200Y381947D03*
X1184859Y348796D03*
X1167960Y378047D03*
X1188239Y346847D03*
Y342947D03*
X1167960Y385847D03*
X1161200D03*
Y393647D03*
X1184859Y344896D03*
X1174719Y405347D03*
X1167960D03*
X1177799Y493544D03*
X1184142Y493394D03*
X1200974Y493344D03*
X1193063Y493509D03*
X1208267Y496144D03*
X1187978Y495909D03*
X1193063Y496209D03*
X1204400Y498487D03*
X1198100Y498400D03*
X1187978Y493209D03*
X1180400Y498387D03*
X1174203D03*
X1177849Y550914D03*
X1171456Y588714D03*
X1164763D03*
X1184142Y550914D03*
X1208267D03*
X1201574D03*
X1214874Y550574D03*
X1187963Y553100D03*
X1193063Y550714D03*
Y553314D03*
X1218307Y555957D03*
Y566699D03*
X1211614Y555957D03*
X1214574Y572500D03*
X1211614Y566699D03*
X1204921Y555957D03*
X1198228D03*
X1187963Y550500D03*
X1181496Y555957D03*
X1174803D03*
X1168110Y593757D03*
X1161417D03*
X1241732Y27899D03*
X1278900Y-14800D03*
X1220953Y33700D03*
X1235039Y27899D03*
X1224800Y30750D03*
X1229874Y30540D03*
X1224774Y33399D03*
X1229874Y33149D03*
X1255118Y27899D03*
Y16999D03*
Y9157D03*
X1241732Y54957D03*
X1245078Y34100D03*
Y49914D03*
X1238385Y34100D03*
Y49914D03*
X1220953D03*
X1235039Y54957D03*
X1224774Y52100D03*
X1229874Y52314D03*
X1224774Y49500D03*
X1229874Y49714D03*
X1255118Y65699D03*
Y54799D03*
Y36057D03*
Y46957D03*
Y92599D03*
Y84757D03*
Y73857D03*
X1277100Y122670D03*
X1277600Y106200D03*
X1275470Y99390D03*
X1249025Y130460D03*
X1257850Y116950D03*
Y113850D03*
X1268500Y102100D03*
X1271500D03*
X1251980Y106960D03*
X1250200Y122900D03*
X1244410Y173150D03*
X1246910D03*
X1242800Y175200D03*
X1252800Y176000D03*
X1255200D03*
X1229780Y181980D03*
Y178980D03*
X1232780Y181980D03*
X1226914Y184708D03*
X1232780Y178980D03*
X1226780D03*
Y181980D03*
X1243399Y398339D03*
X1249230Y402022D03*
X1246010Y400110D03*
X1277978Y491571D03*
X1262843Y497553D03*
X1267584Y499694D03*
X1271105Y498516D03*
X1269209Y501777D03*
X1255120Y510158D03*
Y518000D03*
X1248474Y488913D03*
X1249193Y491308D03*
X1277137Y547393D03*
X1279318Y545212D03*
X1245078Y550914D03*
X1238385D03*
X1241732Y555957D03*
X1245078Y572900D03*
X1241732Y566699D03*
X1238385Y572900D03*
X1273200Y582200D03*
X1220953Y550914D03*
X1229874Y550714D03*
X1224774Y550500D03*
X1229874Y553314D03*
X1220953Y572500D03*
X1235039Y555957D03*
Y566699D03*
X1229874Y571949D03*
X1224774Y572199D03*
X1229874Y569340D03*
X1224774Y553100D03*
X1224800Y569550D03*
X1270400Y593600D03*
X1299549Y-18619D03*
X1293600Y-17000D03*
X1293816Y-13533D03*
X1321452Y31803D03*
X1320000Y85500D03*
X1298422Y74000D03*
X1298754Y83233D03*
X1308983Y93814D03*
X1327452Y55544D03*
X1327500Y51547D03*
X1317195Y87098D03*
X1311559Y91431D03*
X1311551Y93952D03*
X1336850Y76450D03*
X1317300Y89600D03*
Y84600D03*
X1293700Y121800D03*
X1295240Y149830D03*
X1295172Y153670D03*
X1291735Y150061D03*
X1291772Y153694D03*
X1293335Y148177D03*
X1293543Y151756D03*
X1295700Y144450D03*
X1308972Y96742D03*
X1325125Y100001D03*
X1301770Y101300D03*
X1301900Y124400D03*
X1330039Y279618D03*
X1314792Y286427D03*
X1314490Y283862D03*
X1335400Y284900D03*
X1334400Y292050D03*
X1337200Y292012D03*
X1323688Y290205D03*
X1338700Y284700D03*
X1305873Y309245D03*
X1305950Y306611D03*
X1331720Y334810D03*
X1326300Y341309D03*
X1331650Y317250D03*
X1319888Y290205D03*
X1341375Y314675D03*
Y319675D03*
X1336336Y333825D03*
X1326014Y347732D03*
X1330100Y350100D03*
X1332600Y349900D03*
X1332613Y346417D03*
X1329757Y346511D03*
X1296468Y437500D03*
X1300438Y433001D03*
X1297878Y493150D03*
X1295240Y493359D03*
X1299450Y484950D03*
X1301240Y476228D03*
X1320300Y498300D03*
X1335100Y507700D03*
X1308500Y540784D03*
X1305500Y542500D03*
X1285400Y561000D03*
X1288100Y562000D03*
X1343100Y566300D03*
X1340700D03*
X1338000D03*
X1340526Y563337D03*
X1343026D03*
X1338026D03*
X1333026D03*
X1335526D03*
Y566237D03*
X1318500Y539900D03*
X1316100Y543400D03*
X1333026Y566237D03*
X1306600Y610000D03*
X1376094Y4406D03*
X1380008Y-3805D03*
X1366789Y5776D03*
X1380678Y-422D03*
X1380950Y30232D03*
X1400616Y13795D03*
X1379200Y27000D03*
X1375412Y92182D03*
X1378464Y91979D03*
X1397550Y68059D03*
X1395050D03*
X1397050Y58559D03*
X1392050D03*
X1394550D03*
X1397050Y55559D03*
X1394550D03*
X1392050D03*
X1397539Y65098D03*
X1394939D03*
X1392339D03*
X1377009Y39753D03*
X1367100Y37800D03*
X1395000Y78800D03*
X1397400D03*
X1392584Y78798D03*
X1395000Y76200D03*
X1392584D03*
X1397400D03*
X1357000Y86640D03*
X1383171Y57549D03*
X1392149Y68006D03*
X1372300Y86400D03*
X1345050Y272350D03*
X1392400Y330800D03*
X1400400Y335400D03*
X1355300Y321675D03*
X1400558Y316357D03*
X1360294Y315025D03*
X1371090Y315395D03*
X1380904Y315947D03*
X1392226Y315658D03*
X1349134Y321145D03*
X1392226Y319458D03*
X1349134Y317436D03*
X1400558Y320157D03*
X1380904Y319747D03*
X1371090Y319195D03*
X1360294Y318825D03*
X1396470Y330014D03*
X1381431Y284259D03*
X1384300Y398900D03*
X1386800D03*
X1384252Y401343D03*
X1386752D03*
X1374344Y371431D03*
X1380200Y370400D03*
X1376979Y370536D03*
X1380200Y373100D03*
X1377103Y373428D03*
X1374300Y402053D03*
X1376800D03*
X1381752Y401343D03*
X1379252D03*
X1381800Y398900D03*
X1374300Y377885D03*
Y381485D03*
X1374268Y374285D03*
X1377028Y458125D03*
X1372028D03*
X1395375Y453561D03*
X1385100Y452500D03*
Y447500D03*
X1344090Y463630D03*
X1346739Y463615D03*
X1402775Y453561D03*
X1395375Y457561D03*
X1401398Y429775D03*
Y434775D03*
X1402775Y457561D03*
X1402950Y510650D03*
X1395242Y520301D03*
X1396035Y514863D03*
X1400980Y587086D03*
X1397980D03*
X1355548Y559959D03*
X1361926Y584037D03*
Y586537D03*
X1359100Y586200D03*
X1357400Y588400D03*
X1360100D03*
X1344613Y556376D03*
Y561376D03*
Y558876D03*
X1347700Y554100D03*
X1344613Y553876D03*
X1358439Y559959D03*
X1382331Y543818D03*
X1382200Y562700D03*
X1364426Y586637D03*
Y584137D03*
X1360500Y570900D03*
Y574700D03*
X1360261Y578873D03*
X1360247Y567390D03*
X1360261Y562373D03*
Y581373D03*
X1362000Y576700D03*
Y572800D03*
X1362100Y569100D03*
X1362000Y565600D03*
X1375961Y569473D03*
X1376000Y565700D03*
X1375961Y562273D03*
X1363761Y581373D03*
X1400980Y589586D03*
X1395060Y590630D03*
X1380890Y615820D03*
X1357726Y591037D03*
X1360226D03*
X1375600Y589700D03*
X1382100Y592800D03*
X1382000Y589500D03*
X1363761Y612573D03*
X1360261D03*
X1360200Y597800D03*
X1361600Y599900D03*
X1361500Y595700D03*
X1360100Y610100D03*
X1360200Y606300D03*
Y602000D03*
X1361900Y608200D03*
X1361500Y604200D03*
X1360261Y593573D03*
X1375961Y600673D03*
X1375861Y597073D03*
X1375961Y593473D03*
X1363761Y610073D03*
X1398010Y590040D03*
X1454991Y5589D03*
X1449991D03*
X1436025Y7756D03*
X1427442Y11563D03*
X1431025Y7756D03*
X1422442Y11563D03*
X1465237D03*
X1460237D03*
X1446340D03*
X1441340D03*
X1451228Y141261D03*
X1451233Y146405D03*
X1451365Y176014D03*
X1450532Y178372D03*
X1444850Y242730D03*
X1412579Y268273D03*
X1426658Y274252D03*
X1435655Y246550D03*
X1434300Y251600D03*
X1437400Y244150D03*
X1464150Y235550D03*
X1410979Y270473D03*
X1451850Y262200D03*
X1461348Y244350D03*
X1454350Y262200D03*
X1447154Y251710D03*
X1454000Y259700D03*
X1452200Y254500D03*
X1448500Y257700D03*
X1408376Y339882D03*
X1408250Y333000D03*
X1408348Y336436D03*
X1410489Y337988D03*
X1443500Y327900D03*
X1416000Y332900D03*
Y338100D03*
Y335500D03*
X1413387Y316233D03*
Y320033D03*
X1463870Y367869D03*
X1463617Y357259D03*
X1413400Y361300D03*
X1461016Y359965D03*
X1446700Y387900D03*
X1464361Y385275D03*
X1445510Y350327D03*
X1415450Y350550D03*
X1465048Y402370D03*
X1439000Y423000D03*
X1461800Y454100D03*
X1464200Y449997D03*
X1466382Y406773D03*
X1405423Y413281D03*
X1407158Y421575D03*
X1454000Y459800D03*
X1405423Y408281D03*
X1407158Y416575D03*
X1414982Y417040D03*
X1409300Y429775D03*
X1410475Y457561D03*
X1415146Y421946D03*
X1409300Y434775D03*
X1464400Y465500D03*
X1456600D03*
X1461800Y459800D03*
X1454000Y454100D03*
X1461600Y449997D03*
X1464400Y454100D03*
X1461800Y465500D03*
X1454000D03*
X1410475Y453561D03*
X1456600Y454100D03*
X1464400Y459800D03*
X1456600D03*
X1405950Y510650D03*
X1460661Y484891D03*
X1461267Y489790D03*
X1456602Y485864D03*
X1456590Y488976D03*
X1449568Y487276D03*
X1458060Y495020D03*
X1441252Y548631D03*
X1433100Y581770D03*
X1430570Y580890D03*
X1432590Y584550D03*
X1427500Y581100D03*
X1465700Y570500D03*
X1415173Y586332D03*
X1412673D03*
X1422920Y586250D03*
X1417920D03*
X1420420D03*
X1445145Y605727D03*
X1442525Y597279D03*
X1443654Y594749D03*
X1456277Y603454D03*
X1453628Y603368D03*
X1450720Y606067D03*
X1448071Y605981D03*
X1443473Y599944D03*
X1453451Y606114D03*
X1456100Y606200D03*
X1460200D03*
X1410950Y589670D03*
X1477100Y2400D03*
X1524800Y3500D03*
X1509400D03*
X1469388Y5589D03*
X1474388D03*
X1501900Y-9124D03*
X1493770Y6909D03*
X1484135Y11563D03*
X1488770Y6909D03*
X1479135Y11563D03*
X1519599Y86117D03*
X1514600Y126650D03*
X1482455Y124222D03*
X1474717Y110370D03*
X1473096Y120999D03*
X1468590Y131200D03*
X1475200Y142600D03*
X1476761Y152725D03*
X1513879Y113349D03*
X1518514Y130991D03*
X1518438Y100926D03*
X1518376Y111499D03*
X1488800Y145000D03*
X1495848Y150600D03*
X1496150Y148115D03*
X1513136Y157081D03*
X1515358Y151743D03*
X1513500Y153800D03*
X1500643Y154819D03*
X1505673Y146346D03*
X1472500Y123700D03*
X1473100Y131900D03*
X1473200Y118300D03*
X1524900Y139100D03*
X1473354Y153246D03*
X1524000Y123300D03*
X1498810Y108290D03*
X1473100Y128950D03*
X1526310Y142190D03*
X1520150Y127600D03*
X1468700Y163100D03*
X1476761Y157400D03*
X1496713Y174853D03*
X1488300Y161700D03*
X1497493Y162078D03*
X1494939Y159500D03*
X1492500Y176887D03*
X1489088Y176680D03*
X1504706Y164871D03*
X1527657Y278700D03*
X1479000Y254500D03*
X1523580Y237960D03*
X1509800Y244676D03*
X1504461Y274426D03*
X1495682Y255861D03*
X1493199Y255507D03*
X1495696Y258361D03*
X1492753Y273724D03*
X1516613Y240656D03*
X1520413Y239498D03*
X1525650Y248700D03*
X1505946Y254432D03*
X1468399Y324930D03*
X1514050Y327490D03*
X1526936Y307015D03*
X1516138Y310749D03*
X1487858Y340412D03*
X1484100Y330115D03*
X1513796Y330680D03*
X1525677Y311835D03*
X1510584Y330640D03*
X1492540Y328250D03*
X1516301Y313244D03*
X1525051Y329553D03*
X1487904Y337500D03*
X1524575Y394414D03*
X1481000Y350000D03*
X1478612Y361670D03*
X1522625Y377514D03*
X1515328Y363389D03*
X1478163Y354940D03*
X1489915Y352637D03*
X1488479Y360367D03*
X1466873Y397648D03*
X1469873D03*
X1468048Y402370D03*
X1517367Y349964D03*
X1512954Y407653D03*
X1524575Y407624D03*
X1518650Y416750D03*
X1485250Y408017D03*
X1491425Y446926D03*
X1483375Y458375D03*
X1469400Y449997D03*
X1472000D03*
X1469382Y406773D03*
X1485100Y469900D03*
X1472250Y485100D03*
X1468649Y570012D03*
X1483279Y619100D03*
X1518900Y619800D03*
X1513700Y619900D03*
X1478500Y619300D03*
X1538520Y11911D03*
X1581947Y-6702D03*
X1530800Y3500D03*
X1534000D03*
X1546800Y3400D03*
X1586500Y-16100D03*
X1549800Y3400D03*
X1554800D03*
X1560500D03*
X1567498Y12506D03*
X1577048D03*
X1586998Y11355D03*
X1540000Y3400D03*
X1552300D03*
X1558000D03*
X1548698Y12506D03*
X1558148Y12306D03*
X1573048Y12506D03*
X1581998Y11355D03*
X1554148Y12306D03*
X1563498Y12506D03*
X1544698D03*
X1563200Y3400D03*
X1543500D03*
X1584748Y70840D03*
X1587359Y84348D03*
X1573060Y84120D03*
X1587734Y70974D03*
X1575018Y71213D03*
X1579100Y69000D03*
X1574780Y90992D03*
X1544180Y91660D03*
X1546370Y84180D03*
X1529449Y137408D03*
X1574000Y149500D03*
Y152100D03*
X1572634Y98546D03*
X1576506Y143416D03*
X1574197Y127915D03*
X1576606Y104392D03*
X1573153Y103721D03*
X1577770Y149519D03*
X1577950Y152600D03*
X1553353Y124209D03*
X1552171Y133000D03*
X1541421Y106742D03*
X1541390Y136498D03*
X1553500Y121000D03*
X1531726Y123800D03*
X1563108Y126423D03*
X1541351Y151900D03*
X1531985Y147000D03*
X1532923Y144518D03*
X1573121Y120649D03*
X1541765Y114000D03*
X1541831Y149030D03*
X1570294Y167384D03*
X1572817Y169910D03*
X1562150Y160700D03*
X1552051Y172053D03*
X1567000Y259560D03*
X1586950Y251267D03*
X1570318Y238116D03*
X1572700Y239400D03*
X1568365Y247761D03*
X1589592Y252472D03*
X1579867Y265445D03*
X1541325Y245090D03*
X1547869Y243356D03*
X1563157Y258164D03*
X1558700Y252000D03*
X1581077Y284825D03*
X1565000Y290500D03*
X1571293Y284755D03*
X1573790Y284895D03*
X1577486Y307621D03*
X1566000Y341000D03*
X1587800Y308200D03*
X1581090Y338795D03*
X1569211Y331542D03*
Y334142D03*
X1581940Y295820D03*
X1588551Y341410D03*
X1581834Y318591D03*
X1533228Y325000D03*
X1529734Y319714D03*
X1530500Y287700D03*
X1537500Y292800D03*
X1548273Y313227D03*
X1551250Y320303D03*
X1536027Y305048D03*
X1534833Y309798D03*
X1560400Y307683D03*
X1550619Y303087D03*
X1559997Y310317D03*
X1563000Y341000D03*
X1559500Y290300D03*
X1559800Y285300D03*
X1552900Y281700D03*
X1548100Y342200D03*
X1554800Y341100D03*
X1557550D03*
X1549000Y316600D03*
X1575645Y320664D03*
X1582800Y312100D03*
X1564400Y308383D03*
X1534325Y377514D03*
X1559675Y380894D03*
X1565525Y384274D03*
X1571375Y394414D03*
X1565525Y377514D03*
X1567121Y363217D03*
X1566922Y359681D03*
X1576074Y359600D03*
X1582600Y389300D03*
X1571450Y359650D03*
X1585150Y397400D03*
X1586500Y354900D03*
X1589100Y358400D03*
X1530425Y384274D03*
X1533719Y362783D03*
X1533790Y360283D03*
X1528475Y380894D03*
X1530425Y397794D03*
X1532375Y401174D03*
X1546025Y391034D03*
X1563575Y394414D03*
X1550639Y350200D03*
X1538500Y359363D03*
X1552500Y358500D03*
X1557725Y377514D03*
X1538397Y361861D03*
X1538478Y350694D03*
Y353294D03*
Y355894D03*
X1559675Y401174D03*
Y387654D03*
X1586500Y358400D03*
X1587684Y362653D03*
X1587032Y350996D03*
X1565525Y446926D03*
X1546025Y460446D03*
X1569425Y453686D03*
X1589396Y425674D03*
X1582300Y446100D03*
X1532375Y407934D03*
X1549950Y404490D03*
X1544075Y463826D03*
X1536275Y407934D03*
X1540175D03*
X1540700Y413600D03*
X1549926Y411312D03*
X1553825Y411314D03*
X1544150Y409900D03*
X1549964Y424753D03*
X1551875Y436786D03*
X1549925Y460446D03*
X1584970Y472370D03*
X1533595Y505530D03*
Y509030D03*
X1540175Y470586D03*
X1581730Y537170D03*
X1550990Y586588D03*
X1554358Y587258D03*
X1585155Y538574D03*
X1541162Y607903D03*
X1543697Y606719D03*
X1553000Y591100D03*
X1555600D03*
X1605004Y-17346D03*
X1600004D03*
X1637482Y21623D03*
X1638550Y7200D03*
X1595848Y11406D03*
X1607504Y-17346D03*
X1590431Y-6702D03*
X1598602Y-600D03*
X1591848Y11406D03*
X1600898Y11355D03*
X1609833Y5425D03*
X1605898Y11355D03*
X1614833Y5425D03*
X1593000Y78140D03*
X1651250Y36750D03*
X1649900Y78600D03*
X1599000Y61500D03*
X1602000Y84500D03*
X1596900D03*
X1599500Y75000D03*
X1597867Y93900D03*
X1625075Y80182D03*
X1632006Y94500D03*
X1643500Y80400D03*
X1597987Y79500D03*
X1590800Y137800D03*
X1593500D03*
X1594452Y111377D03*
X1591800Y164900D03*
X1613053Y184949D03*
X1602185Y180709D03*
X1614000Y177800D03*
X1598950Y180300D03*
X1603300Y185100D03*
X1637281Y254322D03*
X1627043Y256900D03*
X1636684Y274815D03*
X1637281Y260922D03*
X1636914Y270900D03*
X1596600Y246350D03*
X1596300Y250320D03*
X1601870Y270470D03*
X1599270Y246310D03*
X1600810Y266006D03*
X1631300Y280400D03*
X1626291Y273309D03*
X1620250Y254741D03*
X1620240Y257660D03*
X1617498Y273433D03*
X1610290Y265352D03*
X1636684Y277315D03*
X1623447Y273273D03*
X1643775Y246137D03*
X1622000Y279495D03*
X1639413Y310235D03*
X1590212Y315425D03*
X1639040Y316343D03*
X1638086Y319664D03*
X1609172Y339630D03*
X1625846Y286154D03*
X1608764Y322440D03*
X1630200Y367730D03*
X1630900Y375600D03*
X1603307Y393224D03*
X1590218Y350995D03*
X1642443Y344879D03*
X1640001Y370790D03*
X1630300Y395300D03*
X1630408Y357603D03*
X1630534Y354900D03*
X1630400Y398700D03*
X1630240Y365099D03*
X1630400Y391800D03*
X1643150Y348692D03*
X1643700Y351667D03*
X1630337Y362600D03*
X1621727Y395374D03*
X1613452Y387098D03*
X1602215Y363981D03*
X1630000Y381400D03*
X1621800Y386300D03*
Y381500D03*
X1630800Y378500D03*
X1590154Y354762D03*
X1612500Y411800D03*
X1595200Y412700D03*
X1617900Y409900D03*
X1591446Y440472D03*
X1591350Y445300D03*
X1593400Y432200D03*
X1630150Y427663D03*
X1611642Y461877D03*
X1603000Y435500D03*
X1630386Y413942D03*
X1634400Y412900D03*
X1612183Y442623D03*
X1602600Y444287D03*
X1622700Y461900D03*
X1612825Y405438D03*
X1642880Y490047D03*
X1640781Y487760D03*
X1617300Y519000D03*
X1600780Y495416D03*
X1597380D03*
X1633359Y472859D03*
X1620030Y525066D03*
X1623551Y525015D03*
X1639271Y491135D03*
X1637500Y529400D03*
X1592934Y592396D03*
X1590530Y610620D03*
X1653100Y11500D03*
X1666500Y10500D03*
X1688000Y3000D03*
X1653000Y77600D03*
X1692300Y56900D03*
X1658600Y44700D03*
X1694155Y77991D03*
X1691655D03*
X1674749Y87050D03*
X1676428Y74646D03*
X1673800Y75200D03*
X1673000Y81600D03*
X1695300Y94712D03*
X1697800Y94612D03*
X1692285D03*
X1667000Y88000D03*
X1689368Y98750D03*
X1686876Y98962D03*
X1696907Y99077D03*
X1672200Y112200D03*
X1674455Y172658D03*
X1655031Y184505D03*
X1677600Y172700D03*
X1666345Y241987D03*
X1690565Y251052D03*
X1667667Y257920D03*
X1670140Y257547D03*
X1670822Y254691D03*
X1661186Y245352D03*
X1662000Y250008D03*
X1664324Y248002D03*
X1666329Y245139D03*
X1662956Y243582D03*
X1684509Y245631D03*
X1688451Y249716D03*
X1686113Y250604D03*
X1679100Y276400D03*
X1657498Y279900D03*
Y274700D03*
Y269700D03*
X1657567Y264600D03*
X1657500Y259700D03*
X1666968Y260611D03*
X1679100Y278924D03*
Y271300D03*
Y273900D03*
X1653091Y326500D03*
X1657498Y284900D03*
X1679100Y284093D03*
Y286593D03*
Y289500D03*
Y281593D03*
X1654809Y401645D03*
X1652186Y354700D03*
Y352100D03*
X1654861Y396637D03*
X1660972Y401447D03*
X1661243Y390364D03*
Y392943D03*
X1660890Y397300D03*
X1667946Y412987D03*
X1673550Y442696D03*
X1684435Y456832D03*
Y459421D03*
X1676304Y449794D03*
X1676287Y447244D03*
X1673074Y453185D03*
X1660834Y404934D03*
X1655790Y476593D03*
X1667674Y467271D03*
X1672265Y473600D03*
X1676800Y483800D03*
X1744900Y9100D03*
X1759093Y9310D03*
X1734875Y9238D03*
X1745094Y47106D03*
X1735150Y58150D03*
X1746552Y38900D03*
X1767250Y94500D03*
Y89500D03*
X1748425Y119190D03*
X1765015Y119100D03*
X1733484Y211631D03*
X1746125D03*
X1758725D03*
X1771325D03*
X1738484D03*
X1751125D03*
X1763725D03*
X1727193Y176525D03*
X1744792D03*
X1757390D03*
X1769988D03*
X1732193D03*
X1739792D03*
X1752390D03*
X1764988D03*
X1727896Y246175D03*
X1720651Y246141D03*
X1730996Y442804D03*
X1724369Y441601D03*
X1737300Y500900D03*
X1738180Y503487D03*
X1766100Y521124D03*
X1748125Y496400D03*
X1733639Y500085D03*
X1758575Y496406D03*
X1743125Y496400D03*
X1728639Y500085D03*
X1753575Y496406D03*
X1770325Y487355D03*
X1765325D03*
X1772578Y575993D03*
X1743500Y564500D03*
X1750399Y603201D03*
X1757319Y606953D03*
X1832900Y10300D03*
X1785366Y8100D03*
X1823600Y8800D03*
X1808100Y21800D03*
X1797700Y21018D03*
X1791500Y26918D03*
X1786865Y22375D03*
X1788216Y59197D03*
X1779750Y36530D03*
X1820457Y39128D03*
X1789356Y38286D03*
X1796100Y68800D03*
X1824130Y39703D03*
X1824240Y83680D03*
X1802119Y56581D03*
X1799438Y44328D03*
X1794100Y70898D03*
X1824509Y143653D03*
X1821348Y143437D03*
X1808226Y136171D03*
X1812743Y104395D03*
X1810245Y104500D03*
X1814900Y116900D03*
X1816418Y127976D03*
X1808313Y111705D03*
X1800420Y148240D03*
X1827500Y144900D03*
X1778900Y165800D03*
X1785500Y168000D03*
X1834400Y216900D03*
X1776325Y211631D03*
X1777587Y176525D03*
X1783925Y211631D03*
X1796526Y212231D03*
X1809125D03*
X1821685Y212161D03*
X1788925Y211631D03*
X1801526Y212231D03*
X1814125D03*
X1826685Y212161D03*
X1790185Y176525D03*
X1802784D03*
X1815382D03*
X1782587D03*
X1795185D03*
X1807784D03*
X1820382D03*
X1831700Y252272D03*
X1804388Y249904D03*
X1790250Y522350D03*
X1834100Y523900D03*
X1814852Y519901D03*
X1809700Y506875D03*
X1806076Y523525D03*
X1798883Y515636D03*
X1796153Y514200D03*
X1789300Y520000D03*
X1828200Y519000D03*
X1795200Y525700D03*
X1824125Y488930D03*
X1811975Y488730D03*
X1801125Y488930D03*
X1789525D03*
X1819125D03*
X1806975Y488730D03*
X1796125Y488930D03*
X1784525D03*
X1818509Y527893D03*
X1816100Y576200D03*
X1816330Y545260D03*
X1816052Y584101D03*
X1835000Y550300D03*
X1779000Y585500D03*
X1781300Y537800D03*
X1808057Y573125D03*
Y570125D03*
X1816584Y530542D03*
X1793900Y550100D03*
X1816280Y550400D03*
Y553500D03*
X1811100Y586800D03*
X1829176Y584287D03*
X1776500Y621200D03*
X1778400Y618900D03*
X1800352Y596101D03*
X1795000Y599600D03*
X1784200Y593924D03*
X1829051Y591299D03*
X1822273Y595046D03*
X1848322Y12723D03*
X1853467Y35000D03*
X1846527Y34435D03*
X1883200Y76600D03*
X1850600Y41348D03*
X1855400Y40800D03*
X1848208Y49427D03*
X1896970Y73460D03*
X1895354Y75650D03*
X1864904Y114735D03*
X1872254Y138618D03*
X1837090Y149830D03*
X1839941Y156858D03*
X1845469Y135500D03*
X1862400Y124500D03*
X1851341Y106358D03*
X1857020Y129619D03*
Y126619D03*
X1881324Y153250D03*
X1875425Y152925D03*
X1875600Y156300D03*
X1886299Y153928D03*
X1872400Y144619D03*
X1857919Y156123D03*
X1895060Y136099D03*
X1869668Y146750D03*
X1864637Y201861D03*
X1876700Y207600D03*
X1895614Y204785D03*
X1895100Y201770D03*
X1883539Y199813D03*
X1883350Y202410D03*
X1858470Y206335D03*
X1855670Y206430D03*
X1863750Y163750D03*
X1876832Y173919D03*
X1875066Y175782D03*
X1859604Y213206D03*
X1861497Y211481D03*
X1874236Y213800D03*
X1864464Y198466D03*
X1886093Y202184D03*
X1864000Y184900D03*
X1861243Y183100D03*
X1891880Y204370D03*
X1847200Y202050D03*
X1864170Y211869D03*
X1892791Y200069D03*
X1856874Y219443D03*
X1844444Y224035D03*
X1861605Y253925D03*
X1864305Y253825D03*
X1837200Y525700D03*
X1866688Y517128D03*
X1859530Y516430D03*
X1843100Y494100D03*
X1840500D03*
X1843100Y491500D03*
X1840500D03*
X1842450Y507520D03*
X1896700Y472600D03*
X1896800Y470200D03*
X1894100Y472600D03*
X1894200Y470200D03*
X1843750Y475724D03*
X1840750D03*
X1847000Y487500D03*
X1860000Y495500D03*
X1844490Y509230D03*
X1875973Y499838D03*
X1869914Y517225D03*
X1854508Y552708D03*
X1858528Y544528D03*
X1857108Y552708D03*
X1848800Y551400D03*
X1848900Y548200D03*
X1854530Y533132D03*
X1859708Y552708D03*
X1895523Y586365D03*
X1844018Y586482D03*
X1866800Y588000D03*
X1848900Y590750D03*
X1845000Y590800D03*
X1903160Y-19416D03*
X1918352Y89300D03*
X1923300Y94300D03*
X1920300Y68300D03*
X1917600Y66000D03*
X1948472Y80362D03*
X1918210Y96103D03*
X1950934Y143730D03*
X1936187Y144013D03*
X1951700Y141000D03*
X1919702Y125920D03*
X1919195Y134396D03*
X1923329Y99475D03*
X1949389Y152083D03*
X1934000Y147100D03*
X1925358Y140685D03*
X1929756Y131037D03*
X1911440Y128840D03*
X1916310Y149676D03*
X1919514Y131701D03*
X1918002Y98902D03*
X1903917Y201472D03*
X1935600Y198700D03*
X1950981Y191218D03*
X1904042Y204895D03*
X1957334Y201269D03*
X1939300Y204300D03*
X1939550Y165600D03*
X1930300Y170147D03*
X1944300Y190200D03*
X1940500Y157600D03*
X1909438Y204307D03*
X1940240Y169970D03*
X1931065Y175520D03*
X1927500Y170400D03*
X1909421Y208805D03*
X1904724Y447930D03*
X1901574Y454422D03*
X1939845Y445055D03*
X1957212Y479521D03*
X1899100Y472600D03*
X1899200Y470200D03*
X1945000Y474000D03*
X1909800Y510700D03*
X1904200Y472700D03*
X1901700Y472600D03*
X1904300Y470300D03*
X1901800Y470200D03*
X1938300Y486250D03*
X1912800Y510700D03*
X1957063Y474769D03*
X1948200Y474300D03*
X1907200Y551600D03*
X1934600Y561900D03*
X1911750Y592800D03*
X1927000Y614500D03*
X1967580Y104721D03*
X1962800Y149300D03*
X1966700Y152400D03*
X1972598Y165236D03*
X1963092Y167936D03*
X1968375Y509375D03*
X1972800Y565200D03*
X1962950Y566600D03*
X1973000Y597200D03*
G54D31*
G01X117600Y193805D02*
Y191000D01*
X107800Y181200D01*
Y168920D01*
X99250Y160370D01*
G54D22*
X476672Y235696D03*
X483432Y239596D03*
X484552Y374146D03*
G54D13*
X-15354Y365236D03*
Y396732D03*
X22835Y132717D03*
X-10236Y116969D03*
X-4725D03*
Y132717D03*
X28346D03*
X22835Y357362D03*
X6299D03*
X17716Y365236D03*
X22835Y373110D03*
X1181Y396732D03*
X-10236Y404606D03*
X23228Y365236D03*
X-9843D03*
X11811Y357362D03*
X28346D03*
Y373110D03*
X6693Y396732D03*
X-9843D03*
X-4725Y404606D03*
X1181Y412480D03*
X6693D03*
G54D32*
G01X94998Y481612D02*
Y480002D01*
X135460Y439540D01*
X138380D01*
X153094Y424826D01*
Y414452D01*
X151909Y413267D01*
G01X340590Y616600D02*
X120351D01*
X109800Y606049D01*
Y506556D01*
G01X119892Y510100D02*
X113497Y516495D01*
Y521747D01*
X118000Y526250D01*
Y535091D01*
X119892Y536983D01*
G01Y547900D02*
X114600Y553192D01*
Y560700D01*
X117400Y563500D01*
Y572208D01*
X119892Y574700D01*
G01Y585700D02*
Y597208D01*
X117500Y599600D01*
Y606899D01*
X119892Y609291D01*
Y612583D01*
G01X669300Y504000D02*
X671496Y506196D01*
X688104D01*
X693604Y500696D01*
Y494303D01*
G01X1340841Y40100D02*
X1344929Y44188D01*
X1357706D01*
X1362200Y39694D01*
Y35500D01*
X1363200Y34500D01*
X1372792D01*
X1374799Y32493D01*
G01X1380890Y615820D02*
Y618020D01*
X1380900Y618030D01*
Y620300D01*
X1377900Y623300D01*
X1322300D01*
X1309000Y610000D01*
X1306600D01*
G01X1367100Y37800D02*
Y38600D01*
X1371295Y42795D01*
X1377717D01*
X1380424Y40088D01*
Y34723D01*
X1377256Y31555D01*
Y28600D01*
X1378856Y27000D01*
X1379200D01*
G01X1374799Y32493D02*
X1377009Y34703D01*
Y39753D01*
G01X1376094Y4406D02*
X1377965Y6277D01*
Y9573D01*
X1381700Y13308D01*
Y18373D01*
X1374799Y25274D01*
Y32493D01*
G01X1844018Y586482D02*
X1842100Y584564D01*
Y571278D01*
X1838261Y567439D01*
Y553839D01*
X1840400Y551700D01*
Y545982D01*
X1839600Y545182D01*
Y531800D01*
X1834100Y526300D01*
Y523900D01*
G01X1816100Y576200D02*
X1816700D01*
X1820000Y572900D01*
Y549400D01*
X1816330Y545730D01*
Y545260D01*
G54D23*
X1452000Y-15000D03*
X1819504Y-5000D03*
X1809504D03*
G54D14*
X-14488Y434094D03*
X89980Y145531D03*
G54D33*
G01X523244Y549457D02*
X523692Y549905D01*
Y554759D01*
X522792Y555659D01*
G01X527105Y548657D02*
X525092Y550670D01*
Y555854D01*
X525195Y555957D01*
G01X1172852Y549457D02*
X1173300Y549905D01*
Y554759D01*
X1172400Y555659D01*
G01X1174803Y555957D02*
X1174700Y555854D01*
Y550670D01*
X1176713Y548657D01*
G54D24*
X1809665Y618663D03*
X1829665D03*
G54D15*
X30500Y-42250D03*
Y-52250D03*
X12290Y264640D03*
X18450Y267010D03*
X22970Y244400D03*
X28720Y244450D03*
X17120Y244220D03*
X24200Y267060D03*
X50500Y-42250D03*
X70500D03*
X50500Y-52250D03*
X70500D03*
X80500Y-42250D03*
Y-52250D03*
X457246Y-52301D03*
Y-42301D03*
X477246Y-52301D03*
Y-42301D03*
X497246Y-52301D03*
Y-42301D03*
X507246Y-52301D03*
Y-42301D03*
X788984Y-52057D03*
Y-42057D03*
X808984Y-52057D03*
Y-42057D03*
X828984Y-52057D03*
Y-42057D03*
X838984Y-52057D03*
Y-42057D03*
X1125583Y-52285D03*
Y-42285D03*
X1145583Y-52285D03*
Y-42285D03*
X1382258Y-52257D03*
Y-42257D03*
X1402258Y-52257D03*
Y-42257D03*
X1422258Y-52257D03*
Y-42257D03*
X1442258Y-52257D03*
Y-42257D03*
G54D34*
G01X548049Y-193422D02*
Y-210922D01*
G01X543027Y-193422D02*
X553071D01*
G01X565549Y-199256D02*
Y-210922D01*
G01Y-194589D02*
X565112Y-194297D01*
Y-193714D01*
X565549Y-193422D01*
X565986Y-193714D01*
Y-194297D01*
X565549Y-194589D01*
G01X583049Y-210922D02*
X581739Y-210630D01*
X580429Y-209464D01*
X579555Y-207422D01*
X579119Y-205089D01*
X579555Y-202755D01*
X580429Y-200714D01*
X581739Y-199547D01*
X583049Y-199256D01*
X584359Y-199547D01*
X585669Y-200714D01*
X586542Y-202755D01*
X586761Y-205089D01*
X586542Y-207422D01*
X585669Y-209464D01*
X584359Y-210630D01*
X583049Y-210922D01*
G01X597492Y-215297D02*
X599021Y-216464D01*
X600767Y-216755D01*
X602295Y-216464D01*
X603606Y-215006D01*
X604479Y-212964D01*
Y-199256D01*
G01Y-201589D02*
X603606Y-200422D01*
X602295Y-199547D01*
X600767Y-199256D01*
X599021Y-199839D01*
X597929Y-201005D01*
X597055Y-203047D01*
X596619Y-205089D01*
X596837Y-206839D01*
X597711Y-208881D01*
X599021Y-210339D01*
X600767Y-210922D01*
X602077Y-210630D01*
X603606Y-209464D01*
X604479Y-208298D01*
G01X621979Y-210922D02*
Y-199256D01*
G01Y-201297D02*
X621106Y-200131D01*
X619795Y-199547D01*
X618267Y-199256D01*
X616739Y-199839D01*
X615429Y-201005D01*
X614555Y-202755D01*
X614119Y-205089D01*
X614555Y-207422D01*
X615429Y-209172D01*
X616739Y-210339D01*
X618267Y-210922D01*
X619795Y-210630D01*
X621106Y-209756D01*
X621979Y-208589D01*
G01X648682Y-210922D02*
Y-193422D01*
X653922D01*
X655669Y-194297D01*
X656979Y-196339D01*
X657416Y-198672D01*
X656979Y-201005D01*
X655887Y-202755D01*
X653922Y-203631D01*
X648682D01*
G01X674479Y-210922D02*
Y-199256D01*
G01Y-201297D02*
X673606Y-200131D01*
X672295Y-199547D01*
X670767Y-199256D01*
X669239Y-199839D01*
X667929Y-201005D01*
X667055Y-202755D01*
X666619Y-205089D01*
X667055Y-207422D01*
X667929Y-209172D01*
X669239Y-210339D01*
X670767Y-210922D01*
X672295Y-210630D01*
X673606Y-209756D01*
X674479Y-208589D01*
G01X684774Y-208881D02*
X685866Y-210047D01*
X687394Y-210922D01*
X688704D01*
X690014Y-210339D01*
X690887Y-209464D01*
X691324Y-208298D01*
X691106Y-206547D01*
X690232Y-205672D01*
X686302Y-203922D01*
X685429Y-201880D01*
X685866Y-200422D01*
X686739Y-199547D01*
X688049Y-199256D01*
X689359Y-199547D01*
X690669Y-200422D01*
G01X702274Y-208881D02*
X703366Y-210047D01*
X704894Y-210922D01*
X706204D01*
X707514Y-210339D01*
X708387Y-209464D01*
X708824Y-208298D01*
X708606Y-206547D01*
X707732Y-205672D01*
X703802Y-203922D01*
X702929Y-201880D01*
X703366Y-200422D01*
X704239Y-199547D01*
X705549Y-199256D01*
X706859Y-199547D01*
X708169Y-200422D01*
G01X735746Y-210922D02*
Y-193422D01*
X740112D01*
X741859Y-194297D01*
X743169Y-195464D01*
X744261Y-197213D01*
X745134Y-199256D01*
X745352Y-202172D01*
X745134Y-205089D01*
X744261Y-207131D01*
X743169Y-208881D01*
X741859Y-210047D01*
X740112Y-210922D01*
X735746D01*
G01X752590Y-193422D02*
X758049Y-210922D01*
X763508Y-193422D01*
G01X775549D02*
Y-210922D01*
G01X770527Y-193422D02*
X780571D01*
G01X804872Y-210922D02*
Y-193422D01*
X810549Y-208005D01*
X816226Y-193422D01*
Y-210922D01*
G01X829795Y-201589D02*
X830669Y-200714D01*
X831324Y-199256D01*
X831761Y-197213D01*
X831324Y-195464D01*
X830451Y-194297D01*
X828922Y-193422D01*
X823027D01*
Y-210922D01*
X830232D01*
X831761Y-209756D01*
X832634Y-208005D01*
X833071Y-205964D01*
X832634Y-203922D01*
X831324Y-202172D01*
X829795Y-201589D01*
X823027D01*
G01X647372Y-165922D02*
Y-148422D01*
X653049Y-163005D01*
X658726Y-148422D01*
Y-165922D01*
G01X670549D02*
X669239Y-165630D01*
X667929Y-164464D01*
X667055Y-162422D01*
X666619Y-160089D01*
X667055Y-157755D01*
X667929Y-155714D01*
X669239Y-154547D01*
X670549Y-154256D01*
X671859Y-154547D01*
X673169Y-155714D01*
X674042Y-157755D01*
X674261Y-160089D01*
X674042Y-162422D01*
X673169Y-164464D01*
X671859Y-165630D01*
X670549Y-165922D01*
G01X691979Y-148422D02*
Y-165922D01*
G01Y-163298D02*
X691106Y-164756D01*
X689795Y-165630D01*
X688267Y-165922D01*
X686521Y-165339D01*
X685211Y-163881D01*
X684337Y-162131D01*
X684119Y-160089D01*
X684337Y-158047D01*
X685211Y-156297D01*
X686521Y-154839D01*
X688267Y-154256D01*
X689795Y-154547D01*
X690887Y-155131D01*
X691979Y-156297D01*
G01X702274Y-158047D02*
X709261D01*
X708606Y-156005D01*
X707514Y-154839D01*
X705986Y-154256D01*
X704457Y-154547D01*
X703147Y-155422D01*
X702274Y-157464D01*
X701837Y-159214D01*
Y-160964D01*
X702274Y-162714D01*
X703366Y-164464D01*
X704676Y-165630D01*
X706204Y-165922D01*
X707732Y-165339D01*
X709261Y-163589D01*
G01X723049Y-165922D02*
Y-148422D01*
G01X975549Y-210922D02*
Y-193422D01*
X972929Y-196922D01*
G01Y-210922D02*
X978169D01*
G01X988246Y-208298D02*
X989555Y-209756D01*
X991084Y-210630D01*
X993049Y-210922D01*
X995014Y-210339D01*
X996542Y-209172D01*
X997634Y-207131D01*
X997852Y-204797D01*
X997416Y-202464D01*
X996324Y-201005D01*
X994795Y-199839D01*
X993267Y-199547D01*
X991739Y-199839D01*
X989774Y-201005D01*
X990429Y-193422D01*
X996324D01*
G01X1010549Y-210922D02*
Y-193422D01*
X1007929Y-196922D01*
G01Y-210922D02*
X1013169D01*
G01X1023901Y-196339D02*
X1025211Y-194589D01*
X1026739Y-193714D01*
X1028486Y-193422D01*
X1030669Y-194005D01*
X1032197Y-195464D01*
X1032634Y-197213D01*
X1032416Y-198964D01*
X1031542Y-200422D01*
X1027176Y-203339D01*
X1025211Y-205380D01*
X1023901Y-208298D01*
X1023464Y-210922D01*
X1032634D01*
G01X1041401Y-203631D02*
X1042929Y-201589D01*
X1044239Y-200422D01*
X1045986Y-199839D01*
X1047514Y-200422D01*
X1048606Y-201589D01*
X1049479Y-203339D01*
X1049697Y-205380D01*
X1049479Y-207131D01*
X1048606Y-208881D01*
X1047295Y-210339D01*
X1045767Y-210922D01*
X1044021Y-210339D01*
X1042492Y-208589D01*
X1041619Y-205964D01*
X1041401Y-203047D01*
X1041837Y-199256D01*
X1042492Y-197213D01*
X1043584Y-195172D01*
X1045112Y-193714D01*
X1046641Y-193422D01*
X1048169Y-194005D01*
X1049261Y-195464D01*
G01X962432Y-165922D02*
Y-148422D01*
X967672D01*
X969419Y-149297D01*
X970729Y-151339D01*
X971166Y-153672D01*
X970729Y-156005D01*
X969637Y-157755D01*
X967672Y-158631D01*
X962432D01*
G01X989102Y-149881D02*
X987792Y-149005D01*
X986264Y-148422D01*
X984517D01*
X982552Y-149297D01*
X981024Y-150755D01*
X979932Y-152506D01*
X979059Y-155422D01*
X978840Y-158047D01*
X979277Y-160672D01*
X979932Y-162422D01*
X981242Y-164172D01*
X982771Y-165339D01*
X984299Y-165922D01*
X985827D01*
X987356Y-165339D01*
X988666Y-164464D01*
X989758Y-163298D01*
G01X1003545Y-156589D02*
X1004419Y-155714D01*
X1005074Y-154256D01*
X1005511Y-152213D01*
X1005074Y-150464D01*
X1004201Y-149297D01*
X1002672Y-148422D01*
X996777D01*
Y-165922D01*
X1003982D01*
X1005511Y-164756D01*
X1006384Y-163005D01*
X1006821Y-160964D01*
X1006384Y-158922D01*
X1005074Y-157172D01*
X1003545Y-156589D01*
X996777D01*
G01X1012749Y-171755D02*
X1025849D01*
G01X1031777Y-165922D02*
Y-148422D01*
X1041821Y-165922D01*
Y-148422D01*
G01X1054299Y-165922D02*
X1052552Y-165630D01*
X1051024Y-164464D01*
X1049714Y-162714D01*
X1048840Y-160672D01*
X1048404Y-158339D01*
Y-156005D01*
X1048840Y-153672D01*
X1049714Y-151630D01*
X1051024Y-149881D01*
X1052552Y-148714D01*
X1054299Y-148422D01*
X1056045Y-148714D01*
X1057574Y-149881D01*
X1058884Y-151630D01*
X1059758Y-153672D01*
X1060194Y-156005D01*
Y-158339D01*
X1059758Y-160672D01*
X1058884Y-162714D01*
X1057574Y-164464D01*
X1056045Y-165630D01*
X1054299Y-165922D01*
G01X1128099Y-210922D02*
Y-193422D01*
X1125479Y-196922D01*
G01Y-210922D02*
X1130719D01*
G01X1147345Y-201589D02*
X1148219Y-200714D01*
X1148874Y-199256D01*
X1149311Y-197213D01*
X1148874Y-195464D01*
X1148001Y-194297D01*
X1146472Y-193422D01*
X1140577D01*
Y-210922D01*
X1147782D01*
X1149311Y-209756D01*
X1150184Y-208005D01*
X1150621Y-205964D01*
X1150184Y-203922D01*
X1148874Y-202172D01*
X1147345Y-201589D01*
X1140577D01*
G01X1105140Y-148422D02*
X1110599Y-165922D01*
X1116058Y-148422D01*
G01X1132466Y-165922D02*
X1123732D01*
Y-148422D01*
X1132466D01*
G01X1128972Y-156880D02*
X1123732D01*
G01X1141232Y-165922D02*
Y-148422D01*
X1146691D01*
X1148437Y-149297D01*
X1149529Y-150464D01*
X1149966Y-152797D01*
X1149529Y-155131D01*
X1148219Y-156589D01*
X1146691Y-157464D01*
X1141232D01*
G01X1146691D02*
X1149966Y-165922D01*
G01X1163099Y-166505D02*
X1162662Y-166214D01*
Y-165630D01*
X1163099Y-165339D01*
X1163536Y-165630D01*
Y-166214D01*
X1163099Y-166505D01*
G01X1264932Y-193422D02*
Y-210922D01*
X1273666D01*
G01X1281996Y-208298D02*
X1283305Y-209756D01*
X1284834Y-210630D01*
X1286799Y-210922D01*
X1288764Y-210339D01*
X1290292Y-209172D01*
X1291384Y-207131D01*
X1291602Y-204797D01*
X1291166Y-202464D01*
X1290074Y-201005D01*
X1288545Y-199839D01*
X1287017Y-199547D01*
X1285489Y-199839D01*
X1283524Y-201005D01*
X1284179Y-193422D01*
X1290074D01*
G01X1238682Y-148422D02*
Y-165922D01*
X1247416D01*
G01X1264479D02*
Y-154256D01*
G01Y-156297D02*
X1263606Y-155131D01*
X1262295Y-154547D01*
X1260767Y-154256D01*
X1259239Y-154839D01*
X1257929Y-156005D01*
X1257055Y-157755D01*
X1256619Y-160089D01*
X1257055Y-162422D01*
X1257929Y-164172D01*
X1259239Y-165339D01*
X1260767Y-165922D01*
X1262295Y-165630D01*
X1263606Y-164756D01*
X1264479Y-163589D01*
G01X1273464Y-171172D02*
X1274774Y-171755D01*
X1276521Y-171172D01*
X1277612Y-170006D01*
X1278486Y-168547D01*
X1279795Y-163881D01*
X1282634Y-154256D01*
G01X1275647D02*
X1279795Y-163881D01*
G01X1292274Y-158047D02*
X1299261D01*
X1298606Y-156005D01*
X1297514Y-154839D01*
X1295986Y-154256D01*
X1294457Y-154547D01*
X1293147Y-155422D01*
X1292274Y-157464D01*
X1291837Y-159214D01*
Y-160964D01*
X1292274Y-162714D01*
X1293366Y-164464D01*
X1294676Y-165630D01*
X1296204Y-165922D01*
X1297732Y-165339D01*
X1299261Y-163589D01*
G01X1309992Y-165922D02*
Y-154256D01*
G01Y-156589D02*
X1311084Y-155422D01*
X1312176Y-154547D01*
X1313704Y-154256D01*
X1314795Y-154547D01*
X1316106Y-155422D01*
G01X1380796Y-165922D02*
Y-148422D01*
X1385162D01*
X1386909Y-149297D01*
X1388219Y-150464D01*
X1389311Y-152213D01*
X1390184Y-154256D01*
X1390402Y-157172D01*
X1390184Y-160089D01*
X1389311Y-162131D01*
X1388219Y-163881D01*
X1386909Y-165047D01*
X1385162Y-165922D01*
X1380796D01*
G01X1399824Y-158047D02*
X1406811D01*
X1406156Y-156005D01*
X1405064Y-154839D01*
X1403536Y-154256D01*
X1402007Y-154547D01*
X1400697Y-155422D01*
X1399824Y-157464D01*
X1399387Y-159214D01*
Y-160964D01*
X1399824Y-162714D01*
X1400916Y-164464D01*
X1402226Y-165630D01*
X1403754Y-165922D01*
X1405282Y-165339D01*
X1406811Y-163589D01*
G01X1417324Y-163881D02*
X1418416Y-165047D01*
X1419944Y-165922D01*
X1421254D01*
X1422564Y-165339D01*
X1423437Y-164464D01*
X1423874Y-163298D01*
X1423656Y-161547D01*
X1422782Y-160672D01*
X1418852Y-158922D01*
X1417979Y-156880D01*
X1418416Y-155422D01*
X1419289Y-154547D01*
X1420599Y-154256D01*
X1421909Y-154547D01*
X1423219Y-155422D01*
G01X1438099Y-154256D02*
Y-165922D01*
G01Y-149589D02*
X1437662Y-149297D01*
Y-148714D01*
X1438099Y-148422D01*
X1438536Y-148714D01*
Y-149297D01*
X1438099Y-149589D01*
G01X1452542Y-170297D02*
X1454071Y-171464D01*
X1455817Y-171755D01*
X1457345Y-171464D01*
X1458656Y-170006D01*
X1459529Y-167964D01*
Y-154256D01*
G01Y-156589D02*
X1458656Y-155422D01*
X1457345Y-154547D01*
X1455817Y-154256D01*
X1454071Y-154839D01*
X1452979Y-156005D01*
X1452105Y-158047D01*
X1451669Y-160089D01*
X1451887Y-161839D01*
X1452761Y-163881D01*
X1454071Y-165339D01*
X1455817Y-165922D01*
X1457127Y-165630D01*
X1458656Y-164464D01*
X1459529Y-163298D01*
G01X1469387Y-165922D02*
Y-154256D01*
G01Y-157172D02*
X1470261Y-155714D01*
X1471571Y-154547D01*
X1473317Y-154256D01*
X1474845Y-154547D01*
X1476156Y-155714D01*
X1476811Y-157755D01*
Y-165922D01*
G01X1487324Y-158047D02*
X1494311D01*
X1493656Y-156005D01*
X1492564Y-154839D01*
X1491036Y-154256D01*
X1489507Y-154547D01*
X1488197Y-155422D01*
X1487324Y-157464D01*
X1486887Y-159214D01*
Y-160964D01*
X1487324Y-162714D01*
X1488416Y-164464D01*
X1489726Y-165630D01*
X1491254Y-165922D01*
X1492782Y-165339D01*
X1494311Y-163589D01*
G01X1505042Y-165922D02*
Y-154256D01*
G01Y-156589D02*
X1506134Y-155422D01*
X1507226Y-154547D01*
X1508754Y-154256D01*
X1509845Y-154547D01*
X1511156Y-155422D01*
G01X1426729Y-193422D02*
X1431969D01*
G01X1429349D02*
Y-210922D01*
G01X1426729D02*
X1431969D01*
G01X1441390Y-193422D02*
X1446849Y-210922D01*
X1452308Y-193422D01*
G01X1464349Y-210922D02*
Y-203047D01*
X1459982Y-193422D01*
G01X1468716D02*
X1464349Y-203047D01*
G01X1551799Y-193422D02*
X1550052Y-194005D01*
X1548742Y-195464D01*
X1547869Y-197213D01*
X1547214Y-199547D01*
X1546996Y-202172D01*
X1547214Y-204797D01*
X1547869Y-207131D01*
X1548742Y-208881D01*
X1550052Y-210339D01*
X1551799Y-210922D01*
X1553545Y-210339D01*
X1554856Y-208881D01*
X1555729Y-207131D01*
X1556384Y-204797D01*
X1556602Y-202172D01*
X1556384Y-199547D01*
X1555729Y-197213D01*
X1554856Y-195464D01*
X1553545Y-194005D01*
X1551799Y-193422D01*
G01X1565151Y-196339D02*
X1566461Y-194589D01*
X1567989Y-193714D01*
X1569736Y-193422D01*
X1571919Y-194005D01*
X1573447Y-195464D01*
X1573884Y-197213D01*
X1573666Y-198964D01*
X1572792Y-200422D01*
X1568426Y-203339D01*
X1566461Y-205380D01*
X1565151Y-208298D01*
X1564714Y-210922D01*
X1573884D01*
G01X1582869Y-211505D02*
X1590729Y-193422D01*
G01X1604299Y-210922D02*
Y-193422D01*
X1601679Y-196922D01*
G01Y-210922D02*
X1606919D01*
G01X1621799Y-193422D02*
X1620052Y-194005D01*
X1618742Y-195464D01*
X1617869Y-197213D01*
X1617214Y-199547D01*
X1616996Y-202172D01*
X1617214Y-204797D01*
X1617869Y-207131D01*
X1618742Y-208881D01*
X1620052Y-210339D01*
X1621799Y-210922D01*
X1623545Y-210339D01*
X1624856Y-208881D01*
X1625729Y-207131D01*
X1626384Y-204797D01*
X1626602Y-202172D01*
X1626384Y-199547D01*
X1625729Y-197213D01*
X1624856Y-195464D01*
X1623545Y-194005D01*
X1621799Y-193422D01*
G01X1635369Y-211505D02*
X1643229Y-193422D01*
G01X1652651Y-196339D02*
X1653961Y-194589D01*
X1655489Y-193714D01*
X1657236Y-193422D01*
X1659419Y-194005D01*
X1660947Y-195464D01*
X1661384Y-197213D01*
X1661166Y-198964D01*
X1660292Y-200422D01*
X1655926Y-203339D01*
X1653961Y-205380D01*
X1652651Y-208298D01*
X1652214Y-210922D01*
X1661384D01*
G01X1674299Y-193422D02*
X1672552Y-194005D01*
X1671242Y-195464D01*
X1670369Y-197213D01*
X1669714Y-199547D01*
X1669496Y-202172D01*
X1669714Y-204797D01*
X1670369Y-207131D01*
X1671242Y-208881D01*
X1672552Y-210339D01*
X1674299Y-210922D01*
X1676045Y-210339D01*
X1677356Y-208881D01*
X1678229Y-207131D01*
X1678884Y-204797D01*
X1679102Y-202172D01*
X1678884Y-199547D01*
X1678229Y-197213D01*
X1677356Y-195464D01*
X1676045Y-194005D01*
X1674299Y-193422D01*
G01X1691799Y-210922D02*
Y-193422D01*
X1689179Y-196922D01*
G01Y-210922D02*
X1694419D01*
G01X1708862D02*
X1709299Y-207131D01*
X1709954Y-203922D01*
X1710827Y-201005D01*
X1711919Y-197797D01*
X1713666Y-193422D01*
X1704932D01*
G01X1599496Y-165922D02*
Y-148422D01*
X1603862D01*
X1605609Y-149297D01*
X1606919Y-150464D01*
X1608011Y-152213D01*
X1608884Y-154256D01*
X1609102Y-157172D01*
X1608884Y-160089D01*
X1608011Y-162131D01*
X1606919Y-163881D01*
X1605609Y-165047D01*
X1603862Y-165922D01*
X1599496D01*
G01X1625729D02*
Y-154256D01*
G01Y-156297D02*
X1624856Y-155131D01*
X1623545Y-154547D01*
X1622017Y-154256D01*
X1620489Y-154839D01*
X1619179Y-156005D01*
X1618305Y-157755D01*
X1617869Y-160089D01*
X1618305Y-162422D01*
X1619179Y-164172D01*
X1620489Y-165339D01*
X1622017Y-165922D01*
X1623545Y-165630D01*
X1624856Y-164756D01*
X1625729Y-163589D01*
G01X1639299Y-148422D02*
Y-165922D01*
G01X1636242Y-154256D02*
X1642356D01*
G01X1653524Y-158047D02*
X1660511D01*
X1659856Y-156005D01*
X1658764Y-154839D01*
X1657236Y-154256D01*
X1655707Y-154547D01*
X1654397Y-155422D01*
X1653524Y-157464D01*
X1653087Y-159214D01*
Y-160964D01*
X1653524Y-162714D01*
X1654616Y-164464D01*
X1655926Y-165630D01*
X1657454Y-165922D01*
X1658982Y-165339D01*
X1660511Y-163589D01*
G54D16*
X18228Y178386D03*
X-1969D03*
X44291D03*
G54D25*
X1900595Y525415D03*
X1908469D03*
G54D35*
G01X-9900Y486400D02*
X-11200Y487700D01*
Y490734D01*
X-9354Y492580D01*
X-5132D01*
X2248Y485200D01*
X22341D01*
X28011Y479530D01*
X55529D01*
X70047Y494048D01*
Y508707D01*
X75390Y514050D01*
Y524265D01*
X84900Y533775D01*
Y615495D01*
X89360Y619955D01*
Y620310D01*
G01X-13500Y486400D02*
X-12200Y487700D01*
Y491149D01*
X-9769Y493580D01*
X-4717D01*
X2663Y486200D01*
X22756D01*
X28426Y480530D01*
X55114D01*
X69047Y494463D01*
Y509122D01*
X74390Y514465D01*
Y524680D01*
X83900Y534190D01*
Y615910D01*
X86230Y618240D01*
Y620250D01*
G01X98538Y341139D02*
X100700Y338977D01*
Y337750D01*
X97730Y334780D01*
Y317330D01*
X95799Y315399D01*
Y298844D01*
X97300Y297343D01*
Y278049D01*
X105930Y269419D01*
Y232685D01*
X111900Y226715D01*
Y216803D01*
X112915Y215788D01*
X114784D01*
X115508Y216512D01*
G01X102040Y348960D02*
X103850Y347150D01*
Y341280D01*
X106010Y339120D01*
Y322960D01*
X100600Y317550D01*
Y285315D01*
X108430Y277485D01*
Y256890D01*
X111350Y253970D01*
Y248699D01*
X112574Y247475D01*
X114471D01*
X115372Y248376D01*
X115497D01*
G01X98680Y338080D02*
Y337145D01*
X96730Y335195D01*
Y317745D01*
X94799Y315814D01*
Y298429D01*
X96300Y296928D01*
Y277634D01*
X104930Y269004D01*
Y232270D01*
X110900Y226300D01*
Y216388D01*
X112500Y214788D01*
X114256D01*
X115536Y213508D01*
G01X101880Y346300D02*
X102850Y345330D01*
Y340865D01*
X105010Y338705D01*
Y323375D01*
X99600Y317965D01*
Y284900D01*
X107430Y277070D01*
Y256475D01*
X110350Y253555D01*
Y248284D01*
X112159Y246475D01*
X114569D01*
X115525Y245519D01*
Y245372D01*
G01X102160Y354780D02*
X102660Y354280D01*
X105381D01*
X106466Y353195D01*
Y342363D01*
X108820Y340009D01*
Y319490D01*
X107500Y318170D01*
Y294590D01*
X112990Y289100D01*
Y279838D01*
X113490Y279338D01*
X114334D01*
X115508Y280512D01*
G01X102060Y351759D02*
X103540Y353239D01*
Y353280D01*
X104966D01*
X105466Y352780D01*
Y341948D01*
X107820Y339594D01*
Y319905D01*
X106500Y318585D01*
Y294175D01*
X111990Y288685D01*
Y279423D01*
X113075Y278338D01*
X114706D01*
X115536Y277508D01*
G01X101770Y363150D02*
X103860D01*
X109000Y358010D01*
Y343570D01*
X111360Y341210D01*
Y327050D01*
X113000Y325410D01*
Y312511D01*
X113913Y311598D01*
X114594D01*
X115508Y312512D01*
G01X101828Y371096D02*
X102534Y370390D01*
X103801D01*
X111500Y362691D01*
Y357300D01*
X113750Y355050D01*
Y344452D01*
X114250Y343952D01*
X114959D01*
X115508Y344512D01*
G01X115536Y309508D02*
X114446Y310598D01*
X113498D01*
X112000Y312096D01*
Y324995D01*
X110360Y326635D01*
Y340795D01*
X108000Y343155D01*
Y357595D01*
X104404Y361191D01*
X103280D01*
X102209Y360120D01*
X101750D01*
G01X101965Y368296D02*
Y368890D01*
X102465Y369390D01*
X103386D01*
X110500Y362276D01*
Y356885D01*
X112750Y354635D01*
Y344037D01*
X113835Y342952D01*
X114064D01*
X115536Y341508D01*
G01X167680Y408440D02*
X168089D01*
X171800Y404729D01*
Y404601D01*
X171790Y404591D01*
Y403109D01*
X174161Y400738D01*
X176462D01*
X185546Y391654D01*
Y390154D01*
X191000Y384700D01*
X195360D01*
X203230Y376830D01*
Y369042D01*
X205440Y366832D01*
Y359260D01*
X247175Y317525D01*
X260813D01*
G01X167640Y404842D02*
X168351Y405553D01*
X169555D01*
X170890Y404218D01*
Y402736D01*
X173788Y399838D01*
X176089D01*
X184646Y391281D01*
Y389781D01*
X190627Y383800D01*
X194987D01*
X202330Y376457D01*
Y368669D01*
X204540Y366459D01*
Y358887D01*
X246802Y316625D01*
X260813D01*
G01X559000Y247703D02*
X580476D01*
X587667Y254894D01*
X608006D01*
X615165Y247735D01*
X617235D01*
G01X559000Y246703D02*
X580891D01*
X588082Y253894D01*
X607591D01*
X614456Y247029D01*
Y244956D01*
G01X737912Y315500D02*
Y401684D01*
X740808Y404580D01*
X769087D01*
X771507Y407000D01*
X774253D01*
X776973Y404280D01*
X793793D01*
X795873Y402200D01*
X798227D01*
X802027Y406000D01*
X803967D01*
X805367Y407400D01*
G01X741512Y315538D02*
X738812Y318238D01*
Y401311D01*
X741181Y403680D01*
X769460D01*
X771880Y406100D01*
X773880D01*
X776600Y403380D01*
X793420D01*
X795500Y401300D01*
X798600D01*
X802400Y405100D01*
X804400D01*
X805600Y403900D01*
G01X1293600Y-17000D02*
X1296166Y-14434D01*
Y1451D01*
X1298950Y4235D01*
Y18583D01*
X1301800Y21433D01*
Y48685D01*
X1306271Y53156D01*
X1325626D01*
X1327500Y51547D01*
G01X1293816Y-13533D02*
X1295166Y-12183D01*
Y1866D01*
X1297950Y4650D01*
Y18998D01*
X1300800Y21848D01*
Y49100D01*
X1305856Y54156D01*
X1326256D01*
X1327452Y55544D01*
G01X1623551Y525015D02*
X1622959D01*
X1622319Y525655D01*
Y527602D01*
X1620204Y529717D01*
X1610598D01*
X1604114Y536201D01*
X1603286D01*
X1603285Y536200D01*
X1587529D01*
X1585155Y538574D01*
G01X1620030Y525066D02*
X1620832D01*
X1621301Y525535D01*
Y527205D01*
X1619789Y528717D01*
X1610183D01*
X1603700Y535200D01*
X1583700D01*
X1581730Y537170D01*
G54D26*
X1944882Y597834D03*
G54D17*
X3937Y204370D03*
X-3937D03*
X-11811D03*
X35433D03*
X27559D03*
X19685D03*
X3937Y227992D03*
X-3937D03*
X-11811D03*
X35433D03*
X27559D03*
X19685D03*
X3937Y313504D03*
X-3937D03*
X-11811D03*
X3937Y337126D03*
X-3937D03*
X-11811D03*
X35433D03*
X27559D03*
X19685D03*
X35433Y313504D03*
X27559D03*
X19685D03*
G54D36*
G01X261898Y269321D02*
X263234Y267985D01*
X264836D01*
G03X265687Y268761I-657J1575D01*
G02X267059Y269934I2172J-1152D01*
G01X267903D01*
G03X269224Y270722I-44J1575D01*
G02X271169Y271885I2015J-1162D01*
G01X271298D01*
G03X272604Y272672I-59J1575D01*
G02X274534Y273834I2015J-1163D01*
G01X274704D01*
G02X276634Y272672I-85J-2325D01*
G03X277940Y271885I1365J788D01*
G01X278069D01*
G02X280014Y270722I-70J-2325D01*
G01X280082Y270605D01*
X280523Y269891D01*
X281379Y267609D01*
G01X260278Y239841D02*
X261387D01*
X261768Y240222D01*
Y247322D01*
X262931Y248485D01*
X264538D01*
G03X265844Y249272I-59J1575D01*
G02X267774Y250434I2015J-1163D01*
G01X267903D01*
G03X269224Y251222I-44J1575D01*
G02X271169Y252385I2015J-1162D01*
G01X271298D01*
G03X272604Y253172I-59J1575D01*
G02X274534Y254334I2015J-1163D01*
G01X274663D01*
G03X275301Y254489I-45J1575D01*
G01X276345Y254999D01*
X277698Y255535D01*
X278043D01*
G02X279138Y255049I-44J-1575D01*
G01X280265Y254307D01*
X282067Y253427D01*
G02X282638Y252957I-688J-1418D01*
G01X283631Y251600D01*
X284759Y250060D01*
G01X261473Y237484D02*
Y238816D01*
X262518Y239861D01*
Y247011D01*
X263242Y247735D01*
X264564D01*
G03X266494Y248897I-85J2325D01*
G02X267800Y249684I1365J-788D01*
G01X267929D01*
G03X269874Y250847I-70J2325D01*
G02X271195Y251635I1365J-787D01*
G01X271324D01*
G03X273254Y252797I-85J2325D01*
G02X274560Y253584I1365J-788D01*
G01X274998D01*
X275873Y253297D01*
X277023Y252723D01*
G03X277940Y252385I977J1237D01*
G01X278069D01*
G02X280014Y251222I-70J-2325D01*
G03X281335Y250434I1365J787D01*
G01X281464D01*
G02X283394Y249272I-85J-2325D01*
G03X284700Y248485I1365J788D01*
G01X284901D01*
X288139Y248109D01*
G01X261898Y266821D02*
X262312Y267235D01*
X264979D01*
G03X266351Y268408I-800J2325D01*
G02X267202Y269184I1508J-799D01*
G01X267929D01*
G03X269874Y270347I-70J2325D01*
G02X271195Y271135I1365J-787D01*
G01X271324D01*
G03X273254Y272297I-85J2325D01*
G02X274560Y273084I1365J-788D01*
G01X274678D01*
G02X275984Y272297I-59J-1575D01*
G03X277914Y271135I2015J1163D01*
G01X278043D01*
G02X279364Y270347I-44J-1575D01*
G01X279578Y269976D01*
X279805Y267686D01*
G03X281335Y266034I1574J-77D01*
G01X281748D01*
X283903Y266983D01*
G02X286124Y266447I856J-1323D01*
G01X286190Y266331D01*
X288139Y263709D01*
G01X256241Y245039D02*
X257528D01*
X258348Y245859D01*
Y248972D01*
X261761Y252385D01*
X264836D01*
G03X265687Y253161I-657J1575D01*
G02X267059Y254334I2172J-1152D01*
G01X267903D01*
G03X269224Y255122I-44J1575D01*
G02X271169Y256285I2015J-1162D01*
G01X271298D01*
G03X272604Y257072I-59J1575D01*
G02X274534Y258234I2015J-1163D01*
G01X275282D01*
X277947Y257926D01*
X277999Y257860D01*
G01X258409Y243671D02*
Y244862D01*
X259098Y245551D01*
Y248661D01*
X262072Y251635D01*
X264979D01*
G03X266351Y252808I-800J2325D01*
G02X267202Y253584I1508J-799D01*
G01X267929D01*
G03X269874Y254747I-70J2325D01*
G02X271195Y255535I1365J-787D01*
G01X271324D01*
G03X273254Y256697I-85J2325D01*
G02X274560Y257484I1365J-788D01*
G01X275075D01*
G02X276905Y256726I0J-2588D01*
G03X277940Y256285I1095J1134D01*
G01X278141D01*
X281379Y255909D01*
G01X266178Y274261D02*
X266504Y273935D01*
X267355Y273934D01*
X267681D01*
X268190Y273971D01*
G03X269075Y274724I-631J1638D01*
G02X270303Y275785I2164J-1264D01*
G01X271298D01*
G03X272604Y276572I-59J1575D01*
G02X276634I2015J-1163D01*
G03X277940Y275785I1365J788D01*
G01X278069D01*
G02X280014Y274622I-70J-2325D01*
G03X281335Y273834I1365J787D01*
G01X281464D01*
G02X283669Y271920I-85J-2325D01*
G01X284759Y269560D01*
G01X266290Y272529D02*
X266945Y273184D01*
X267737D01*
X268343Y273229D01*
G03X269723Y274345I-784J2380D01*
G02X270464Y275035I1516J-885D01*
G01X271324D01*
G03X273254Y276197I-85J2325D01*
G02X274560Y276984I1365J-788D01*
G01X274678D01*
G02X275984Y276197I-59J-1575D01*
G03X277914Y275035I2015J1163D01*
G01X278043D01*
G02X279364Y274247I-44J-1575D01*
G03X281309Y273084I2015J1162D01*
G01X281438D01*
G02X282763Y270756I-59J-1575D01*
G01X282744Y270722D01*
X282719Y270680D01*
G03X282798Y268841I1443J-859D01*
G03X284149Y268108I1433J1030D01*
G03X284715Y267986I609J1453D01*
G01X284903D01*
X288139Y267609D01*
G01X253695Y249585D02*
X254681D01*
X261381Y256285D01*
X264836D01*
G03X265687Y257061I-657J1575D01*
G02X267059Y258234I2172J-1152D01*
G01X267903D01*
G03X269224Y259022I-44J1575D01*
G02X271169Y260185I2015J-1162D01*
G01X271298D01*
G03X272604Y260972I-59J1575D01*
G02X274534Y262134I2015J-1163D01*
G01X274765D01*
X277999Y261760D01*
G01X255673Y248007D02*
Y249519D01*
X261689Y255535D01*
X264979D01*
G03X266351Y256708I-800J2325D01*
G02X267202Y257484I1508J-799D01*
G01X267929D01*
G03X269874Y258647I-70J2325D01*
G02X271195Y259435I1365J-787D01*
G01X271324D01*
G03X273254Y260597I-85J2325D01*
G02X274560Y261384I1365J-788D01*
G01X274678D01*
G02X275984Y260597I-59J-1575D01*
G03X276698Y260185I714J413D01*
G01X278069D01*
G02X280014Y259022I-70J-2325D01*
G03X281335Y258234I1365J787D01*
G01X281525D01*
X284759Y257860D01*
G01X263924Y236385D02*
X265069D01*
X265282Y236598D01*
X265844Y237572D01*
G03X265863Y239113I-1365J787D01*
G01X265844Y239147D01*
X265819Y239189D01*
G02X265844Y241472I2040J1119D01*
G03X265863Y243013I-1365J787D01*
G01X265844Y243047D01*
X265819Y243089D01*
G02X267774Y246534I2040J1120D01*
G01X267903D01*
G03X269224Y247322I-44J1575D01*
G02X271169Y248485I2015J-1162D01*
G01X271298D01*
G03X272604Y249272I-59J1575D01*
G02X274534Y250434I2015J-1163D01*
G01X275223D01*
G03X276798Y251087I-1J2228D01*
G01X276855Y251143D01*
G02X279364Y250847I1144J-1083D01*
G01X279430Y250731D01*
X281379Y248109D01*
G01X264964Y233875D02*
Y235222D01*
X265881Y236139D01*
X266492Y237198D01*
X266494Y237197D01*
G03X266519Y239480I-2015J1164D01*
G01X266494Y239522D01*
X266475Y239556D01*
G02X266494Y241097I1384J754D01*
G03X266519Y243380I-2015J1164D01*
G01X266494Y243422D01*
X266475Y243456D01*
G02X267800Y245784I1384J753D01*
G01X267929D01*
G03X269874Y246947I-70J2325D01*
G02X271195Y247735I1365J-787D01*
G01X271324D01*
G03X273254Y248897I-85J2325D01*
G02X274560Y249684I1365J-788D01*
G01X275373D01*
G02X276696Y249136I0J-1871D01*
G01X276928Y248904D01*
G03X277940Y248485I1071J1156D01*
G01X278069D01*
G02X280014Y247322I-70J-2325D01*
G03X281335Y246534I1365J787D01*
G01X281848D01*
X282426Y246817D01*
X283993Y247656D01*
G02X284453Y247735I461J-1304D01*
G01X284803D01*
G02X286124Y246947I-44J-1575D01*
G01X286190Y246831D01*
X288139Y244209D01*
G01X261755Y259280D02*
X261842D01*
X261997Y259435D01*
X264979D01*
G03X266351Y260608I-800J2325D01*
G02X267202Y261384I1508J-799D01*
G01X267929D01*
G03X269874Y262547I-70J2325D01*
G02X271195Y263335I1365J-787D01*
G01X271324D01*
G03X273254Y264497I-85J2325D01*
G02X274560Y265284I1365J-788D01*
G01X274678D01*
G02X275984Y264497I-59J-1575D01*
G03X277914Y263335I2015J1163D01*
G01X278043D01*
G02X279364Y262547I-44J-1575D01*
G03X281309Y261384I2015J1162D01*
G01X281438D01*
G02X282744Y260597I-59J-1575D01*
G03X284674Y259435I2015J1163D01*
G01X284844D01*
G03X286633Y260380I-84J2325D01*
G01X286985Y260475D01*
X288139Y259809D01*
G01X258392Y263180D02*
X258479D01*
X258634Y263335D01*
X264401D01*
G03X266351Y264508I0J2207D01*
G02X267202Y265284I1508J-799D01*
G01X267929D01*
G03X269874Y266447I-70J2325D01*
G02X271195Y267235I1365J-787D01*
G01X271324D01*
G03X273254Y268397I-85J2325D01*
G02X274560Y269184I1365J-788D01*
G01X274678D01*
G02X275984Y268397I-59J-1575D01*
G03X276371Y267793I6585J3793D01*
G01X276888Y267064D01*
X277999Y265660D01*
G01X261755Y260340D02*
X261842D01*
X261997Y260185D01*
X264836D01*
G03X265687Y260961I-657J1575D01*
G02X267059Y262134I2172J-1152D01*
G01X267903D01*
G03X269224Y262922I-44J1575D01*
G02X271169Y264085I2015J-1162D01*
G01X271298D01*
G03X272604Y264872I-59J1575D01*
G02X274534Y266034I2015J-1163D01*
G01X274704D01*
G02X276634Y264872I-85J-2325D01*
G03X277940Y264085I1365J788D01*
G01X278053D01*
G02X280014Y262922I-54J-2325D01*
G03X281335Y262134I1365J787D01*
G01X281464D01*
G02X283394Y260972I-85J-2325D01*
G03X284700Y260185I1365J788D01*
G01X284818D01*
G03X285996Y260784I-60J1575D01*
G01X285913Y261094D01*
X284759Y261760D01*
G01X258392Y264240D02*
X258479D01*
X258634Y264085D01*
X264402D01*
X264401Y264086D01*
G03X265688Y264860I0J1456D01*
G01X265685Y264857D01*
X265687Y264861D01*
G02X267059Y266034I2172J-1152D01*
G01X257793Y308818D02*
X257877Y308796D01*
X258152Y308956D01*
X268305Y306235D01*
X271752D01*
G03X273088Y307410I-860J2325D01*
G02X273909Y308184I1531J-801D01*
G01X274689D01*
G03X276634Y309347I-70J2325D01*
G02X277955Y310135I1365J-787D01*
G01X278084D01*
G03X280014Y311297I-85J2325D01*
G02X281320Y312084I1365J-788D01*
G01X281438D01*
G02X282744Y311297I-59J-1575D01*
G03X284674Y310135I2015J1163D01*
G01X284844D01*
G03X286774Y311297I-85J2325D01*
G02X288080Y312084I1365J-788D01*
G01X288209D01*
G03X290154Y313247I-70J2325D01*
G02X291475Y314035I1365J-787D01*
G01X291604D01*
G03X293534Y315197I-85J2325D01*
G02X296264I1365J-788D01*
G03X300294I2015J1163D01*
G02X301600Y315984I1365J-788D01*
G01X301729D01*
G03X303674Y317147I-70J2325D01*
G02X304995Y317935I1365J-787D01*
G01X305137D01*
G03X307054Y319096I-98J2325D01*
G01X307067Y319119D01*
G02X309783Y319097I1352J-810D01*
G03X313813I2015J1163D01*
G02X316543I1365J-788D01*
G03X318473Y317935I2015J1163D01*
G01X318643D01*
G03X320573Y319097I-85J2325D01*
G02X321879Y319884I1365J-788D01*
G01X322008D01*
G03X323953Y321047I-70J2325D01*
G02X325274Y321835I1365J-787D01*
G01X325403D01*
G03X327333Y322997I-85J2325D01*
G02X328639Y323784I1365J-788D01*
G01X328749D01*
G03X330713Y327273I-51J2326D01*
G02X332034Y329635I1365J787D01*
G01X332163D01*
G03X334093Y330797I-85J2325D01*
G02X335399Y331584I1365J-788D01*
G01X335528D01*
G03X337473Y332747I-70J2325D01*
G02X338794Y333535I1365J-787D01*
G01X338923D01*
G03X340853Y334697I-85J2325D01*
G02X342159Y335484I1365J-788D01*
G01X342288D01*
G03X344233Y336647I-70J2325D01*
G02X345554Y337435I1365J-787D01*
G01X345683D01*
G03X347613Y338597I-85J2325D01*
G02X348919Y339384I1365J-788D01*
G01X349048D01*
G03X350993Y340547I-70J2325D01*
G01X351006Y340570D01*
G02X352357Y341335I1351J-810D01*
G01X352494D01*
X355736Y341710D01*
X355737Y341709D01*
G01X258103Y309978D02*
X258187Y309956D01*
X258345Y309682D01*
X268404Y306985D01*
X271602D01*
G03X272423Y307759I-710J1575D01*
G02X273759Y308934I2196J-1150D01*
G01X274663D01*
G03X275984Y309722I-44J1575D01*
G02X277929Y310885I2015J-1162D01*
G01X278058D01*
G03X279364Y311672I-59J1575D01*
G02X281294Y312834I2015J-1163D01*
G01X281464D01*
G02X283394Y311672I-85J-2325D01*
G03X284700Y310885I1365J788D01*
G01X284818D01*
G03X286124Y311672I-59J1575D01*
G02X288054Y312834I2015J-1163D01*
G01X288183D01*
G03X289504Y313622I-44J1575D01*
G02X291449Y314785I2015J-1162D01*
G01X291578D01*
G03X292884Y315572I-59J1575D01*
G02X296914I2015J-1163D01*
G03X299644I1365J788D01*
G02X301574Y316734I2015J-1163D01*
G01X301703D01*
G03X303024Y317522I-44J1575D01*
G02X304969Y318685I2015J-1162D01*
G01X305039D01*
G03X306390Y319450I0J1575D01*
G01X306403Y319473D01*
G02X308320Y320634I2015J-1164D01*
G01X308503D01*
G02X310433Y319472I-85J-2325D01*
G03X313163I1365J788D01*
G02X317193I2015J-1163D01*
G03X318499Y318685I1365J788D01*
G01X318617D01*
G03X319923Y319472I-59J1575D01*
G02X321853Y320634I2015J-1163D01*
G01X321982D01*
G03X323303Y321422I-44J1575D01*
G02X325248Y322585I2015J-1162D01*
G01X325377D01*
G03X326683Y323372I-59J1575D01*
G02X328647Y324535I2015J-1163D01*
G01X328742D01*
G03X330063Y326897I-44J1575D01*
G02X332008Y330385I2015J1163D01*
G01X332137D01*
G03X333443Y331172I-59J1575D01*
G02X335373Y332334I2015J-1163D01*
G01X335502D01*
G03X336823Y333122I-44J1575D01*
G02X338768Y334285I2015J-1162D01*
G01X338897D01*
G03X340203Y335072I-59J1575D01*
G02X342133Y336234I2015J-1163D01*
G01X342262D01*
G03X343583Y337022I-44J1575D01*
G02X345528Y338185I2015J-1162D01*
G01X345657D01*
G03X346963Y338972I-59J1575D01*
G02X348893Y340134I2015J-1163D01*
G01X348978D01*
G03X350329Y340899I0J1575D01*
G01X350342Y340922D01*
G02X352287Y342085I2015J-1162D01*
G01X352416D01*
G03X353722Y342872I-59J1575D01*
G02X355509Y343904I1787J-1032D01*
G01X356251D01*
X356882Y344535D01*
G03X357102Y344822I-976J976D01*
G01X357168Y344938D01*
X359117Y347560D01*
G01X259088Y327380D02*
X259949Y328241D01*
X260548D01*
X263052Y325737D01*
X265274D01*
X265922Y326385D01*
X266799Y327394D01*
G02X267200Y327684I821J-714D01*
G01X267930D01*
G02X269224Y326897I-71J-1574D01*
G03X271154Y325735I2015J1163D01*
G01X271283D01*
G02X272604Y324947I-44J-1575D01*
G03X276634I2015J1163D01*
G02X277955Y325735I1365J-787D01*
G01X278084D01*
G03X280014Y326897I-85J2325D01*
G02X281308Y327684I1365J-787D01*
G01X281449D01*
G03X283394Y328847I-70J2325D01*
G02X284715Y329635I1365J-787D01*
G01X284844D01*
G03X286774Y330797I-85J2325D01*
G01X286840Y330910D01*
X288139Y333909D01*
G01X259208Y329880D02*
X260099Y328989D01*
X260858D01*
X263362Y326485D01*
X264954D01*
X265259Y326790D01*
X265687Y327261D01*
G02X267061Y328435I2172J-1151D01*
G01X267944D01*
G02X269874Y327273I-85J-2325D01*
G03X271195Y326485I1365J787D01*
G01X271324D01*
G02X273254Y325323I-85J-2325D01*
G03X275984I1365J787D01*
G02X277914Y326485I2015J-1163D01*
G01X278043D01*
G03X279364Y327273I-44J1575D01*
G01X279429Y327387D01*
X281379Y330009D01*
G01X252358Y348100D02*
X253333D01*
X254392Y347041D01*
X260848D01*
X262654Y345235D01*
X264523D01*
G02X265844Y344447I-44J-1575D01*
G03X267789Y343284I2015J1162D01*
G01X267918D01*
G02X269224Y342497I-59J-1575D01*
G03X271154Y341335I2015J1163D01*
G01X271283D01*
G02X272604Y340547I-44J-1575D01*
G03X274549Y339384I2015J1162D01*
G01X274678D01*
G02X275984Y338597I-59J-1575D01*
G03X277914Y337435I2015J1163D01*
G01X278084D01*
G03X280014Y338597I-85J2325D01*
G01X280080Y338710D01*
X281379Y341709D01*
G01X288139Y330009D02*
X286839Y327009D01*
X286774Y326897D01*
G02X284844Y325735I-2015J1163D01*
G01X284715D01*
G03X283394Y324947I44J-1575D01*
G02X281430Y323784I-2015J1163D01*
G01X281320D01*
G03X280014Y322997I59J-1575D01*
G02X278084Y321835I-2015J1163D01*
G01X277955D01*
G03X276634Y321047I44J-1575D01*
G02X274689Y319884I-2015J1162D01*
G01X274549D01*
G02X272604Y321047I70J2325D01*
G03X271283Y321835I-1365J-787D01*
G01X271154D01*
G02X269224Y322997I85J2325D01*
G03X267918Y323784I-1365J-788D01*
G01X266891D01*
X265788Y322681D01*
X260719D01*
X259818Y321780D01*
G01X284759Y328060D02*
X282809Y325436D01*
X282744Y325323D01*
G02X281423Y324535I-1365J787D01*
G01X281328D01*
G03X279364Y323372I51J-2326D01*
G02X278058Y322585I-1365J788D01*
G01X277929D01*
G03X275984Y321422I70J-2325D01*
G02X273254I-1365J787D01*
G03X271309Y322585I-2015J-1162D01*
G01X271180D01*
G02X269874Y323372I59J1575D01*
G03X267931Y324534I-2015J-1163D01*
G01X266580D01*
X265475Y323429D01*
X260669D01*
X259818Y324280D01*
G01X284759Y339760D02*
X282810Y337138D01*
X282744Y337022D01*
G02X281423Y336234I-1365J787D01*
G01X281294D01*
G03X279364Y335072I85J-2325D01*
G02X278058Y334285I-1365J788D01*
G01X276698D01*
G02X275984Y334697I0J825D01*
G03X274678Y335484I-1365J-788D01*
G01X274549D01*
G02X272604Y336647I70J2325D01*
G03X271283Y337435I-1365J-787D01*
G01X271154D01*
G02X269224Y338597I85J2325D01*
G03X267918Y339384I-1365J-788D01*
G01X267789D01*
G02X265844Y340547I70J2325D01*
G03X264523Y341335I-1365J-787D01*
G01X263154D01*
X262748Y341741D01*
X256248D01*
X255448Y340941D01*
G01Y343441D02*
X256400Y342489D01*
X263061D01*
X263465Y342085D01*
X264549D01*
G02X266494Y340922I-70J-2325D01*
G03X267815Y340134I1365J787D01*
G01X267944D01*
G02X269874Y338972I-85J-2325D01*
G03X271180Y338185I1365J788D01*
G01X271309D01*
G02X273254Y337022I-70J-2325D01*
G03X274575Y336234I1365J787D01*
G01X274765D01*
X277999Y335860D01*
G01X255384Y336929D02*
X255471D01*
X255626Y337084D01*
X260791D01*
X261142Y337435D01*
X264536D01*
G02X265844Y336647I-57J-1575D01*
G03X267789Y335484I2015J1162D01*
G01X267918D01*
G02X269224Y334697I-59J-1575D01*
G03X271154Y333535I2015J1163D01*
G01X271283D01*
G02X272604Y332747I-44J-1575D01*
G03X274549Y331584I2015J1162D01*
G01X275817D01*
X277999Y331960D01*
G01X260505Y333980D02*
X260592D01*
X260747Y333825D01*
X262271D01*
X262731Y334285D01*
X264977D01*
G02X266351Y333111I-798J-2325D01*
G01X266438Y333024D01*
Y332965D01*
G03X267204Y332334I1421J944D01*
G01X267944D01*
G02X269874Y331172I-85J-2325D01*
G03X271180Y330385I1365J788D01*
G01X271309D01*
G02X273254Y329222I-70J-2325D01*
G03X274548Y328435I1365J787D01*
G01X274690D01*
G03X275984Y329222I-71J1574D01*
G02X277929Y330385I2015J-1162D01*
G01X278058D01*
G03X279364Y331172I-59J1575D01*
G02X281294Y332334I2015J-1163D01*
G01X281423D01*
G03X282744Y333122I-44J1575D01*
G02X284689Y334285I2015J-1162D01*
G01X284818D01*
G03X286223Y336441I-60J1575D01*
G01X285913Y336525D01*
X284759Y335860D01*
G01X255384Y337989D02*
X255471D01*
X255626Y337834D01*
X260480D01*
X260831Y338185D01*
X264563D01*
G02X266494Y337022I-84J-2325D01*
G03X267802Y336234I1365J787D01*
G01X267944D01*
G02X269874Y335072I-85J-2325D01*
G03X271180Y334285I1365J788D01*
G01X271309D01*
G02X273254Y333122I-70J-2325D01*
G03X274575Y332334I1365J787D01*
G01X275438D01*
X277580Y333529D01*
X279103Y333548D01*
X281379Y333909D01*
G01X260505Y332920D02*
X260592D01*
X260747Y333075D01*
X262582D01*
X263042Y333535D01*
X264840D01*
G02X265688Y332760I-661J-1575D01*
G01Y332759D01*
X265687Y332758D01*
G03X265811Y332549I2174J1148D01*
G03X267061Y331584I2048J1360D01*
G01X267918D01*
G02X269224Y330797I-59J-1575D01*
G03X271154Y329635I2015J1163D01*
G01X271283D01*
G02X272604Y328847I-44J-1575D01*
G03X274549Y327684I2015J1162D01*
G01X274689D01*
G03X276634Y328847I-70J2325D01*
G02X277955Y329635I1365J-787D01*
G01X278084D01*
G03X280014Y330797I-85J2325D01*
G02X281320Y331584I1365J-788D01*
G01X281449D01*
G03X283394Y332747I-70J2325D01*
G02X284715Y333535I1365J-787D01*
G01X284844D01*
G03X286891Y336793I-85J2325D01*
G01X286985Y337144D01*
X288139Y337809D01*
G01X260813Y317525D02*
X260900D01*
X260975Y317450D01*
X263265D01*
X266280Y314435D01*
X270920D01*
G03X272242Y315030I19J1725D01*
G01X272440Y315446D01*
G02X273972Y316734I2179J-1037D01*
G01X274704D01*
G02X276634Y315572I-85J-2325D01*
G03X277940Y314785I1365J788D01*
G01X278058D01*
G03X279364Y315572I-59J1575D01*
G02X281294Y316734I2015J-1163D01*
G01X281423D01*
G03X282744Y317522I-44J1575D01*
G02X284689Y318685I2015J-1162D01*
G01X284818D01*
G03X286124Y319472I-59J1575D01*
G02X288054Y320634I2015J-1163D01*
G01X288183D01*
G03X289504Y321422I-44J1575D01*
G02X291449Y322585I2015J-1162D01*
G01X291578D01*
G03X292884Y323372I-59J1575D01*
G02X294812Y324534I2015J-1163D01*
G02X294986I87J-2325D01*
G02X296914Y323372I-87J-2325D01*
G03X298051Y322601I1365J789D01*
G01X298279Y322829D01*
Y324160D01*
G01X260813Y316625D02*
X260900D01*
X260975Y316700D01*
X262954D01*
X265969Y313685D01*
X270911D01*
G03X272881Y314625I28J2475D01*
G01X273118Y315123D01*
G02X274088Y315984I1501J-714D01*
G01X274678D01*
G02X275984Y315197I-59J-1575D01*
G03X277914Y314035I2015J1163D01*
G01X278084D01*
G03X280014Y315197I-85J2325D01*
G02X281320Y315984I1365J-788D01*
G01X281449D01*
G03X283394Y317147I-70J2325D01*
G02X284715Y317935I1365J-787D01*
G01X284844D01*
G03X286774Y319097I-85J2325D01*
G02X288080Y319884I1365J-788D01*
G01X288209D01*
G03X290154Y321047I-70J2325D01*
G02X291475Y321835I1365J-787D01*
G01X291604D01*
G03X293534Y322997I-85J2325D01*
G02X294840Y323784I1365J-788D01*
G01X294958D01*
G02X296264Y322997I-59J-1575D01*
G03X298023Y321847I2015J1162D01*
G01X298279Y321591D01*
Y320260D01*
G01X255287Y356741D02*
X256648D01*
X261248Y352141D01*
Y350780D01*
X262893Y349135D01*
X264523D01*
G02X265844Y348347I-44J-1575D01*
G03X267789Y347184I2015J1162D01*
G01X267918D01*
G02X269224Y346397I-59J-1575D01*
G03X271154Y345235I2015J1163D01*
G01X271283D01*
G02X272604Y344447I-44J-1575D01*
G03X274549Y343284I2015J1162D01*
G01X274678D01*
G02X275984Y342497I-59J-1575D01*
G03X277914Y341335I2015J1163D01*
G01X278084D01*
G03X280014Y342497I-85J2325D01*
G02X281320Y343284I1365J-788D01*
G01X281449D01*
G03X283394Y344447I-70J2325D01*
G02X284715Y345235I1365J-787D01*
G01X284844D01*
G03X286774Y346397I-85J2325D01*
G01X288139Y349509D01*
G01X256948Y358616D02*
Y357499D01*
X261996Y352451D01*
Y351090D01*
X263201Y349885D01*
X264549D01*
G02X266494Y348722I-70J-2325D01*
G03X267815Y347934I1365J787D01*
G01X267944D01*
G02X269874Y346772I-85J-2325D01*
G03X271180Y345985I1365J788D01*
G01X271309D01*
G02X273254Y344822I-70J-2325D01*
G03X274575Y344034I1365J787D01*
G01X274704D01*
G02X276634Y342872I-85J-2325D01*
G03X277940Y342085I1365J788D01*
G01X278058D01*
G03X279364Y342872I-59J1575D01*
G02X281294Y344034I2015J-1163D01*
G01X281423D01*
G03X282744Y344822I-44J1575D01*
G02X283228Y345411I2015J-1162D01*
G01X284759Y347560D01*
G01X277999Y339760D02*
X274765Y340134D01*
X274575D01*
G02X273254Y340922I44J1575D01*
G03X271309Y342085I-2015J-1162D01*
G01X271180D01*
G02X269874Y342872I59J1575D01*
G03X267944Y344034I-2015J-1163D01*
G01X267815D01*
G02X266494Y344822I44J1575D01*
G03X264533Y345985I-2015J-1162D01*
G01X262962D01*
X261158Y347789D01*
X254804D01*
X253792Y348801D01*
Y349333D01*
X253108Y350017D01*
G01X258459Y360641D02*
X259948D01*
X262348Y358241D01*
X264848D01*
X266086Y357003D01*
Y355307D01*
X265687Y354561D01*
G03X267061Y351084I2172J-1152D01*
G01X267918D01*
G02X269224Y350297I-59J-1575D01*
G03X271154Y349135I2015J1163D01*
G01X271283D01*
G02X272604Y348347I-44J-1575D01*
G03X274549Y347184I2015J1162D01*
G01X274678D01*
G02X275984Y346397I-59J-1575D01*
G03X277914Y345235I2015J1163D01*
G01X278084D01*
G03X280014Y346397I-85J2325D01*
G02X281320Y347184I1365J-788D01*
G01X281379D01*
G03X282096Y347598I0J828D01*
G01X282744Y348722D01*
G02X284689Y349885I2015J-1162D01*
G01X284818D01*
G03X286124Y350672I-59J1575D01*
G01X286190Y350788D01*
X288139Y353409D01*
G01X277999Y238360D02*
X279153Y237694D01*
X279247Y237342D01*
G03X279339Y235289I2131J-933D01*
G01X279364Y235247D01*
X279383Y235213D01*
G02X279364Y233672I-1384J-754D01*
G03Y231346I2015J-1163D01*
G02Y229772I-1365J-787D01*
G01X279339Y229730D01*
G03X279364Y227447I2040J-1119D01*
G01X279383Y227413D01*
G02X279364Y225872I-1384J-754D01*
G03X279339Y223589I2015J-1164D01*
G01X279364Y223547D01*
X279383Y223513D01*
G02X279364Y221972I-1384J-754D01*
G03X279339Y219689I2015J-1164D01*
G01X279364Y219647D01*
X279383Y219613D01*
G02X278058Y217285I-1384J-753D01*
G01X277929D01*
G03X276279Y216525I71J-2325D01*
G03X276078Y216005I572J-520D01*
G01Y215951D01*
G02X275887Y215490I-652J0D01*
G01X275397Y215000D01*
G01X279799Y215372D02*
Y216900D01*
X279800Y217138D01*
X279844Y217444D01*
G03X280039Y219980I-1845J1417D01*
G01X280014Y220022D01*
X279995Y220056D01*
G02X280014Y221597I1384J754D01*
G03X280039Y223880I-2015J1164D01*
G01X280014Y223922D01*
X279995Y223956D01*
G02X280014Y225497I1384J754D01*
G03Y227823I-2015J1163D01*
G02Y229397I1365J787D01*
G01X280039Y229439D01*
G03X280014Y231722I-2040J1119D01*
G01X279995Y231756D01*
G02X280014Y233297I1384J754D01*
G03X280039Y235580I-2015J1164D01*
G01X280014Y235622D01*
X279995Y235656D01*
G02X279915Y236991I1385J753D01*
G01X280225Y237075D01*
X281379Y236409D01*
G01X277999Y242260D02*
Y242259D01*
G03X275984Y239522I11254J-10395D01*
G03Y237196I2015J-1163D01*
G02Y235622I-1365J-787D01*
G03Y233296I2015J-1163D01*
G02Y231722I-1365J-787D01*
G03Y229396I2015J-1163D01*
G02Y227822I-1365J-787D01*
G03Y225496I2015J-1163D01*
G02Y223922I-1365J-787D01*
G03Y221596I2015J-1163D01*
G02X276111Y221315I-1373J-790D01*
G02X276003Y220056I-1492J-506D01*
G01X275984Y220022D01*
G02X275856Y219834I-1127J630D01*
G02X274663Y219234I-1238J975D01*
G01X273485D01*
X272608Y220111D01*
G01X284759Y238360D02*
Y238359D01*
X280876D01*
X279301Y239934D01*
X277955D01*
G03X276634Y237572I44J-1575D01*
G02Y235246I-2015J-1163D01*
G03Y233672I1365J-787D01*
G02Y231346I-2015J-1163D01*
G03Y229772I1365J-787D01*
G02Y227446I-2015J-1163D01*
G03Y225872I1365J-787D01*
G02Y223546I-2015J-1163D01*
G03Y221972I1365J-787D01*
G02X276659Y219689I-2015J-1164D01*
G01X276634Y219647D01*
G02X276493Y219430I-2830J1684D01*
G02X274689Y218484I-1873J1379D01*
G01X273481D01*
X272608Y217611D01*
G01X284759Y203260D02*
X281515Y202884D01*
X281320D01*
G03X280429Y202566I60J-1575D01*
G02X278548Y201686I-3004J3970D01*
G01X277929D01*
G03X275984Y200523I70J-2325D01*
G01X275433Y199570D01*
X269614Y193751D01*
X269613D01*
X269612Y193752D01*
X268019D01*
X262123Y187856D01*
X260786D01*
G01X262544Y186099D02*
Y187217D01*
X268330Y193003D01*
X269924D01*
X276032Y199110D01*
X276634Y200147D01*
G02X277940Y200935I1365J-786D01*
G01X278348D01*
X280439Y200045D01*
G03X281320Y199735I940J1264D01*
G01X281438D01*
G03X282744Y200523I-59J1574D01*
G02X284689Y201686I2015J-1162D01*
G01X284840D01*
G03X286124Y202472I-81J1574D01*
G03X286143Y204013I-1365J787D01*
G01X286124Y204047D01*
X285953Y204344D01*
X285711Y204533D01*
X283800Y205909D01*
G02X283394Y206372I959J1250D01*
G02Y207946I1365J787D01*
G01X283460Y208060D01*
X284759Y211060D01*
G01X294899Y205210D02*
Y206541D01*
X295127Y206769D01*
G02X296264Y204423I-228J-1559D01*
G03Y202097I2015J-1163D01*
G02X296283Y200556I-1365J-787D01*
G01X296264Y200522D01*
X296239Y200480D01*
G03X296264Y198197I2040J-1119D01*
G01X296508Y197737D01*
Y195741D01*
X285159Y184392D01*
X283417D01*
G01X285119Y182551D02*
Y183292D01*
X297258Y195431D01*
Y198050D01*
X296965Y198492D01*
G02X296895Y200113I1311J869D01*
G01X296914Y200147D01*
X296939Y200189D01*
G03X296914Y202472I-2040J1119D01*
G02X296895Y204013I1365J787D01*
G01X296914Y204047D01*
G03X295155Y207522I-2015J1163D01*
G01X294899Y207778D01*
Y209109D01*
G01X281379Y205210D02*
X279932Y205437D01*
X278651Y205585D01*
X277914D01*
G03X275984Y204423I85J-2325D01*
G02X274663Y203635I-1365J787D01*
G01X274568D01*
G03X272604Y202472I51J-2326D01*
G01X272606Y202471D01*
X271852Y201164D01*
X267797Y197109D01*
X263136D01*
X257683Y191656D01*
X256447D01*
X255292Y190501D01*
G01X258209Y188367D02*
Y191122D01*
X259116Y192029D01*
G01X291519Y203260D02*
X292850D01*
X293078Y203032D01*
G02X292990Y202694I-1560J226D01*
G02X292884Y202472I-1445J554D01*
G03X292859Y200189I2015J-1164D01*
G01X292884Y200147D01*
X292903Y200113D01*
G02X292884Y198572I-1384J-754D01*
G01X292498Y197904D01*
Y196020D01*
X286119Y189641D01*
X283208D01*
X281525Y187958D01*
X279911D01*
G01X281634Y186145D02*
Y187006D01*
X283519Y188891D01*
X286430D01*
X293248Y195709D01*
Y197704D01*
X293534Y198197D01*
G03X293559Y200480I-2015J1164D01*
G01X293534Y200522D01*
X293515Y200556D01*
G02X293534Y202097I1384J754D01*
G03Y204423I-2015J1163D01*
G01Y204424D01*
G02X293071Y206891I3278J1892D01*
G03X292884Y207948I-1552J270D01*
G01X291519Y211060D01*
G01X260284Y223607D02*
X260346Y223669D01*
Y223887D01*
X262058Y225599D01*
Y227206D01*
X263045Y228193D01*
X263661D01*
X268852Y233384D01*
X269873Y235191D01*
G03X269872Y237575I-2014J1191D01*
G02X269874Y239147I1367J784D01*
G03Y241471I-2015J1162D01*
G02X271170Y243834I1365J788D01*
G01X271283D01*
G03X273258Y245004I0J2252D01*
G02X274550Y245784I1361J-795D01*
G01X274673D01*
G03X275555Y245980I-54J2325D01*
G03X275952Y246202I-931J2131D01*
G01Y246203D01*
G03X276430Y246401I-552666J1334890D01*
G01X276777Y246545D01*
X277999Y246160D01*
G01X288139Y201309D02*
X287086Y199341D01*
G02X286774Y198197I-2326J20D01*
G01X286370Y197500D01*
X284321Y195451D01*
X276879D01*
X269026Y187598D01*
Y187378D01*
X268964Y187316D01*
G01X272703Y230644D02*
Y230731D01*
X272548Y230886D01*
Y232217D01*
X273044Y232713D01*
Y236834D01*
X273254Y237196D01*
G03Y239521I-2015J1162D01*
G02X274550Y241884I1365J788D01*
G01X274673D01*
G03X276634Y243047I-54J2325D01*
G02X277996Y243834I1362J-785D01*
G01X278002D01*
G02X279364Y243047I0J-1572D01*
G03X281325Y241884I2015J1162D01*
G01X281448D01*
G02X282744Y241097I-69J-1575D01*
G03X284687Y239935I2015J1163D01*
G01X284831D01*
G03X286633Y240880I-71J2326D01*
G01X286985Y240975D01*
X288139Y240309D01*
G01Y213009D02*
Y211678D01*
X288395Y211422D01*
G02X290154Y207946I-256J-2313D01*
G03Y206372I1365J-787D01*
G01X290179Y206330D01*
G02X290154Y204047I-2040J-1119D01*
G01X290135Y204013D01*
G03X290154Y202472I1384J-754D01*
G02X290179Y200189I-2015J-1164D01*
G01X289779Y199497D01*
Y196508D01*
X285531Y192260D01*
X280350D01*
X273581Y185491D01*
Y185271D01*
X273519Y185209D01*
G01X259534Y224357D02*
X259596Y224419D01*
X259816D01*
X261308Y225911D01*
Y227517D01*
X262734Y228943D01*
X263350D01*
X268249Y233842D01*
X269224Y235567D01*
G03Y237196I-1365J815D01*
G02Y239522I2015J1163D01*
G03Y241096I-1365J787D01*
G02X271154Y244584I2015J1163D01*
G01X271283D01*
G03X272604Y245372I0J1501D01*
G02X274534Y246534I2015J-1163D01*
G01X274663D01*
G03X275253Y246667I-45J1575D01*
G03X275582Y246862I-633J1443D01*
G03X277394Y247614I-552605J1334103D01*
G02X279364Y246946I605J-1455D01*
G03X281379Y244209I13218J7621D01*
G01X288139Y205210D02*
X287448Y203141D01*
X286774Y202097D01*
G03X286248Y200841I4657J-2688D01*
G03X286223Y199941I1812J-501D01*
G02X286334Y199347I-1466J-581D01*
G02X286124Y198573I-1577J12D01*
G01X285770Y197961D01*
X284010Y196201D01*
X276568D01*
X268494Y188127D01*
X268275D01*
X268213Y188065D01*
G01X271643Y230644D02*
Y230731D01*
X271798Y230886D01*
Y232528D01*
X272294Y233024D01*
Y237036D01*
X272604Y237572D01*
G03Y239146I-1365J787D01*
G02X274534Y242634I2015J1163D01*
G01X274663D01*
G03X275984Y243422I-44J1575D01*
G02X277995Y244584I2011J-1160D01*
G01X278001D01*
G02X280014Y243422I2J-2322D01*
G03X281335Y242634I1365J787D01*
G01X281464D01*
G02X283394Y241472I-85J-2325D01*
G03X284700Y240685I1365J788D01*
G01X284818D01*
G03X285996Y241284I-60J1575D01*
G01X285913Y241594D01*
X284759Y242260D01*
G01X288139Y209109D02*
Y210440D01*
X288367Y210668D01*
G02X289523Y208356I-228J-1559D01*
G01X289504Y208322D01*
G03X289479Y206039I2015J-1164D01*
G01X289504Y205997D01*
G02Y204423I-1365J-787D01*
G03Y202097I2015J-1163D01*
G02X289523Y200556I-1365J-787D01*
G01X289029Y199699D01*
Y196819D01*
X285220Y193010D01*
X280039D01*
X273050Y186021D01*
X272831D01*
X272769Y185959D01*
G01X260192Y362444D02*
Y361455D01*
X262658Y358989D01*
X265158D01*
X266834Y357313D01*
Y355119D01*
X266351Y354208D01*
G03X267204Y351834I1508J-799D01*
G01X267944D01*
G02X269874Y350672I-85J-2325D01*
G03X271180Y349885I1365J788D01*
G01X271309D01*
G02X273254Y348722I-70J-2325D01*
G03X274575Y347934I1365J787D01*
G01X274704D01*
G02X276634Y346772I-85J-2325D01*
G03X277940Y345985I1365J788D01*
G01X278058D01*
G03X279364Y346772I-59J1575D01*
G01X279430Y346888D01*
X281379Y349509D01*
G01X262404Y365426D02*
X262466Y365364D01*
Y365144D01*
X263768Y363841D01*
X268548D01*
X270184Y362205D01*
Y356577D01*
X269568Y355961D01*
Y355105D01*
X269874Y354572D01*
G03X271170Y353785I1365J788D01*
G01X271309D01*
G02X273254Y352622I-70J-2325D01*
G03X274575Y351834I1365J787D01*
G01X274704D01*
G02X276634Y350672I-85J-2325D01*
G03X277940Y349885I1365J788D01*
G01X278058D01*
G03X279364Y350672I-59J1575D01*
G02X281294Y351834I2015J-1163D01*
G01X281423D01*
G03X282744Y352622I-44J1575D01*
G02X284689Y353785I2015J-1162D01*
G01X284818D01*
G03X286223Y355941I-60J1575D01*
G01X285913Y356025D01*
X284759Y355360D01*
G01X288139Y357309D02*
X286985Y356644D01*
X286891Y356293D01*
G02X284844Y353035I-2132J-933D01*
G01X284715D01*
G03X283394Y352247I44J-1575D01*
G02X281449Y351084I-2015J1162D01*
G01X281320D01*
G03X280014Y350297I59J-1575D01*
G02X278084Y349135I-2015J1163D01*
G01X277914D01*
G02X275984Y350297I85J2325D01*
G03X274678Y351084I-1365J-788D01*
G01X274549D01*
G02X272604Y352247I70J2325D01*
G03X271283Y353035I-1365J-787D01*
G01X271154D01*
G02X269224Y354197I85J2325D01*
G01X269223Y354199D01*
X268818Y354905D01*
Y356272D01*
X269434Y356888D01*
Y361894D01*
X268237Y363091D01*
X263457D01*
X261937Y364612D01*
X261715D01*
X261653Y364674D01*
G01X279364Y361550D02*
G02Y362372I712J411D01*
G03X279383Y363913I-1365J787D01*
G01X279364Y363947D01*
X279339Y363989D01*
G02X279364Y366272I2040J1119D01*
G03X279383Y367813I-1365J787D01*
G01X279364Y367847D01*
G02X279339Y370130I2015J1164D01*
G01X279364Y370172D01*
G03X278043Y372534I-1365J787D01*
G01X277948D01*
G02X275984Y373697I51J2326D01*
G03X274678Y374484I-1365J-788D01*
G01X270405D01*
X264016Y380873D01*
X263179D01*
G01X281379Y361209D02*
X280082Y364205D01*
X279995Y364356D01*
G02X280014Y365897I1384J754D01*
G03Y368223I-2015J1163D01*
G02Y369797I1365J787D01*
G01X280039Y369839D01*
G03X278050Y373285I-2040J1120D01*
G01X277940D01*
G02X276634Y374072I59J1575D01*
G03X274704Y375234I-2015J-1163D01*
G01X270713D01*
X264958Y380989D01*
Y382652D01*
G01X277999Y355360D02*
X276700Y358359D01*
X276634Y358472D01*
G02X276550Y359880I1365J788D01*
G03X276485Y361129I-1305J558D01*
G01X275984Y361997D01*
G02X275959Y364280I2015J1164D01*
G01X275984Y364322D01*
X276003Y364356D01*
G03X274678Y366684I-1384J753D01*
G01X273606D01*
X268149Y372141D01*
X266148D01*
X258648Y379641D01*
X257339D01*
G01X277999Y359260D02*
G03X277135Y361504I-7568J-1626D01*
G01X276634Y362372D01*
G02X276615Y363913I1365J787D01*
G01X276634Y363947D01*
X276659Y363989D01*
G03X274670Y367435I-2040J1120D01*
G01X273917D01*
X272833Y368519D01*
X272829D01*
X268459Y372889D01*
X266458D01*
X259048Y380299D01*
Y381468D01*
G01X284759Y386560D02*
X282810Y389181D01*
X282744Y389297D01*
G02Y391623I2015J1163D01*
G03X281450Y393984I-1365J787D01*
G01X281294D01*
G02X279364Y395146I85J2325D01*
G03X278043Y395934I-1365J-787D01*
G01X277948D01*
G02X275984Y397097I51J2326D01*
G03X274678Y397884I-1365J-788D01*
G01X274549D01*
G02X272604Y399047I70J2325D01*
G01X272429Y399350D01*
X268544Y403235D01*
X266925D01*
G01X281379Y388509D02*
X279429Y391134D01*
X279364Y391247D01*
G03X278070Y392034I-1365J-787D01*
G01X277929D01*
G02X275984Y393197I70J2325D01*
G03X274690Y393984I-1365J-787D01*
G01X274534D01*
G02X272604Y395146I85J2325D01*
G03X271283Y395934I-1365J-787D01*
G01X266255D01*
X263545Y398644D01*
X262350D01*
G01X281379Y392410D02*
X278143Y392785D01*
X277928D01*
G02X276634Y393572I71J1574D01*
G03X274689Y394735I-2015J-1162D01*
G01X274548D01*
G02X273254Y395522I71J1574D01*
G03X271290Y396685I-2015J-1163D01*
G01X266567D01*
X264218Y399034D01*
Y400312D01*
G01X277999Y351460D02*
X279153Y352125D01*
X279236Y352435D01*
G03X278043Y353035I-1238J-975D01*
G01X277914D01*
G02X275984Y354197I85J2325D01*
G03X274678Y354984I-1365J-788D01*
G01X274549D01*
G02X272604Y356147I70J2325D01*
G01X272294Y356685D01*
Y363434D01*
X269937Y365791D01*
X266146D01*
X260281Y371656D01*
X260059D01*
X259997Y371718D01*
G01X260747Y372469D02*
X260809Y372407D01*
Y372189D01*
X266457Y366541D01*
X270248D01*
X273044Y363745D01*
Y356886D01*
X273254Y356522D01*
G03X274575Y355734I1365J787D01*
G01X274704D01*
G02X276634Y354572I-85J-2325D01*
G03X277940Y353785I1365J788D01*
G01X278069D01*
G02X279873Y352839I-69J-2325D01*
G01X280225Y352744D01*
X281379Y353409D01*
G01X284759Y394359D02*
X281521Y394735D01*
X281308D01*
G02X280014Y395522I71J1574D01*
G03X278050Y396685I-2015J-1163D01*
G01X277940D01*
G02X276634Y397472I59J1575D01*
G03X274704Y398634I-2015J-1163D01*
G01X274577D01*
X274575Y398632D01*
X274562D01*
G02X273252Y399421I57J1577D01*
G01X273028Y399809D01*
X268748Y404089D01*
Y404948D01*
G01X294899Y388509D02*
X292949Y391134D01*
X292884Y391247D01*
G02X294829Y394735I2015J1163D01*
G01X294970D01*
G03X296264Y397097I-71J1574D01*
G02X296239Y399380I2015J1164D01*
G01X296305Y399492D01*
X296796Y400370D01*
Y403393D01*
X294807Y405382D01*
X293707D01*
G01X291519Y386560D02*
X290220Y389559D01*
X290154Y389672D01*
G02X290135Y391213I1365J787D01*
G01X290154Y391247D01*
G03X290179Y393530I-2015J1164D01*
G01X290154Y393572D01*
G02X290943Y395826I1365J787D01*
G03X292884Y397472I-1439J3664D01*
G03X292903Y399013I-1365J787D01*
G01X292701Y399374D01*
X289532Y402543D01*
X286546D01*
X282205Y406884D01*
Y407954D01*
X281958Y408201D01*
X280998D01*
G01X291519Y394359D02*
G02X292778Y396021I11539J-7434D01*
G03X293468Y396982I-4364J3861D01*
G01X293534Y397097D01*
G03X293559Y399380I-2015J1164D01*
G01X293492Y399493D01*
X293303Y399831D01*
X289843Y403291D01*
X286856D01*
X282953Y407194D01*
Y409796D01*
G01X288139Y388509D02*
Y387178D01*
X287911Y386950D01*
G02X286774Y389297I228J1559D01*
G03Y391623I-2015J1163D01*
G02Y393197I1365J787D01*
G01X286799Y393239D01*
G03X284810Y396685I-2040J1120D01*
G01X284700D01*
G02X283394Y397472I59J1575D01*
G03X281464Y398634I-2015J-1163D01*
G01X281335D01*
G02X280015Y399420I44J1575D01*
G01X279638Y400072D01*
X276100Y403610D01*
X275117D01*
X269723Y409004D01*
X269724Y409222D01*
X269663Y409283D01*
G01X288139Y396309D02*
G03X287610Y397944I-2791J0D01*
G02X286124Y399047I529J2265D01*
G03X284830Y399834I-1365J-787D01*
G01X284661D01*
G02X282744Y400996I98J2324D01*
G01X282740Y401003D01*
X282735Y401011D01*
X282732Y401016D01*
X282331Y401738D01*
X282335Y401734D01*
X279629Y404441D01*
X278585D01*
X273775Y409251D01*
X273555D01*
X273493Y409313D01*
G01X288139Y384609D02*
Y385940D01*
X287882Y386197D01*
G02X286124Y389672I257J2312D01*
G03X286143Y391213I-1365J787D01*
G01X286124Y391247D01*
G02X286099Y393530I2015J1164D01*
G01X286124Y393572D01*
G03X284803Y395934I-1365J787D01*
G01X284708D01*
G02X282744Y397097I51J2326D01*
G03X281438Y397884I-1365J-788D01*
G01X281325D01*
G02X279365Y399044I53J2325D01*
G01X279038Y399611D01*
X275789Y402860D01*
X274806D01*
X269195Y408471D01*
X268975D01*
X268913Y408533D01*
G01X289331Y397471D02*
X288560Y398242D01*
G03X287781Y398675I-1148J-1148D01*
G02X286774Y399422I358J1534D01*
G03X284857Y400584I-2015J-1162D01*
G01X284679D01*
G02X283403Y401365I80J1564D01*
G01X283395Y401381D01*
X283393Y401384D01*
X283389Y401391D01*
X283386Y401396D01*
X283384Y401401D01*
X283361Y401441D01*
X282939Y402192D01*
X279940Y405191D01*
X278896D01*
X274303Y409784D01*
X274304Y410002D01*
X274243Y410063D01*
G01X294899Y392410D02*
X296849Y395032D01*
X296914Y395146D01*
G03Y397472I-2015J1163D01*
G02X296895Y399013I1365J787D01*
G01X297544Y400175D01*
Y403703D01*
X295173Y406074D01*
Y407266D01*
G01X315178Y263709D02*
X315171Y263694D01*
G02X313813Y260596I-14719J4605D01*
G03X313794Y259056I1365J-787D01*
G01X313813Y259022D01*
X313838Y258980D01*
G02X313813Y256697I-2040J-1119D01*
G03X313794Y255156I1365J-787D01*
G01X313813Y255122D01*
X313838Y255080D01*
G02X313813Y252797I-2040J-1119D01*
G03X313794Y251256I1365J-787D01*
G01X313813Y251222D01*
X313838Y251180D01*
G02X313813Y248897I-2040J-1119D01*
G03X313794Y247356I1365J-787D01*
G01X313813Y247322D01*
X313838Y247280D01*
G02X313813Y244997I-2040J-1119D01*
G03X313794Y243456I1365J-787D01*
G01X313813Y243422D01*
X313838Y243380D01*
G02X313813Y241097I-2040J-1119D01*
G03X313794Y239556I1365J-787D01*
G01X313813Y239522D01*
X313838Y239480D01*
G02X313813Y237197I-2040J-1119D01*
G03X313794Y235656I1365J-787D01*
G01X313813Y235622D01*
X313838Y235580D01*
G02X313813Y233297I-2040J-1119D01*
G03X313794Y231756I1365J-787D01*
G01X313813Y231722D01*
G02X313838Y229439I-2015J-1164D01*
G01X313813Y229397D01*
G03Y227823I1365J-787D01*
G02Y225497I-2015J-1163D01*
G03X313794Y223956I1365J-787D01*
G01X313813Y223922D01*
X313838Y223880D01*
G02X313813Y221597I-2040J-1119D01*
G03X313794Y220056I1365J-787D01*
G01X313813Y220022D01*
X313838Y219980D01*
G02X313813Y217697I-2040J-1119D01*
G03X313794Y216156I1365J-787D01*
G01X313813Y216122D01*
X313838Y216080D01*
G02X313813Y213797I-2040J-1119D01*
G03X313794Y212256I1365J-787D01*
G01X313813Y212222D01*
X313838Y212180D01*
G02X313813Y209897I-2040J-1119D01*
G01X313598Y209524D01*
Y208122D01*
X314306Y207414D01*
X314778D01*
X315243Y206949D01*
Y204215D01*
X314818Y203790D01*
Y194492D01*
X314973Y194337D01*
Y194250D01*
G01X315178Y275409D02*
Y274078D01*
X315434Y273822D01*
G02X317218Y270389I-256J-2313D01*
G01X317193Y270347D01*
X317174Y270313D01*
G03X317193Y268772I1384J-754D01*
G02X317218Y266489I-2015J-1164D01*
G01X317193Y266447D01*
X317174Y266413D01*
G03X317193Y264872I1384J-754D01*
G02Y262546I-2015J-1163D01*
G03Y260972I1365J-787D01*
G02X317218Y258689I-2018J-1164D01*
G01X317193Y258647D01*
X317174Y258613D01*
G03X317193Y257072I1384J-754D01*
G02X317218Y254789I-2015J-1164D01*
G01X317193Y254747D01*
X317174Y254713D01*
G03X317193Y253172I1384J-754D01*
G02X317218Y250889I-2015J-1164D01*
G01X317193Y250847D01*
X317174Y250813D01*
G03X317193Y249272I1384J-754D01*
G02X317218Y246989I-2015J-1164D01*
G01X317193Y246947D01*
X317174Y246913D01*
G03X317193Y245372I1384J-754D01*
G02X317218Y243089I-2015J-1164D01*
G01X317193Y243047D01*
X317174Y243013D01*
G03X317193Y241472I1384J-754D01*
G02X317218Y239189I-2015J-1164D01*
G01X317193Y239147D01*
X317174Y239113D01*
G03X317193Y237572I1384J-754D01*
G02X317218Y235289I-2015J-1164D01*
G01X317193Y235247D01*
X317174Y235213D01*
G03X317193Y233672I1384J-754D01*
G02Y231346I-2015J-1163D01*
G03Y229772I1365J-787D01*
G01X317218Y229730D01*
G02X317193Y227447I-2040J-1119D01*
G01X317174Y227413D01*
G03X317193Y225872I1384J-754D01*
G02X317218Y223589I-2015J-1164D01*
G01X317193Y223547D01*
X317174Y223513D01*
G03X317193Y221972I1384J-754D01*
G02X317218Y219689I-2015J-1164D01*
G01X317193Y219647D01*
G03Y218073I1365J-787D01*
G01X317628Y217319D01*
Y207954D01*
X319208Y206374D01*
Y199709D01*
X320286Y198631D01*
Y196855D01*
X320441Y196700D01*
Y196613D01*
G01X315178Y267609D02*
X315171Y267594D01*
G02X313813Y264496I-14719J4605D01*
G03X313652Y263317I1365J-787D01*
G02X313163Y260972I-3808J-429D01*
G03X313138Y258689I2016J-1164D01*
G01X313163Y258647D01*
X313182Y258613D01*
G02X313163Y257072I-1384J-754D01*
G03X313138Y254789I2015J-1164D01*
G01X313163Y254747D01*
X313182Y254713D01*
G02X313163Y253172I-1384J-754D01*
G03X313138Y250889I2015J-1164D01*
G01X313163Y250847D01*
X313182Y250813D01*
G02X313163Y249272I-1384J-754D01*
G03X313138Y246989I2015J-1164D01*
G01X313163Y246947D01*
X313182Y246913D01*
G02X313163Y245372I-1384J-754D01*
G03X313138Y243089I2015J-1164D01*
G01X313163Y243047D01*
X313182Y243013D01*
G02X313163Y241472I-1384J-754D01*
G03X313138Y239189I2015J-1164D01*
G01X313163Y239147D01*
X313182Y239113D01*
G02X313163Y237572I-1384J-754D01*
G03X313138Y235289I2015J-1164D01*
G01X313163Y235247D01*
X313182Y235213D01*
G02X313163Y233672I-1384J-754D01*
G03Y231346I2015J-1163D01*
G02Y229772I-1365J-787D01*
G01X313138Y229730D01*
G03X313163Y227447I2040J-1119D01*
G01X313182Y227413D01*
G02X313163Y225872I-1384J-754D01*
G03X313138Y223589I2015J-1164D01*
G01X313163Y223547D01*
X313182Y223513D01*
G02X313163Y221972I-1384J-754D01*
G03X313138Y219689I2015J-1164D01*
G01X313163Y219647D01*
X313182Y219613D01*
G02X313163Y218072I-1384J-754D01*
G03X313138Y215789I2015J-1164D01*
G01X313163Y215747D01*
X313182Y215713D01*
G02X313163Y214172I-1384J-754D01*
G03X313138Y211889I2015J-1164D01*
G01X313163Y211847D01*
X313182Y211813D01*
G02X313163Y210272I-1384J-754D01*
G01X312848Y209726D01*
Y207811D01*
X314493Y206166D01*
Y204526D01*
X314068Y204101D01*
Y194492D01*
X313913Y194337D01*
Y194250D01*
G01X315178Y271509D02*
Y272840D01*
X315406Y273068D01*
G02X316562Y270756I-228J-1559D01*
G01X316543Y270722D01*
X316518Y270680D01*
G03X316543Y268397I2040J-1119D01*
G02X316562Y266856I-1365J-787D01*
G01X316543Y266822D01*
X316518Y266780D01*
G03X316543Y264496I2041J-1120D01*
G02Y262922I-1365J-787D01*
G03Y260596I2015J-1163D01*
G02X316562Y259056I-1363J-787D01*
G01X316543Y259022D01*
X316518Y258980D01*
G03X316543Y256697I2040J-1119D01*
G02X316562Y255156I-1365J-787D01*
G01X316543Y255122D01*
X316518Y255080D01*
G03X316543Y252797I2040J-1119D01*
G02X316562Y251256I-1365J-787D01*
G01X316543Y251222D01*
X316518Y251180D01*
G03X316543Y248897I2040J-1119D01*
G02X316562Y247356I-1365J-787D01*
G01X316543Y247322D01*
X316518Y247280D01*
G03X316543Y244997I2040J-1119D01*
G02X316562Y243456I-1365J-787D01*
G01X316543Y243422D01*
X316518Y243380D01*
G03X316543Y241097I2040J-1119D01*
G02X316562Y239556I-1365J-787D01*
G01X316543Y239522D01*
X316518Y239480D01*
G03X316543Y237197I2040J-1119D01*
G02X316562Y235656I-1365J-787D01*
G01X316543Y235622D01*
X316518Y235580D01*
G03X316543Y233297I2040J-1119D01*
G02X316562Y231756I-1365J-787D01*
G01X316543Y231722D01*
G03X316518Y229439I2015J-1164D01*
G01X316543Y229397D01*
G02Y227823I-1365J-787D01*
G03Y225497I2015J-1163D01*
G02X316562Y223956I-1365J-787D01*
G01X316543Y223922D01*
X316518Y223880D01*
G03X316543Y221597I2040J-1119D01*
G02X316562Y220056I-1365J-787D01*
G01X316543Y220022D01*
G03Y217698I2015J-1162D01*
G01X316878Y217118D01*
Y207643D01*
X318458Y206063D01*
Y199398D01*
X319536Y198320D01*
Y196855D01*
X319381Y196700D01*
Y196613D01*
G01X311798Y265660D02*
G03X310890Y264585I10671J-9934D01*
G03X309799Y262950I12078J-9241D01*
G01X309783Y262922D01*
G03Y260596I2015J-1163D01*
G02X309802Y259056I-1363J-787D01*
G01X309783Y259022D01*
X309758Y258980D01*
G03X309783Y256697I2040J-1119D01*
G02X309802Y255156I-1365J-787D01*
G01X309783Y255122D01*
X309758Y255080D01*
G03X309783Y252797I2040J-1119D01*
G02X309802Y251256I-1365J-787D01*
G01X309783Y251222D01*
X309758Y251180D01*
G03X309783Y248897I2040J-1119D01*
G02X309802Y247356I-1365J-787D01*
G01X309783Y247322D01*
X309758Y247280D01*
G03X309783Y244997I2040J-1119D01*
G02X309802Y243456I-1365J-787D01*
G01X309783Y243422D01*
X309758Y243380D01*
G03X309783Y241097I2040J-1119D01*
G02X309802Y239556I-1365J-787D01*
G01X309783Y239522D01*
X309758Y239480D01*
G03X309783Y237197I2040J-1119D01*
G02X309802Y235656I-1365J-787D01*
G01X309783Y235622D01*
X309758Y235580D01*
G03X309783Y233297I2040J-1119D01*
G02X309802Y231756I-1365J-787D01*
G01X309783Y231722D01*
G03X309758Y229439I2015J-1164D01*
G01X309783Y229397D01*
G02Y227823I-1365J-787D01*
G03Y225497I2015J-1163D01*
G02X309802Y223956I-1365J-787D01*
G01X309783Y223922D01*
X309758Y223880D01*
G03X309783Y221597I2040J-1119D01*
G02X309802Y220056I-1365J-787D01*
G01X309783Y220022D01*
X309758Y219980D01*
G03X309783Y217697I2040J-1119D01*
G02X309802Y216156I-1365J-787D01*
G01X309783Y216122D01*
X309758Y216080D01*
G03X309783Y213797I2040J-1119D01*
G02X309802Y212256I-1365J-787D01*
G01X309783Y212222D01*
X309758Y212180D01*
G03X309783Y209897I2040J-1119D01*
G01X309830Y209815D01*
Y202279D01*
X310001Y202108D01*
Y199994D01*
X309318Y199311D01*
Y198211D01*
X308448Y197341D01*
G01X311798Y273460D02*
X310433Y270346D01*
G03X311194Y268104I1365J-787D01*
G02X313048Y266618I-1636J-3940D01*
G02X312372Y264192I-1250J-959D01*
G03X310433Y262546I1328J-3530D01*
G03Y260972I1365J-787D01*
G02X310458Y258689I-2018J-1164D01*
G01X310433Y258647D01*
X310414Y258613D01*
G03X310433Y257072I1384J-754D01*
G02X310458Y254789I-2015J-1164D01*
G01X310433Y254747D01*
X310414Y254713D01*
G03X310433Y253172I1384J-754D01*
G02X310458Y250889I-2015J-1164D01*
G01X310433Y250847D01*
X310414Y250813D01*
G03X310433Y249272I1384J-754D01*
G02X310458Y246989I-2015J-1164D01*
G01X310433Y246947D01*
X310414Y246913D01*
G03X310433Y245372I1384J-754D01*
G02X310458Y243089I-2015J-1164D01*
G01X310433Y243047D01*
X310414Y243013D01*
G03X310433Y241472I1384J-754D01*
G02X310458Y239189I-2015J-1164D01*
G01X310433Y239147D01*
X310414Y239113D01*
G03X310433Y237572I1384J-754D01*
G02X310458Y235289I-2015J-1164D01*
G01X310433Y235247D01*
X310414Y235213D01*
G03X310433Y233672I1384J-754D01*
G02Y231346I-2015J-1163D01*
G03Y229772I1365J-787D01*
G01X310458Y229730D01*
G02X310433Y227447I-2040J-1119D01*
G01X310414Y227413D01*
G03X310433Y225872I1384J-754D01*
G02X310458Y223589I-2015J-1164D01*
G01X310433Y223547D01*
X310414Y223513D01*
G03X310433Y221972I1384J-754D01*
G02X310458Y219689I-2015J-1164D01*
G01X310433Y219647D01*
X310414Y219613D01*
G03X310433Y218072I1384J-754D01*
G02X310458Y215789I-2015J-1164D01*
G01X310433Y215747D01*
X310414Y215713D01*
G03X310433Y214172I1384J-754D01*
G02X310458Y211889I-2015J-1164D01*
G01X310433Y211847D01*
X310414Y211813D01*
G03X310433Y210272I1384J-754D01*
G01X310580Y210017D01*
Y202587D01*
X310751Y202416D01*
Y199660D01*
X310068Y198977D01*
Y198221D01*
X310948Y197341D01*
G01X308418Y267609D02*
X308187Y267360D01*
G03X306419Y264900I11400J-10059D01*
G01X306403Y264872D01*
G03Y262546I2015J-1163D01*
G02Y260972I-1364J-787D01*
G03X306368Y258707I2017J-1164D01*
G01X306403Y258647D01*
G02Y257073I-1364J-787D01*
G03X306368Y254807I2015J-1164D01*
G01X306403Y254747D01*
G02Y253173I-1364J-787D01*
G03X306368Y250907I2015J-1164D01*
G01X306403Y250847D01*
G02Y249273I-1364J-787D01*
G03X306368Y247007I2015J-1164D01*
G01X306403Y246947D01*
G02Y245373I-1364J-787D01*
G03X306368Y243107I2015J-1164D01*
G01X306403Y243047D01*
G02Y241473I-1364J-787D01*
G03X306368Y239207I2015J-1164D01*
G01X306403Y239147D01*
G02Y237573I-1364J-787D01*
G03X306368Y235307I2015J-1164D01*
G01X306403Y235247D01*
G02Y233673I-1364J-787D01*
G03X306378Y231388I2015J-1165D01*
G01X306403Y231346D01*
G02Y229772I-1364J-787D01*
G01X306378Y229730D01*
G03X306403Y227447I2040J-1119D01*
G02Y225873I-1364J-787D01*
G03X306368Y223607I2015J-1164D01*
G01X306403Y223547D01*
G02Y221973I-1364J-787D01*
G03X306368Y219707I2015J-1164D01*
G01X306403Y219647D01*
G02Y218073I-1364J-787D01*
G03X306368Y215807I2015J-1164D01*
G01X306403Y215747D01*
G02Y214173I-1364J-787D01*
G03X306368Y211907I2015J-1164D01*
G01X306403Y211847D01*
G02X306614Y211060I-1364J-787D01*
G01Y203501D01*
X304326Y201213D01*
Y198219D01*
X303448Y197341D01*
G01X307365Y209837D02*
Y203190D01*
X305076Y200901D01*
Y198213D01*
X305948Y197341D01*
G01X259116Y192029D02*
X263447Y196360D01*
X268106D01*
X272451Y200705D01*
X273254Y202097D01*
G02X274560Y202884I1365J-788D01*
G01X274670D01*
G03X276634Y204047I-51J2326D01*
G02X277928Y204834I1365J-787D01*
G01X278248D01*
X278654Y204784D01*
X279191Y204588D01*
X280427Y203955D01*
G03X282744Y205997I952J1255D01*
G02X282719Y206039I594J382D01*
G02X282627Y208092I2039J1120D01*
G01X282533Y208444D01*
X281379Y209109D01*
G01Y263709D02*
G02X279364Y266446I11203J10358D01*
G03X277946Y267234I-1365J-787D01*
G01X276870Y268461D01*
G02X276699Y268669I1127J1101D01*
G02X276634Y268772I1299J892D01*
G03X274691Y269934I-2015J-1163D01*
G01X274547D01*
G03X272604Y268772I72J-2325D01*
G02X271298Y267985I-1365J788D01*
G01X271169D01*
G03X269224Y266822I70J-2325D01*
G02X267903Y266034I-1365J787D01*
G01X267059D01*
G01X279364Y361550D02*
X280014Y360422D01*
G03X281335Y359634I1365J787D01*
G01X281525D01*
X284759Y359260D01*
G01X289504Y397098D02*
X289331Y397471D01*
G01X288139Y392410D02*
G02X289504Y395524I14795J-4629D01*
G03Y397098I-1365J787D01*
G01X318558Y328060D02*
Y326729D01*
X318330Y326501D01*
G02X317193Y328847I228J1559D01*
G01X317218Y328889D01*
G03X317193Y331172I-2040J1119D01*
G02X317174Y332713I1365J787D01*
G01X317193Y332747D01*
X317218Y332789D01*
G03X317193Y335072I-2040J1119D01*
G02X317174Y336613I1365J787D01*
G01X317193Y336647D01*
X317218Y336689D01*
G03X317193Y338972I-2040J1119D01*
G02X317174Y340513I1365J787D01*
G01X317193Y340547D01*
X317218Y340589D01*
G03X317193Y342872I-2040J1119D01*
G02X317174Y344413I1365J787D01*
G01X317193Y344447D01*
X317218Y344489D01*
G03X317193Y346772I-2040J1119D01*
G02X317174Y348313I1365J787D01*
G01X317193Y348347D01*
X317218Y348389D01*
G03X317193Y350672I-2040J1119D01*
G02X317174Y352213I1365J787D01*
G01X317193Y352247D01*
X317218Y352289D01*
G03X317193Y354572I-2040J1119D01*
G02X317174Y356113I1365J787D01*
G01X317193Y356147D01*
X317218Y356189D01*
G03X317193Y358472I-2040J1119D01*
G02X317174Y360013I1365J787D01*
G01X317193Y360047D01*
X317218Y360089D01*
G03X317193Y362372I-2040J1119D01*
G02X317174Y363913I1365J787D01*
G01X317193Y363947D01*
X317218Y363989D01*
G03X317193Y366272I-2040J1119D01*
G02X317174Y367813I1365J787D01*
G01X317193Y367847D01*
G03X317218Y370130I-2015J1164D01*
G01X317193Y370172D01*
G02Y371746I1365J787D01*
G03Y374072I-2015J1163D01*
G02X317174Y375613I1365J787D01*
G01X317193Y375647D01*
X317218Y375689D01*
G03X317193Y377972I-2040J1119D01*
G02X317174Y379513I1365J787D01*
G01X317193Y379547D01*
X317218Y379589D01*
G03X317193Y381872I-2040J1119D01*
G02X317174Y383413I1365J787D01*
G01X317193Y383447D01*
X317218Y383489D01*
G03X317193Y385772I-2040J1119D01*
G02X317174Y387313I1365J787D01*
G01X317193Y387347D01*
X317218Y387389D01*
G03X317193Y389672I-2040J1119D01*
G02Y391248I1365J788D01*
G03X317208Y393544I-2015J1161D01*
G01X317206Y393547D01*
X316804Y394245D01*
X316080Y394969D01*
Y405357D01*
X316235Y405512D01*
G01X318558Y335860D02*
X319618Y338460D01*
X319923Y338972D01*
G03X319942Y340513I-1365J787D01*
G01X319923Y340547D01*
X319898Y340589D01*
G02X319923Y342872I2040J1119D01*
G03X319942Y344413I-1365J787D01*
G01X319923Y344447D01*
X319898Y344489D01*
G02X319923Y346772I2040J1119D01*
G03X319942Y348313I-1365J787D01*
G01X319923Y348347D01*
X319898Y348389D01*
G02X319923Y350672I2040J1119D01*
G03X319942Y352213I-1365J787D01*
G01X319923Y352247D01*
X319898Y352289D01*
G02X319923Y354572I2040J1119D01*
G03X319942Y356113I-1365J787D01*
G01X319923Y356147D01*
X319898Y356189D01*
G02X319923Y358472I2040J1119D01*
G03X319942Y360013I-1365J787D01*
G01X319923Y360047D01*
X319898Y360089D01*
G02X319923Y362372I2040J1119D01*
G03X319942Y363913I-1365J787D01*
G01X319923Y363947D01*
X319898Y363989D01*
G02X319923Y366272I2040J1119D01*
G03X319942Y367813I-1365J787D01*
G01X319923Y367847D01*
G02X319898Y370130I2015J1164D01*
G01X319923Y370172D01*
G03Y371746I-1365J787D01*
G02Y374072I2015J1163D01*
G03X319942Y375613I-1365J787D01*
G01X319923Y375647D01*
X319898Y375689D01*
G02X319923Y377972I2040J1119D01*
G03X319942Y379513I-1365J787D01*
G01X319923Y379547D01*
X319918Y379555D01*
X319914Y379561D01*
X319909Y379571D01*
X319898Y379589D01*
G02X319923Y381872I2040J1119D01*
G01X320148Y382265D01*
Y395180D01*
X318483Y396845D01*
Y402808D01*
X319333Y404278D01*
Y408945D01*
X319178Y409100D01*
Y409187D01*
G01X318558Y324160D02*
Y325491D01*
X318302Y325747D01*
G02X316518Y329180I256J2313D01*
G01X316543Y329222D01*
X316562Y329256D01*
G03X316543Y330797I-1384J754D01*
G02X316518Y333080I2015J1164D01*
G01X316543Y333122D01*
X316562Y333156D01*
G03X316543Y334697I-1384J754D01*
G02X316518Y336980I2015J1164D01*
G01X316543Y337022D01*
X316562Y337056D01*
G03X316543Y338597I-1384J754D01*
G02X316518Y340880I2015J1164D01*
G01X316543Y340922D01*
X316562Y340956D01*
G03X316543Y342497I-1384J754D01*
G02X316518Y344780I2015J1164D01*
G01X316543Y344822D01*
X316562Y344856D01*
G03X316543Y346397I-1384J754D01*
G02X316518Y348680I2015J1164D01*
G01X316543Y348722D01*
X316562Y348756D01*
G03X316543Y350297I-1384J754D01*
G02X316518Y352580I2015J1164D01*
G01X316543Y352622D01*
X316562Y352656D01*
G03X316543Y354197I-1384J754D01*
G02X316518Y356480I2015J1164D01*
G01X316543Y356522D01*
X316562Y356556D01*
G03X316543Y358097I-1384J754D01*
G02X316518Y360380I2015J1164D01*
G01X316543Y360422D01*
X316562Y360456D01*
G03X316543Y361997I-1384J754D01*
G02X316518Y364280I2015J1164D01*
G01X316543Y364322D01*
X316562Y364356D01*
G03X316543Y365897I-1384J754D01*
G02Y368223I2015J1163D01*
G03Y369797I-1365J787D01*
G01X316518Y369839D01*
G02X316543Y372122I2040J1119D01*
G01X316562Y372156D01*
G03X316543Y373697I-1384J754D01*
G02X316518Y375980I2015J1164D01*
G01X316543Y376022D01*
X316562Y376056D01*
G03X316543Y377597I-1384J754D01*
G02X316518Y379880I2015J1164D01*
G01X316543Y379922D01*
X316562Y379956D01*
G03X316543Y381497I-1384J754D01*
G02X316518Y383780I2015J1164D01*
G01X316543Y383822D01*
X316562Y383856D01*
G03X316543Y385397I-1384J754D01*
G02X316518Y387680I2015J1164D01*
G01X316543Y387722D01*
X316562Y387756D01*
G03X316543Y389297I-1384J754D01*
G02Y391623I2015J1163D01*
G03X316555Y393174I-1365J786D01*
G01X316203Y393785D01*
X315330Y394658D01*
Y405357D01*
X315175Y405512D01*
G01X318558Y331960D02*
G02X319923Y335076I14845J-4646D01*
G03X320120Y336067I-1365J786D01*
G01Y337700D01*
G02X320573Y338597I8201J-3579D01*
G03X320598Y340880I-2015J1164D01*
G01X320573Y340922D01*
X320554Y340956D01*
G02X320573Y342497I1384J754D01*
G03X320598Y344780I-2015J1164D01*
G01X320573Y344822D01*
X320554Y344856D01*
G02X320573Y346397I1384J754D01*
G03X320598Y348680I-2015J1164D01*
G01X320573Y348722D01*
X320554Y348756D01*
G02X320573Y350297I1384J754D01*
G03X320598Y352580I-2015J1164D01*
G01X320573Y352622D01*
X320554Y352656D01*
G02X320573Y354197I1384J754D01*
G03X320598Y356480I-2015J1164D01*
G01X320573Y356522D01*
X320554Y356556D01*
G02X320573Y358097I1384J754D01*
G03X320598Y360380I-2015J1164D01*
G01X320573Y360422D01*
X320554Y360456D01*
G02X320573Y361997I1384J754D01*
G03X320598Y364280I-2015J1164D01*
G01X320573Y364322D01*
X320554Y364356D01*
G02X320573Y365897I1384J754D01*
G03Y368223I-2015J1163D01*
G02Y369797I1365J787D01*
G01X320598Y369839D01*
G03X320573Y372122I-2040J1119D01*
G01X320554Y372156D01*
G02X320573Y373697I1384J754D01*
G03X320598Y375980I-2015J1164D01*
G01X320573Y376022D01*
X320554Y376056D01*
G02X320573Y377597I1384J754D01*
G03X320598Y379880I-2015J1164D01*
G01X320555Y379952D01*
X320553Y379955D01*
X320554Y379956D01*
G02X320573Y381497I1384J754D01*
G01X320898Y382060D01*
Y395491D01*
X319233Y397156D01*
Y402606D01*
X320083Y404076D01*
Y408945D01*
X320238Y409100D01*
Y409187D01*
G01X315178Y326110D02*
X313229Y328731D01*
X313163Y328847D01*
X313138Y328889D01*
G02X313163Y331172I2040J1119D01*
G03X313182Y332713I-1365J787D01*
G01X313163Y332747D01*
X313138Y332789D01*
G02X313163Y335072I2040J1119D01*
G03X313182Y336613I-1365J787D01*
G01X313163Y336647D01*
X313138Y336689D01*
G02X313163Y338972I2040J1119D01*
G03X313182Y340513I-1365J787D01*
G01X313163Y340547D01*
X313138Y340589D01*
G02X313163Y342872I2040J1119D01*
G03X313182Y344413I-1365J787D01*
G01X313163Y344447D01*
X313138Y344489D01*
G02X313163Y346772I2040J1119D01*
G03X313182Y348313I-1365J787D01*
G01X313163Y348347D01*
X313138Y348389D01*
G02X313163Y350672I2040J1119D01*
G03X313182Y352213I-1365J787D01*
G01X313163Y352247D01*
X313138Y352289D01*
G02X313163Y354572I2040J1119D01*
G03X313182Y356113I-1365J787D01*
G01X313163Y356147D01*
X313138Y356189D01*
G02X313163Y358472I2040J1119D01*
G03X313182Y360013I-1365J787D01*
G01X313163Y360047D01*
X313138Y360089D01*
G02X313163Y362372I2040J1119D01*
G03X313182Y363913I-1365J787D01*
G01X313163Y363947D01*
X313138Y363989D01*
G02X313163Y366272I2040J1119D01*
G03X313182Y367813I-1365J787D01*
G01X313163Y367847D01*
G02X313138Y370130I2015J1164D01*
G01X313163Y370172D01*
G03Y371746I-1365J787D01*
G02Y374072I2015J1163D01*
G03X313182Y375613I-1365J787D01*
G01X313163Y375647D01*
X313138Y375689D01*
G02X313163Y377972I2040J1119D01*
G03X313182Y379513I-1365J787D01*
G01X313163Y379547D01*
X313138Y379589D01*
G02X313163Y381872I2040J1119D01*
G03X313182Y383413I-1365J787D01*
G01X313163Y383447D01*
X313138Y383489D01*
G02X313163Y385772I2040J1119D01*
G03X313182Y387313I-1365J787D01*
G01X312416Y388684D01*
Y393973D01*
X310748Y395641D01*
Y399541D01*
X309825Y400464D01*
G01X315178Y333909D02*
X313881Y336905D01*
X313794Y337056D01*
G02X313813Y338597I1384J754D01*
G03X313838Y340880I-2015J1164D01*
G01X313813Y340922D01*
X313794Y340956D01*
G02X313813Y342497I1384J754D01*
G03X313838Y344780I-2015J1164D01*
G01X313813Y344822D01*
X313794Y344856D01*
G02X313813Y346397I1384J754D01*
G03X313838Y348680I-2015J1164D01*
G01X313813Y348722D01*
X313794Y348756D01*
G02X313813Y350297I1384J754D01*
G03X313838Y352580I-2015J1164D01*
G01X313813Y352622D01*
X313794Y352656D01*
G02X313813Y354197I1384J754D01*
G03X313838Y356480I-2015J1164D01*
G01X313813Y356522D01*
X313794Y356556D01*
G02X313813Y358097I1384J754D01*
G03X313838Y360380I-2015J1164D01*
G01X313813Y360422D01*
X313794Y360456D01*
G02X313813Y361997I1384J754D01*
G03X313838Y364280I-2015J1164D01*
G01X313813Y364322D01*
X313794Y364356D01*
G02X313813Y365897I1384J754D01*
G03Y368223I-2015J1163D01*
G02Y369797I1365J787D01*
G01X313838Y369839D01*
G03X313813Y372122I-2040J1119D01*
G01X313794Y372156D01*
G02X313813Y373697I1384J754D01*
G03X313838Y375980I-2015J1164D01*
G01X313813Y376022D01*
X313794Y376056D01*
G02X313813Y377597I1384J754D01*
G03X313838Y379880I-2015J1164D01*
G01X313813Y379922D01*
X313794Y379956D01*
G02X313813Y381497I1384J754D01*
G03X313838Y383780I-2015J1164D01*
G01X313813Y383822D01*
X313794Y383856D01*
G02X313813Y385397I1384J754D01*
G03X313838Y387680I-2015J1164D01*
G01X313164Y388879D01*
Y394283D01*
X311496Y395951D01*
Y399483D01*
X312325Y400312D01*
G01X311798Y328060D02*
X309849Y330681D01*
X309783Y330797D01*
G02X309758Y333080I2015J1164D01*
G01X309783Y333122D01*
X309802Y333156D01*
G03X309783Y334697I-1384J754D01*
G02X309758Y336980I2015J1164D01*
G01X309783Y337022D01*
X309802Y337056D01*
G03X309783Y338597I-1384J754D01*
G02X309758Y340880I2015J1164D01*
G01X309783Y340922D01*
X309802Y340956D01*
G03X309783Y342497I-1384J754D01*
G02X309758Y344780I2015J1164D01*
G01X309783Y344822D01*
X309802Y344856D01*
G03X309783Y346397I-1384J754D01*
G02X309758Y348680I2015J1164D01*
G01X309783Y348722D01*
X309802Y348756D01*
G03X309783Y350297I-1384J754D01*
G02X309758Y352580I2015J1164D01*
G01X309783Y352622D01*
X309802Y352656D01*
G03X309783Y354197I-1384J754D01*
G02X309758Y356480I2015J1164D01*
G01X309783Y356522D01*
X309802Y356556D01*
G03X309783Y358097I-1384J754D01*
G02X309758Y360380I2015J1164D01*
G01X309783Y360422D01*
X309802Y360456D01*
G03X309783Y361997I-1384J754D01*
G02X309758Y364280I2015J1164D01*
G01X309783Y364322D01*
X309802Y364356D01*
G03X309783Y365897I-1384J754D01*
G02Y368223I2015J1163D01*
G03Y369797I-1365J787D01*
G01X309758Y369839D01*
G02X309783Y372122I2040J1119D01*
G01X309802Y372156D01*
G03X309783Y373697I-1384J754D01*
G02X309758Y375980I2015J1164D01*
G01X309783Y376022D01*
X309802Y376056D01*
G03X309783Y377597I-1384J754D01*
G02X309758Y379880I2015J1164D01*
G01X309783Y379922D01*
X309802Y379956D01*
G03X309783Y381497I-1384J754D01*
G02X309758Y383780I2015J1164D01*
G01X309783Y383822D01*
X309802Y383856D01*
G03X309783Y385397I-1384J754D01*
G02X309758Y387680I2015J1164D01*
G01X309993Y388075D01*
Y389424D01*
X306747Y392670D01*
Y395242D01*
X305348Y396641D01*
Y399339D01*
X304525Y400162D01*
G01X310499Y334959D02*
X310433Y335072D01*
G02X310414Y336613I1365J787D01*
G01X310433Y336647D01*
X310458Y336689D01*
G03X310433Y338972I-2040J1119D01*
G02X310414Y340513I1365J787D01*
G01X310433Y340547D01*
X310458Y340589D01*
G03X310433Y342872I-2040J1119D01*
G02X310414Y344413I1365J787D01*
G01X310433Y344447D01*
X310458Y344489D01*
G03X310433Y346772I-2040J1119D01*
G02X310414Y348313I1365J787D01*
G01X310433Y348347D01*
X310458Y348389D01*
G03X310433Y350672I-2040J1119D01*
G02X310414Y352213I1365J787D01*
G01X310433Y352247D01*
X310458Y352289D01*
G03X310433Y354572I-2040J1119D01*
G02X310414Y356113I1365J787D01*
G01X310433Y356147D01*
X310458Y356189D01*
G03X310433Y358472I-2040J1119D01*
G02X310414Y360013I1365J787D01*
G01X310433Y360047D01*
X310458Y360089D01*
G03X310433Y362372I-2040J1119D01*
G02X310414Y363913I1365J787D01*
G01X310433Y363947D01*
X310458Y363989D01*
G03X310433Y366272I-2040J1119D01*
G02X310414Y367813I1365J787D01*
G01X310433Y367847D01*
G03X310458Y370130I-2015J1164D01*
G01X310433Y370172D01*
G02Y371746I1365J787D01*
G03Y374072I-2015J1163D01*
G02X310414Y375613I1365J787D01*
G01X310433Y375647D01*
X310458Y375689D01*
G03X310433Y377972I-2040J1119D01*
G02X310414Y379513I1365J787D01*
G01X310433Y379547D01*
X310458Y379589D01*
G03X310433Y381872I-2040J1119D01*
G02X310414Y383413I1365J787D01*
G01X310433Y383447D01*
X310458Y383489D01*
G03X310433Y385772I-2040J1119D01*
G02X310414Y387313I1365J787D01*
G01X310458Y387392D01*
X310741Y387868D01*
Y389734D01*
X307495Y392980D01*
Y395552D01*
X306096Y396951D01*
Y399383D01*
X307025Y400312D01*
G01X321296Y335348D02*
X321928Y335693D01*
X323101Y336672D01*
X323322Y337056D01*
G03X323303Y338597I-1384J754D01*
G02X323278Y340880I2015J1164D01*
G01X323303Y340922D01*
X323322Y340956D01*
G03X323303Y342497I-1384J754D01*
G02X323278Y344780I2015J1164D01*
G01X323303Y344822D01*
X323322Y344856D01*
G03X323303Y346397I-1384J754D01*
G02X323278Y348680I2015J1164D01*
G01X323303Y348722D01*
X323322Y348756D01*
G03X323303Y350297I-1384J754D01*
G02X323278Y352580I2015J1164D01*
G01X323303Y352622D01*
X323322Y352656D01*
G03X323303Y354197I-1384J754D01*
G02X323278Y356480I2015J1164D01*
G01X323303Y356522D01*
X323322Y356556D01*
G03X323303Y358097I-1384J754D01*
G02X323278Y360380I2015J1164D01*
G01X323303Y360422D01*
X323322Y360456D01*
G03X323303Y361997I-1384J754D01*
G02X323278Y364280I2015J1164D01*
G01X323303Y364322D01*
X323322Y364356D01*
G03X323303Y365897I-1384J754D01*
G02Y368223I2015J1163D01*
G03Y369797I-1365J787D01*
G01X323278Y369839D01*
G02X323303Y372122I2040J1119D01*
G01X323322Y372156D01*
G03X323303Y373697I-1384J754D01*
G02X323278Y375980I2015J1164D01*
G01X323303Y376022D01*
X323322Y376056D01*
G03X323303Y377597I-1384J754D01*
G02X323278Y379880I2015J1164D01*
G01X323693Y380617D01*
Y384696D01*
X322948Y385441D01*
Y396041D01*
X321948Y397041D01*
Y400841D01*
X323932Y402825D01*
Y403096D01*
X323104Y403924D01*
G01X345598Y218860D02*
X345451Y218713D01*
G03X343902Y216682I6772J-6771D01*
G01X343583Y216122D01*
X343558Y216080D01*
G03X343583Y213797I2040J-1119D01*
G02X343602Y212256I-1365J-787D01*
G01X343583Y212222D01*
X343558Y212180D01*
G03X343583Y209897I2040J-1119D01*
G02X343602Y208356I-1365J-787D01*
G01X343583Y208322D01*
G03X343558Y206039I2015J-1164D01*
G01X343583Y205997D01*
G02Y204423I-1365J-787D01*
G01X343248Y203841D01*
Y202082D01*
X345037Y200293D01*
Y198346D01*
G01X321938Y267609D02*
X323237Y264610D01*
X323303Y264497D01*
G02X323322Y262956I-1365J-787D01*
G01X323303Y262922D01*
X323278Y262880D01*
G03X323303Y260597I2040J-1119D01*
G02X323322Y259056I-1365J-787D01*
G01X323303Y259022D01*
X323278Y258980D01*
G03X323303Y256697I2040J-1119D01*
G02X323322Y255156I-1365J-787D01*
G01X323303Y255122D01*
X323278Y255080D01*
G03X323303Y252797I2040J-1119D01*
G02X323322Y251256I-1365J-787D01*
G01X323303Y251222D01*
X323278Y251180D01*
G03X323303Y248897I2040J-1119D01*
G02X323322Y247356I-1365J-787D01*
G01X323303Y247322D01*
X323278Y247280D01*
G03X323303Y244997I2040J-1119D01*
G02X323322Y243456I-1365J-787D01*
G01X323303Y243422D01*
X323278Y243380D01*
G03X323303Y241097I2040J-1119D01*
G02X323322Y239556I-1365J-787D01*
G01X323303Y239522D01*
X323278Y239480D01*
G03X323303Y237197I2040J-1119D01*
G02X323322Y235656I-1365J-787D01*
G01X323303Y235622D01*
X323278Y235580D01*
G03X323303Y233297I2040J-1119D01*
G02X323322Y231756I-1365J-787D01*
G01X323303Y231722D01*
G03X323278Y229439I2015J-1164D01*
G01X323303Y229397D01*
G02Y227823I-1365J-787D01*
G03Y225497I2015J-1163D01*
G02X323322Y223956I-1365J-787D01*
G01X323303Y223922D01*
X323278Y223880D01*
G03X323303Y221597I2040J-1119D01*
G02X323514Y220809I-1366J-788D01*
G01Y219957D01*
X322918Y219361D01*
Y210123D01*
X326594Y206447D01*
Y200695D01*
X328948Y198341D01*
Y198091D01*
X328148Y197291D01*
G01X321938Y271509D02*
X323203Y268862D01*
X323744Y268321D01*
Y265638D01*
G03X323953Y264872I1586J21D01*
G02X323978Y262589I-2015J-1164D01*
G01X323953Y262547D01*
X323934Y262513D01*
G03X323953Y260972I1384J-754D01*
G02X323978Y258689I-2015J-1164D01*
G01X323953Y258647D01*
X323934Y258613D01*
G03X323953Y257072I1384J-754D01*
G02X323978Y254789I-2015J-1164D01*
G01X323953Y254747D01*
X323934Y254713D01*
G03X323953Y253172I1384J-754D01*
G02X323978Y250889I-2015J-1164D01*
G01X323953Y250847D01*
X323934Y250813D01*
G03X323953Y249272I1384J-754D01*
G02X323978Y246989I-2015J-1164D01*
G01X323953Y246947D01*
X323934Y246913D01*
G03X323953Y245372I1384J-754D01*
G02X323978Y243089I-2015J-1164D01*
G01X323953Y243047D01*
X323934Y243013D01*
G03X323953Y241472I1384J-754D01*
G02X323978Y239189I-2015J-1164D01*
G01X323953Y239147D01*
X323934Y239113D01*
G03X323953Y237572I1384J-754D01*
G02X323978Y235289I-2015J-1164D01*
G01X323953Y235247D01*
X323934Y235213D01*
G03X323953Y233672I1384J-754D01*
G02Y231346I-2015J-1163D01*
G03Y229772I1365J-787D01*
G01X323978Y229730D01*
G02X323953Y227447I-2040J-1119D01*
G01X323934Y227413D01*
G03X323953Y225872I1384J-754D01*
G02X323978Y223589I-2015J-1164D01*
G01X323953Y223547D01*
X323934Y223513D01*
G03X323953Y221972I1384J-754D01*
G02X324265Y220809I-2015J-1164D01*
G01Y219574D01*
X323669Y218978D01*
Y210474D01*
X327344Y206799D01*
Y201047D01*
X329698Y198693D01*
Y198241D01*
X330648Y197291D01*
G01X318558Y265660D02*
X319712Y264994D01*
X319806Y264642D01*
G03X319898Y262589I2131J-933D01*
G03X319923Y262546I896J492D01*
G02Y260972I-1365J-787D01*
G03X319898Y258689I2018J-1164D01*
G01X319923Y258647D01*
X319942Y258613D01*
G02X319923Y257072I-1384J-754D01*
G03X319898Y254789I2015J-1164D01*
G01X319923Y254747D01*
X319942Y254713D01*
G02X319923Y253172I-1384J-754D01*
G03X319898Y250889I2015J-1164D01*
G01X319923Y250847D01*
X319942Y250813D01*
G02X319923Y249272I-1384J-754D01*
G03X319898Y246989I2015J-1164D01*
G01X319923Y246947D01*
X319942Y246913D01*
G02X319923Y245372I-1384J-754D01*
G03X319898Y243089I2015J-1164D01*
G01X319923Y243047D01*
X319942Y243013D01*
G02X319923Y241472I-1384J-754D01*
G03X319898Y239189I2015J-1164D01*
G01X319923Y239147D01*
X319942Y239113D01*
G02X319923Y237572I-1384J-754D01*
G03X319898Y235289I2015J-1164D01*
G01X319923Y235247D01*
X319942Y235213D01*
G02X319923Y233672I-1384J-754D01*
G03Y231346I2015J-1163D01*
G02Y229772I-1365J-787D01*
G01X319898Y229730D01*
G03X319923Y227447I2040J-1119D01*
G01X319942Y227413D01*
G02X319923Y225872I-1384J-754D01*
G03X319898Y223589I2015J-1164D01*
G01X319923Y223547D01*
X319942Y223513D01*
G02X319923Y221972I-1384J-754D01*
G03X319898Y219689I2015J-1164D01*
G02X320035Y219410I-1351J-836D01*
G02X320133Y218869I-1444J-541D01*
G01Y217659D01*
X319898Y217424D01*
Y208905D01*
X322359Y206444D01*
Y202801D01*
X321836Y201888D01*
Y200207D01*
X323842Y198201D01*
Y197385D01*
X323148Y196691D01*
G01X318558Y273460D02*
X319737Y270754D01*
G03X319923Y270346I2200J757D01*
G02X320110Y269289I-1365J-787D01*
G03X320573Y266822I3741J-575D01*
G02Y264496I-2015J-1163D01*
G03Y262922I1365J-787D01*
G02Y260596I-2015J-1163D01*
G03X320554Y259056I1363J-787D01*
G01X320573Y259022D01*
X320598Y258980D01*
G02X320573Y256697I-2040J-1119D01*
G03X320554Y255156I1365J-787D01*
G01X320573Y255122D01*
X320598Y255080D01*
G02X320573Y252797I-2040J-1119D01*
G03X320554Y251256I1365J-787D01*
G01X320573Y251222D01*
X320598Y251180D01*
G02X320573Y248897I-2040J-1119D01*
G03X320554Y247356I1365J-787D01*
G01X320573Y247322D01*
X320598Y247280D01*
G02X320573Y244997I-2040J-1119D01*
G03X320554Y243456I1365J-787D01*
G01X320573Y243422D01*
X320598Y243380D01*
G02X320573Y241097I-2040J-1119D01*
G03X320554Y239556I1365J-787D01*
G01X320573Y239522D01*
X320598Y239480D01*
G02X320573Y237197I-2040J-1119D01*
G03X320554Y235656I1365J-787D01*
G01X320573Y235622D01*
X320598Y235580D01*
G02X320573Y233297I-2040J-1119D01*
G03X320554Y231756I1365J-787D01*
G01X320573Y231722D01*
G02X320598Y229439I-2015J-1164D01*
G01X320573Y229397D01*
G03Y227823I1365J-787D01*
G02Y225497I-2015J-1163D01*
G03X320554Y223956I1365J-787D01*
G01X320573Y223922D01*
X320598Y223880D01*
G02X320573Y221597I-2040J-1119D01*
G01X320572Y221598D01*
G03X320554Y220052I1366J-789D01*
G02X320744Y219658I-1868J-1144D01*
G02X320883Y218870I-2162J-788D01*
G01Y217327D01*
X320648Y217092D01*
Y209245D01*
X323109Y206784D01*
Y202569D01*
X322586Y201656D01*
Y200551D01*
X324658Y198479D01*
Y197641D01*
X325648Y196651D01*
G01X342218Y224709D02*
X344361Y221255D01*
X346234Y220303D01*
G02X346281Y217441I-636J-1442D01*
G03X345691Y216956I697J-1449D01*
G01X345644Y216909D01*
G02X344972Y216433I-1731J1732D01*
G03X344214Y215713I736J-1534D01*
G03X344233Y214172I1384J-754D01*
G02X344258Y211889I-2015J-1164D01*
G01X344233Y211847D01*
X344214Y211813D01*
G03X344233Y210272I1384J-754D01*
G02Y207946I-2015J-1163D01*
G03Y206372I1365J-787D01*
G01X344258Y206330D01*
G02X344465Y204607I-2040J-1119D01*
G02X344234Y204048I-2247J601D01*
G03X343998Y203165I1535J-883D01*
G01Y202394D01*
X346576Y199816D01*
Y198054D01*
G01X348188Y198224D02*
Y200203D01*
X347198Y201193D01*
Y203641D01*
X346963Y204048D01*
G02Y206374I2015J1163D01*
G03Y207948I-1364J787D01*
G02Y210274I2015J1163D01*
G03Y211848I-1364J787D01*
G02Y214174I2015J1163D01*
G03X347167Y214812I-1365J788D01*
G03X347158Y216254I-7080J677D01*
G02X347613Y217698I3483J-304D01*
G03Y220024I-2015J1163D01*
G02Y221598I1365J787D01*
G03Y223924I-2015J1163D01*
G02Y225498I1365J787D01*
G03Y227824I-2015J1163D01*
G01X347548Y227937D01*
X345598Y230559D01*
G01X348978Y216909D02*
X347846Y214361D01*
G02X347613Y213798I-2248J601D01*
G03Y212224I1365J-787D01*
G02Y209898I-2015J-1163D01*
G03Y208324I1365J-787D01*
G02Y205998I-2015J-1163D01*
G03Y204424I1365J-787D01*
G01X347745Y204195D01*
X347992Y203948D01*
Y202400D01*
X350188Y200204D01*
Y198928D01*
G01X338838Y222760D02*
X337541Y219764D01*
X337454Y219613D01*
G03X337473Y218072I1384J-754D01*
G02X337498Y215789I-2015J-1164D01*
G01X337473Y215747D01*
G03X337263Y215001I1365J-787D01*
G01X337252Y214580D01*
Y202240D01*
X340101Y199391D01*
Y197885D01*
G01X342218Y213009D02*
X340921Y210013D01*
X340834Y209862D01*
G03X340853Y208321I1384J-754D01*
G02X340878Y206038I-2015J-1164D01*
G01X340853Y205996D01*
X340826Y205948D01*
G03X340853Y204422I1392J-739D01*
G02X341355Y202545I-3257J-1877D01*
G01Y202082D01*
X343486Y199951D01*
Y198703D01*
G01X338838Y214960D02*
X340203Y211846D01*
G02X340222Y210305I-1365J-787D01*
G01X340203Y210271D01*
X340178Y210229D01*
G03X340203Y207946I2040J-1119D01*
G02X340230Y206420I-1365J-787D01*
G01X340168Y206312D01*
G03X340203Y204046I2050J-1102D01*
G01X340222Y204012D01*
G02X340501Y203002I-1802J-1041D01*
G01Y201409D01*
X341660Y200250D01*
Y197909D01*
G01X359117Y211060D02*
X359892Y209062D01*
Y204000D01*
X360878Y203014D01*
Y199014D01*
X366092Y193800D01*
Y192683D01*
G01X368092Y192974D02*
Y193800D01*
X361892Y200000D01*
Y203529D01*
X360921Y204500D01*
Y209099D01*
G02X361132Y209898I1576J11D01*
G01X362497Y213009D01*
G01X364092Y192561D02*
Y193800D01*
X359892Y198000D01*
Y202398D01*
X358790Y203500D01*
Y207400D01*
G03X358255Y209400I-4004J0D01*
G01X357752Y210272D01*
G02X357733Y211813I1365J787D01*
G01X357752Y211847D01*
X357777Y211889D01*
G03X357752Y214172I-2040J1119D01*
G02X357733Y215713I1365J787D01*
G01X357820Y215864D01*
X359117Y218860D01*
G01X362092Y192853D02*
Y193900D01*
X358892Y197100D01*
Y201965D01*
X357563Y203294D01*
Y208177D01*
G03X357102Y209897I-3438J0D01*
G02X357077Y212180I2015J1164D01*
G01X357102Y212222D01*
X357121Y212256D01*
G03X357102Y213797I-1384J754D01*
G01X357036Y213910D01*
X355737Y216909D01*
G01X359117Y222760D02*
X357820Y219764D01*
X357752Y219647D01*
G02X355807Y218484I-2015J1162D01*
G01X355678D01*
G03X354353Y216156I59J-1575D01*
G01X354372Y216122D01*
X354397Y216080D01*
G02X354372Y213797I-2040J-1119D01*
G03X354353Y212256I1365J-787D01*
G01X354372Y212222D01*
X354397Y212180D01*
G02X354372Y209897I-2040J-1119D01*
G03X354092Y208853I1808J-1044D01*
G01Y204301D01*
X357892Y200501D01*
Y196200D01*
X360092Y194000D01*
Y192853D01*
G01X356188Y198807D02*
Y200204D01*
X353292Y203100D01*
Y208665D01*
G02X353722Y210272I3217J0D01*
G03X353741Y211813I-1365J787D01*
G01X353722Y211847D01*
X353697Y211889D01*
G02X353722Y214172I2040J1119D01*
G03X353741Y215713I-1365J787D01*
G01X353722Y215747D01*
X353697Y215789D01*
G02X353722Y218072I2040J1119D01*
G03X353741Y219613I-1365J787D01*
G01X353722Y219647D01*
X353697Y219689D01*
G02X353722Y221972I2040J1119D01*
G01X353983Y222423D01*
G02X355737Y224709I9566J-5524D01*
G01X348978Y228610D02*
X350279Y225603D01*
X350342Y225496D01*
G02Y223922I-1364J-787D01*
G01X350307Y223862D01*
G03X350342Y221596I2050J-1102D01*
G02Y220022I-1364J-787D01*
G01X350307Y219962D01*
G03X350342Y217696I2050J-1102D01*
G02Y216122I-1364J-787D01*
G01X350307Y216062D01*
G03X350342Y213796I2050J-1102D01*
G02Y212222I-1364J-787D01*
G01X350307Y212162D01*
G03X350342Y209896I2050J-1102D01*
G02X350592Y208964I-1614J-932D01*
G01Y208100D01*
X350598Y208094D01*
Y201794D01*
X352188Y200204D01*
Y199049D01*
G01X352357Y230559D02*
G02X351983Y229163I-2793J0D01*
G01X350993Y227447D01*
G03Y225873I1364J-787D01*
G02X351028Y223607I-2015J-1164D01*
G01X350993Y223547D01*
G03Y221973I1364J-787D01*
G02X351028Y219707I-2015J-1164D01*
G01X350993Y219647D01*
G03Y218073I1364J-787D01*
G02X351028Y215807I-2015J-1164D01*
G01X350993Y215747D01*
G03Y214173I1364J-787D01*
G02X351028Y211907I-2015J-1164D01*
G01X350993Y211847D01*
G03Y210273I1364J-787D01*
G02X351492Y208410I-3229J-1863D01*
G01Y202800D01*
X354188Y200104D01*
Y198734D01*
G01X308418Y271509D02*
X309498Y268756D01*
G02X309026Y266138I-1088J-1155D01*
G01X309017Y266135D01*
G03X307054Y264496I1191J-3422D01*
G03Y262922I1364J-787D01*
G02Y260596I-2015J-1163D01*
G03Y259022I1364J-787D01*
G01X307089Y258962D01*
G02X307054Y256696I-2050J-1102D01*
G03Y255122I1364J-787D01*
G01X307089Y255062D01*
G02X307054Y252796I-2050J-1102D01*
G03Y251222I1364J-787D01*
G01X307089Y251162D01*
G02X307054Y248896I-2050J-1102D01*
G03Y247322I1364J-787D01*
G01X307089Y247262D01*
G02X307054Y244996I-2050J-1102D01*
G03Y243422I1364J-787D01*
G01X307089Y243362D01*
G02X307054Y241096I-2050J-1102D01*
G03Y239522I1364J-787D01*
G01X307089Y239462D01*
G02X307054Y237196I-2050J-1102D01*
G03Y235622I1364J-787D01*
G01X307089Y235562D01*
G02X307054Y233296I-2050J-1102D01*
G03Y231722I1364J-787D01*
G02X307079Y229439I-2015J-1164D01*
G01X307054Y229397D01*
G03Y227823I1364J-787D01*
G01X307079Y227781D01*
G02X307054Y225496I-2040J-1120D01*
G03Y223922I1364J-787D01*
G01X307089Y223862D01*
G02X307054Y221596I-2050J-1102D01*
G03Y220022I1364J-787D01*
G01X307089Y219962D01*
G02X307054Y217696I-2050J-1102D01*
G03Y216122I1364J-787D01*
G01X307089Y216062D01*
G02X307054Y213796I-2050J-1102D01*
G03Y212222I1364J-787D01*
G01X307089Y212162D01*
G02X307366Y211060I-2050J-1101D01*
G01X307365Y209837D01*
G01X328608Y405717D02*
X329248Y405077D01*
Y382412D01*
X326683Y377972D01*
G03X326658Y375689I2015J-1164D01*
G01X326683Y375647D01*
X326702Y375613D01*
G02X326683Y374072I-1384J-754D01*
G03Y371746I2015J-1163D01*
G02Y370172I-1365J-787D01*
G01X326658Y370130D01*
G03X326683Y367847I2040J-1119D01*
G01X326702Y367813D01*
G02X326683Y366272I-1384J-754D01*
G03X326658Y363989I2015J-1164D01*
G01X326683Y363947D01*
X326702Y363913D01*
G02X326683Y362372I-1384J-754D01*
G03X326658Y360089I2015J-1164D01*
G01X326683Y360047D01*
X326702Y360013D01*
G02X326683Y358472I-1384J-754D01*
G03X326658Y356189I2015J-1164D01*
G01X326683Y356147D01*
X326702Y356113D01*
G02X326683Y354572I-1384J-754D01*
G03X326658Y352289I2015J-1164D01*
G01X326683Y352247D01*
X326702Y352213D01*
G02X326683Y350672I-1384J-754D01*
G03X326658Y348389I2015J-1164D01*
G01X326683Y348347D01*
X326702Y348313D01*
G02X326683Y346772I-1384J-754D01*
G03X326658Y344489I2015J-1164D01*
G01X326683Y344447D01*
X326702Y344413D01*
G02X326683Y342872I-1384J-754D01*
G03X326658Y340589I2015J-1164D01*
G01X326683Y340547D01*
X326702Y340513D01*
G02X326683Y338972I-1384J-754D01*
G03X326658Y336689I2015J-1164D01*
G01X326683Y336647D01*
X326702Y336613D01*
G02X326683Y335072I-1384J-754D01*
G01X326518Y334787D01*
X326183Y334377D01*
X325956Y334173D01*
X324936Y333489D01*
G03X323953Y331172I382J-1529D01*
G01X324019Y331059D01*
X325318Y328060D01*
G01Y331960D02*
X325424Y331976D01*
X326959Y334040D01*
X327333Y334697D01*
G03X327358Y336980I-2015J1164D01*
G01X327333Y337022D01*
X327314Y337056D01*
G02X327333Y338597I1384J754D01*
G03X327358Y340880I-2015J1164D01*
G01X327333Y340922D01*
X327314Y340956D01*
G02X327333Y342497I1384J754D01*
G03X327358Y344780I-2015J1164D01*
G01X327333Y344822D01*
X327314Y344856D01*
G02X327333Y346397I1384J754D01*
G03X327358Y348680I-2015J1164D01*
G01X327333Y348722D01*
X327314Y348756D01*
G02X327333Y350297I1384J754D01*
G03X327358Y352580I-2015J1164D01*
G01X327333Y352622D01*
X327314Y352656D01*
G02X327333Y354197I1384J754D01*
G03X327358Y356480I-2015J1164D01*
G01X327333Y356522D01*
X327314Y356556D01*
G02X327333Y358097I1384J754D01*
G03X327358Y360380I-2015J1164D01*
G01X327333Y360422D01*
X327314Y360456D01*
G02X327333Y361997I1384J754D01*
G03X327358Y364280I-2015J1164D01*
G01X327333Y364322D01*
X327314Y364356D01*
G02X327333Y365897I1384J754D01*
G03Y368223I-2015J1163D01*
G02Y369797I1365J787D01*
G01X327358Y369839D01*
G03X327333Y372122I-2040J1119D01*
G01X327314Y372156D01*
G02X327333Y373697I1384J754D01*
G03X327358Y375980I-2015J1164D01*
G01X327333Y376022D01*
X327314Y376056D01*
G02X327333Y377597I1384J754D01*
G01X327332Y377599D01*
X329996Y382209D01*
Y405013D01*
X330904Y405921D01*
G01X311798Y331960D02*
X310499Y334959D01*
G01X321938Y326110D02*
X320640Y329107D01*
X320573Y329222D01*
X320554Y329256D01*
G02X320573Y330797I1384J754D01*
G03X320598Y333080I-2015J1164D01*
G01X320573Y333122D01*
X320554Y333156D01*
G02X321296Y335348I1384J753D01*
G01X325604Y403862D02*
X324680Y402938D01*
Y402515D01*
X322696Y400531D01*
Y397351D01*
X323696Y396351D01*
Y385751D01*
X324441Y385006D01*
Y380420D01*
X323934Y379513D01*
G03X323953Y377972I1384J-754D01*
G02X323978Y375689I-2015J-1164D01*
G01X323953Y375647D01*
X323934Y375613D01*
G03X323953Y374072I1384J-754D01*
G02Y371746I-2015J-1163D01*
G03Y370172I1365J-787D01*
G01X323978Y370130D01*
G02X323953Y367847I-2040J-1119D01*
G01X323934Y367813D01*
G03X323953Y366272I1384J-754D01*
G02X323978Y363989I-2015J-1164D01*
G01X323953Y363947D01*
X323934Y363913D01*
G03X323953Y362372I1384J-754D01*
G02X323978Y360089I-2015J-1164D01*
G01X323953Y360047D01*
X323934Y360013D01*
G03X323953Y358472I1384J-754D01*
G02X323978Y356189I-2015J-1164D01*
G01X323953Y356147D01*
X323934Y356113D01*
G03X323953Y354572I1384J-754D01*
G02X323978Y352289I-2015J-1164D01*
G01X323953Y352247D01*
X323934Y352213D01*
G03X323953Y350672I1384J-754D01*
G02X323978Y348389I-2015J-1164D01*
G01X323953Y348347D01*
X323934Y348313D01*
G03X323953Y346772I1384J-754D01*
G02X323978Y344489I-2015J-1164D01*
G01X323953Y344447D01*
X323934Y344413D01*
G03X323953Y342872I1384J-754D01*
G02X323978Y340589I-2015J-1164D01*
G01X323953Y340547D01*
X323934Y340513D01*
G03X323953Y338972I1384J-754D01*
G02X323978Y336689I-2015J-1164D01*
G01X323953Y336647D01*
X323608Y336041D01*
G02X321938Y333909I-8038J4576D01*
G01X345598Y378760D02*
X344299Y381759D01*
X344233Y381872D01*
G02X344214Y383413I1365J787D01*
G01X344233Y383447D01*
X344258Y383489D01*
G03X344233Y385772I-2040J1119D01*
G02X344214Y387313I1365J787D01*
G01X344233Y387347D01*
X344258Y387389D01*
G03X344233Y389672I-2040J1119D01*
G02X344214Y391213I1365J787D01*
G01X344232Y391248D01*
X344233Y391247D01*
G02X344232Y391249I1406J704D01*
G01X344966Y392520D01*
X344968Y392522D01*
Y393876D01*
X346790Y395698D01*
Y397118D01*
G01X348978Y380709D02*
X347681Y383705D01*
X347594Y383856D01*
G02X347613Y385397I1384J754D01*
G03Y387723I-2015J1163D01*
G02Y389297I1365J787D01*
G03Y391623I-2015J1163D01*
G01X347388Y392013D01*
Y393310D01*
X352892Y398814D01*
Y404000D01*
X350790Y406102D01*
Y407015D01*
G01X345598Y367060D02*
X346896Y370057D01*
X346963Y370172D01*
G03X347172Y370953I-1354J781D01*
G01Y382592D01*
G03X346982Y383413I-1574J68D01*
G01X346963Y383447D01*
X346938Y383489D01*
G02X346963Y385772I2040J1119D01*
G03X346982Y387313I-1365J787D01*
G01X346963Y387347D01*
G02Y389673I2015J1163D01*
G03Y391247I-1365J787D01*
G01X346492Y392064D01*
Y393700D01*
X348790Y395998D01*
Y397365D01*
G01X344790Y396937D02*
Y395584D01*
X343850Y394644D01*
Y392089D01*
X343404Y391317D01*
G03X343418Y391271I2233J655D01*
G03X343583Y389297I2180J-812D01*
G02X343602Y387756I-1365J-787D01*
G01X343583Y387722D01*
X343558Y387680D01*
G03X343583Y385397I2040J-1119D01*
G02X343602Y383856I-1365J-787D01*
G01X343583Y383822D01*
X343558Y383780D01*
G03X343583Y381497I2040J-1119D01*
G02X343602Y379956I-1365J-787D01*
G01X343583Y379922D01*
X343558Y379880D01*
G03X343583Y377597I2040J-1119D01*
G02X343602Y376056I-1365J-787D01*
G01X343515Y375905D01*
X342218Y372909D01*
G01X338838Y374860D02*
X340137Y377859D01*
X340203Y377972D01*
G03X340222Y379513I-1365J787D01*
G01X340203Y379547D01*
X340178Y379589D01*
G02X340203Y381872I2040J1119D01*
G03X340222Y383413I-1365J787D01*
G01X340203Y383447D01*
X340178Y383489D01*
G02X340203Y385772I2040J1119D01*
G03X340222Y387313I-1365J787D01*
G01X340203Y387347D01*
X340178Y387389D01*
G02X340031Y387714I2040J1119D01*
G01X339652Y388140D01*
X339542Y388250D01*
Y398586D01*
X340746Y399790D01*
Y401003D01*
G01X342746Y400788D02*
Y399854D01*
X340292Y397400D01*
Y389321D01*
X340653Y388320D01*
G03X340834Y387756I1565J191D01*
G01X340853Y387722D01*
X340878Y387680D01*
G02X340853Y385397I-2040J-1119D01*
G03X340834Y383856I1365J-787D01*
G01X340853Y383822D01*
X340878Y383780D01*
G02X340853Y381497I-2040J-1119D01*
G03X340834Y379956I1365J-787D01*
G01X340853Y379922D01*
X340878Y379880D01*
G02X340853Y377597I-2040J-1119D01*
G03X340834Y376056I1365J-787D01*
G01X340853Y376022D01*
X340878Y375980D01*
G02X340853Y373697I-2040J-1119D01*
G01X340787Y373582D01*
X338838Y370959D01*
G01X338746Y400454D02*
Y388694D01*
X337264Y387212D01*
Y386276D01*
G03X337537Y385617I932J0D01*
G01X337571Y385583D01*
G02X337498Y383489I-2113J-975D01*
G01X337473Y383447D01*
X337454Y383413D01*
G03X337473Y381872I1384J-754D01*
G01X337539Y381759D01*
X338838Y378760D01*
G01X359117Y374860D02*
X357818Y377859D01*
X357752Y377972D01*
G03X355822Y379134I-2015J-1163D01*
G01X355693D01*
G02X354372Y381497I44J1575D01*
G03X354397Y383780I-2015J1164D01*
G01X354372Y383822D01*
X354353Y383856D01*
G02X354372Y385397I1384J754D01*
G03X354397Y387680I-2015J1164D01*
G01X354372Y387722D01*
X354163Y388096D01*
Y394271D01*
X356413Y396521D01*
Y405321D01*
X358790Y407698D01*
Y408586D01*
G01X355737Y372909D02*
X356925Y375642D01*
G02X357077Y375980I2191J-782D01*
G01X357102Y376022D01*
X357121Y376056D01*
G03X355796Y378384I-1384J753D01*
G01X355667D01*
G02X353722Y381872I70J2325D01*
G03X353741Y383413I-1365J787D01*
G01X353722Y383447D01*
X353697Y383489D01*
G02X353722Y385772I2040J1119D01*
G03X353741Y387313I-1365J787D01*
G01X352968Y388695D01*
Y394576D01*
X355663Y397271D01*
Y406071D01*
X356790Y407198D01*
Y407982D01*
G01X348978Y369010D02*
G02X350118Y371593I3496J0D01*
G02X350342Y372122I2238J-636D01*
G03Y373696I-1364J787D01*
G02X350307Y375962I2015J1164D01*
G01X350342Y376022D01*
G03Y377596I-1364J787D01*
G02X350307Y379862I2015J1164D01*
G01X350342Y379922D01*
G03Y381496I-1364J787D01*
G02X350307Y383762I2015J1164D01*
G01X350342Y383822D01*
G03Y385396I-1364J787D01*
G02X350307Y387662I2015J1164D01*
G01X350342Y387722D01*
G03X350764Y388570I-6161J3595D01*
G01Y395372D01*
X353892Y398500D01*
Y405250D01*
X352790Y406352D01*
Y407700D01*
G01X352357Y367060D02*
X351058Y370060D01*
X350993Y370172D01*
G02Y371746I1364J787D01*
G01X351018Y371788D01*
G03X350993Y374073I-2040J1120D01*
G02Y375647I1364J787D01*
G01X351028Y375707D01*
G03X350993Y377973I-2050J1102D01*
G02Y379547I1364J787D01*
G01X351028Y379607D01*
G03X350993Y381873I-2050J1102D01*
G02Y383447I1364J787D01*
G01X351028Y383507D01*
G03X350993Y385773I-2050J1102D01*
G02Y387347I1364J787D01*
G02X351392Y388000I13170J-7599D01*
G03X351892Y389200I-3068J1983D01*
G01Y395000D01*
X354790Y397898D01*
Y407727D01*
G01X359117Y378760D02*
X357818Y381759D01*
X357752Y381872D01*
G02X357733Y383413I1365J787D01*
G01X357752Y383447D01*
X357777Y383489D01*
G03X357752Y385772I-2040J1119D01*
G02X358058Y387727I1365J788D01*
G03X358592Y388600I-1223J1348D01*
G01Y396300D01*
X360818Y398526D01*
Y405327D01*
X362790Y407299D01*
Y408331D01*
G01X355737Y380709D02*
X357034Y383705D01*
X357121Y383856D01*
G03X357102Y385397I-1384J754D01*
G02X357431Y388163I2015J1163D01*
G03X357592Y388700I-450J427D01*
G01Y397400D01*
X359618Y399426D01*
Y406326D01*
X360790Y407498D01*
Y408385D01*
G01X359117Y386560D02*
Y387880D01*
X359718Y388481D01*
Y395626D01*
X362018Y397926D01*
Y404625D01*
X364790Y407397D01*
Y408465D01*
G01X362497Y384609D02*
X360918Y388040D01*
Y394726D01*
X363218Y397026D01*
Y404227D01*
X366790Y407799D01*
Y408694D01*
G01X376017Y216909D02*
X374863Y217575D01*
X374553Y217491D01*
G03X374442Y216931I1465J-581D01*
G03X374633Y216156I1576J-23D01*
G01X374652Y216122D01*
X374677Y216080D01*
G02X374652Y213797I-2040J-1119D01*
G03X374633Y212256I1365J-787D01*
G01X374652Y212222D01*
X374677Y212180D01*
G02X374652Y209897I-2040J-1119D01*
G03X374633Y208356I1365J-787D01*
G01X374649Y208327D01*
X374652Y208322D01*
G02Y205996I-2015J-1163D01*
G01X374398Y205556D01*
Y202516D01*
X380733Y196181D01*
Y191286D01*
X380882Y191137D01*
Y191050D01*
G01X372637Y218860D02*
X373078Y218420D01*
G02X373690Y216941I-1479J-1478D01*
G03X373977Y215789I2326J-32D01*
G01X374002Y215747D01*
X374021Y215713D01*
G02X374002Y214172I-1384J-754D01*
G03X373977Y211889I2015J-1164D01*
G01X374002Y211847D01*
X374021Y211813D01*
G02X374002Y210272I-1384J-754D01*
G03X373976Y207993I2015J-1163D01*
G01X373996Y207958D01*
X374002Y207947D01*
G02Y206372I-1365J-787D01*
G01X373648Y205757D01*
Y202205D01*
X379983Y195870D01*
Y191331D01*
X379822Y191170D01*
G01X382777Y213009D02*
X382786Y213000D01*
X386380D01*
G02X388172Y209897I0J-2069D01*
G03X388153Y208356I1365J-787D01*
G01X388172Y208322D01*
X388692Y207502D01*
Y205000D01*
X392182Y201510D01*
Y198006D01*
X391284Y197108D01*
Y194246D01*
X392026Y193504D01*
Y192547D01*
G01X376017Y224709D02*
X377316Y221710D01*
X377382Y221597D01*
G02X377401Y220056I-1365J-787D01*
G01X377382Y220022D01*
X377357Y219980D01*
G03X377382Y217697I2040J-1119D01*
G02X377401Y216156I-1365J-787D01*
G01X377382Y216122D01*
X377357Y216080D01*
G03X377382Y213797I2040J-1119D01*
G01X378892Y211177D01*
X379480Y209954D01*
X380439Y208340D01*
G02X380762Y207946I-1041J-1183D01*
G01X381485Y206696D01*
G03X382442Y205450I5226J3024D01*
G01X385719Y202173D01*
Y200166D01*
G01X365877Y218860D02*
X365465Y218447D01*
G03X364824Y216901I1546J-1547D01*
G02X364537Y215789I-2326J7D01*
G01X364512Y215747D01*
X364493Y215713D01*
G03X364512Y214172I1384J-754D01*
G01X365148Y213071D01*
Y205148D01*
X364258Y203608D01*
Y201865D01*
X371745Y194378D01*
Y191247D01*
X371181Y190683D01*
Y189211D01*
X371346Y189046D01*
G01X372637Y222760D02*
X371483Y223426D01*
X371173Y223342D01*
G03X371272Y221974I1464J-582D01*
G02Y219648I-2015J-1163D01*
G03Y218074I1365J-787D01*
G02Y215748I-2015J-1163D01*
G03Y214174I1365J-787D01*
G02X371273Y211849I-2015J-1163D01*
G01X371272D01*
G03X371061Y211016I1365J-789D01*
G01Y202114D01*
X376642Y196533D01*
Y192850D01*
X377742Y191750D01*
Y189250D01*
X377946Y189046D01*
G01X365877Y222760D02*
X364723Y223425D01*
X364413Y223341D01*
G03X364302Y222785I1465J-581D01*
G03X365818Y221185I1576J-25D01*
G01X365947D01*
G02X367892Y217697I-70J-2325D01*
G03X367873Y216156I1365J-787D01*
G01X367920Y216072D01*
X367917Y216080D01*
G02X367893Y213798I-2040J-1120D01*
G01X367659Y213394D01*
X367658Y212399D01*
Y207623D01*
X368292Y206989D01*
Y201499D01*
X374092Y195699D01*
Y192001D01*
X374478Y191615D01*
Y189014D01*
X374646Y188846D01*
G01X362497Y216909D02*
X363651Y217575D01*
X363961Y217491D01*
G02X364072Y216904I-1465J-581D01*
G02X363881Y216156I-1576J4D01*
G01X363862Y216122D01*
X363837Y216080D01*
G03X363862Y213797I2040J-1119D01*
G01X364398Y212869D01*
Y205350D01*
X363508Y203810D01*
Y201554D01*
X370995Y194067D01*
Y191558D01*
X370431Y190994D01*
Y189158D01*
X370286Y189013D01*
Y188926D01*
G01X369257Y224709D02*
X369707Y224259D01*
G02X370310Y222803I-1456J-1456D01*
G03X370622Y221598I2326J-41D01*
G02Y220024I-1365J-787D01*
G03Y217698I2015J-1163D01*
G02Y216124I-1365J-787D01*
G03Y213798I2015J-1163D01*
G01X370623D01*
G02X370642Y212258I-1366J-787D01*
G03X370311Y211006I1995J-1197D01*
G01Y201803D01*
X375892Y196222D01*
Y192539D01*
X376992Y191439D01*
Y189119D01*
X376886Y189013D01*
Y188926D01*
G01X362497Y224709D02*
X362943Y224264D01*
G02X363550Y222797I-1467J-1466D01*
G03X365792Y220435I2327J-37D01*
G01X365921D01*
G02X367242Y218072I-44J-1575D01*
G03X367217Y215789I2015J-1164D01*
G01X367242Y215747D01*
X367261Y215713D01*
G02X367242Y214173I-1384J-753D01*
G01X366909Y213595D01*
X366908Y213246D01*
Y207312D01*
X367542Y206678D01*
Y201188D01*
X373342Y195388D01*
Y191690D01*
X373728Y191304D01*
Y188955D01*
X373586Y188813D01*
Y188726D01*
G01X386157Y211060D02*
X387456Y208060D01*
X387738Y207573D01*
Y204455D01*
X390192Y202001D01*
Y193501D01*
X390516Y193177D01*
Y192316D01*
G01X379397Y207159D02*
Y202275D01*
X384136Y197536D01*
Y195798D01*
G01X382777Y224709D02*
X381092Y220900D01*
Y212400D01*
X382092Y211400D01*
X383742Y210550D01*
X384498Y209794D01*
Y206494D01*
X389006Y201986D01*
Y191891D01*
G01X379397Y222760D02*
X378492Y221855D01*
Y221385D01*
G02X378057Y219689I-3524J0D01*
G01X378032Y219647D01*
X378013Y219613D01*
G03X378032Y218072I1384J-754D01*
G02X378057Y215789I-2015J-1164D01*
G01X378032Y215747D01*
X378013Y215713D01*
G03X378032Y214172I1384J-754D01*
G01X379945Y210853D01*
X380846Y209300D01*
X381303Y208511D01*
X381677Y207864D01*
G03X383492Y205500I9909J5729D01*
G01X387496Y201496D01*
Y199996D01*
G01X386157Y218860D02*
X387454Y215864D01*
X387522Y215747D01*
G03X389467Y214584I2015J1162D01*
G01X389537D01*
G02X390901Y212222I0J-1575D01*
G01X390866Y212162D01*
G03X390901Y209896I2050J-1102D01*
G01X390933Y209840D01*
G02X391111Y209191I-1396J-732D01*
G01Y207481D01*
X394608Y203984D01*
Y200020D01*
X393929Y199341D01*
Y196308D01*
X394608Y195629D01*
Y194462D01*
X393948Y193802D01*
Y192984D01*
G01X376017Y213009D02*
X376030D01*
X377598Y211441D01*
Y201864D01*
X382514Y196948D01*
Y195289D01*
G01X386157Y222760D02*
X387454Y219764D01*
X387522Y219647D01*
G03X389467Y218484I2015J1162D01*
G01X389537D01*
G02X390888Y217719I0J-1575D01*
G01X390901Y217696D01*
G03X392818Y216535I2015J1164D01*
G01X392960D01*
G02X394281Y214172I-44J-1575D01*
G03X394256Y211889I2015J-1164D01*
G01X394281Y211847D01*
X394300Y211813D01*
G02X394281Y210272I-1384J-754D01*
G03X393892Y208819I2521J-1453D01*
G01Y207900D01*
G03X394246Y207044I1210J-1D01*
G01X396692Y204599D01*
Y201324D01*
X397914Y200102D01*
Y195410D01*
G01X399676Y218860D02*
X402750Y215786D01*
Y198358D01*
X404353Y196755D01*
Y195531D01*
G01X396296Y228610D02*
X398245Y225987D01*
X398311Y225872D01*
G02X398336Y223589I-2015J-1164D01*
G01X398311Y223547D01*
X398292Y223513D01*
G03X399617Y221185I1384J-753D01*
G01X399807D01*
X403500Y217492D01*
Y202893D01*
X405992Y200401D01*
Y194366D01*
G01X389537Y224709D02*
X391491Y222081D01*
X391552Y221973D01*
G02X391587Y219707I-2015J-1164D01*
G01X391552Y219647D01*
G03X392916Y217285I1364J-787D01*
G01X392986D01*
G02X394931Y213797I-70J-2325D01*
G03X394912Y212256I1365J-787D01*
G01X394931Y212222D01*
X394956Y212180D01*
G02X394931Y209897I-2040J-1119D01*
G03X394642Y208818I1871J-1079D01*
G01Y208500D01*
G03X394889Y207902I845J-1D01*
G01X397592Y205200D01*
Y201486D01*
X399537Y199541D01*
Y195507D01*
G01X407706Y216909D02*
X405302D01*
X404892Y216499D01*
Y203500D01*
X406892Y201500D01*
Y196000D01*
X407617Y195275D01*
Y194172D01*
G01X399676Y222760D02*
X408418Y218500D01*
X409392Y217526D01*
Y216500D01*
X405892Y209500D01*
Y204000D01*
X407892Y202000D01*
Y197000D01*
X409155Y195737D01*
Y194050D01*
G01X401250Y195652D02*
Y211731D01*
X400346Y212635D01*
X399591D01*
G02X397636Y216080I85J2325D01*
G01X397661Y216122D01*
X397680Y216156D01*
G03X397661Y217697I-1384J754D01*
G01X397013Y218820D01*
G03X396296Y219234I-717J-414D01*
G01X396252D01*
G02X394931Y220022I44J1575D01*
G01X394865Y220138D01*
X392916Y222760D01*
G01X389537Y216909D02*
X390432Y215813D01*
X391237Y214730D01*
X391552Y214173D01*
G02X391587Y211907I-2015J-1164D01*
G01X391552Y211847D01*
G03Y210273I1364J-787D01*
G01X392092Y209284D01*
Y208000D01*
X393941Y206151D01*
X393942D01*
X395692Y204401D01*
Y199818D01*
X394694Y198820D01*
Y196683D01*
X395749Y195628D01*
Y192972D01*
G01X402806Y195555D02*
Y196677D01*
X402000Y197483D01*
Y212092D01*
X400707Y213385D01*
X399617D01*
G02X398292Y215713I59J1575D01*
G01X398311Y215747D01*
X398336Y215789D01*
G03X398311Y218072I-2040J1119D01*
G01X397661Y219198D01*
G02Y220022I714J412D01*
G01X397680Y220056D01*
G03X397661Y221597I-1384J754D01*
G01X397595Y221710D01*
X396296Y224709D01*
G01X415634Y220096D02*
Y218765D01*
X415376Y218507D01*
G03X413676Y217450I258J-2311D01*
G01X413624Y217360D01*
G03X413599Y215075I2010J-1165D01*
G01X413624Y215033D01*
X413682Y214934D01*
G03X415634Y213871I1952J1261D01*
G01X416094D01*
G02X417070Y213090I-460J-1575D01*
G02X417089Y211537I-1436J-794D01*
G01X417046Y211460D01*
G03X417070Y209190I2118J-1113D01*
G01X417209Y208940D01*
Y200499D01*
X420197Y197511D01*
Y192370D01*
X421316Y191251D01*
Y182253D01*
X423058Y180511D01*
Y179166D01*
X422390Y178498D01*
G01X415634Y216196D02*
Y217527D01*
X415407Y217754D01*
G03X414328Y217076I227J-1559D01*
G01X414274Y216983D01*
G03X414255Y215444I1360J-786D01*
G01X414331Y215311D01*
G03X415634Y214621I1303J885D01*
G01X416198D01*
G02X416756Y214409I-564J-2324D01*
G02X417008Y214254I-1101J-2072D01*
G02X417752Y211183I-1374J-1958D01*
G01X417728Y211140D01*
G03Y209554I1436J-793D01*
G01X417957Y209141D01*
Y200813D01*
X420946Y197824D01*
Y192681D01*
X420948Y192679D01*
Y192677D01*
X422064Y191561D01*
Y182563D01*
X423806Y180821D01*
Y179585D01*
X424890Y178501D01*
G01X415634Y227896D02*
X411198Y223460D01*
Y205441D01*
X414191Y202448D01*
Y199202D01*
X417178Y196215D01*
Y190825D01*
X418298Y189705D01*
Y179406D01*
X417666Y178774D01*
G01X419890Y178501D02*
X419046Y179345D01*
Y190015D01*
X417927Y191134D01*
Y196572D01*
X417925D01*
X414944Y199552D01*
X414939Y199558D01*
Y202758D01*
X411946Y205751D01*
X411948Y205753D01*
Y223143D01*
X414466Y225661D01*
X415700D01*
X417149Y227110D01*
G03Y228684I-1365J787D01*
G02X415634Y231797I21416J12348D01*
G01X386192Y406737D02*
Y405992D01*
X385792Y405592D01*
Y404104D01*
X381092Y399404D01*
Y391000D01*
G02X380762Y389672I-2472J-91D01*
G03X380737Y387389I2015J-1164D01*
G01X380762Y387347D01*
X380781Y387313D01*
G02X380762Y385772I-1384J-754D01*
G03X380737Y383489I2015J-1164D01*
G01X380762Y383447D01*
X380781Y383413D01*
G02X380762Y381872I-1384J-754D01*
G03X380737Y379589I2015J-1164D01*
G01X380762Y379547D01*
X380781Y379513D01*
G02X379456Y377185I-1384J-753D01*
G01X379327D01*
G03X377382Y376022I70J-2325D01*
G01X377314Y375905D01*
X376017Y372909D01*
G01X375244Y409402D02*
Y409358D01*
X375374Y409228D01*
Y406882D01*
X370842Y402350D01*
Y391999D01*
X370727Y391808D01*
X370599Y391580D01*
X370597Y391577D01*
G03X370622Y389297I2040J-1118D01*
G02X370641Y387756I-1365J-787D01*
G01X370622Y387722D01*
X370597Y387680D01*
G03X370622Y385397I2040J-1119D01*
G02X370641Y383856I-1365J-787D01*
G01X370622Y383822D01*
X370597Y383780D01*
G03X370622Y381497I2040J-1119D01*
G02X370641Y379956I-1365J-787D01*
G01X370622Y379922D01*
X370597Y379880D01*
G03X370622Y377597I2040J-1119D01*
G02X370641Y376056I-1365J-787D01*
G01X370622Y376022D01*
X370597Y375980D01*
G03X370325Y374592I2039J-1120D01*
G02X369997Y373649I-1139J-132D01*
G01X369257Y372909D01*
G01X362497D02*
X363319Y373730D01*
G03X363576Y374513I-647J646D01*
G02X365807Y377185I2300J347D01*
G01X365936D01*
G03X367261Y379513I-59J1575D01*
G01X367242Y379547D01*
X367217Y379589D01*
G02X367242Y381872I2040J1119D01*
G03X367261Y383413I-1365J787D01*
G01X367242Y383447D01*
G02X366817Y386037I3227J1859D01*
G01X366842Y386160D01*
Y393482D01*
X368242Y394882D01*
Y403411D01*
X372342Y407511D01*
Y409249D01*
X372212Y409379D01*
Y409466D01*
G01X372637Y378760D02*
X373051Y379175D01*
G03X373690Y380716I-1541J1542D01*
G02X374002Y381872I2327J-8D01*
G03X374021Y383413I-1365J787D01*
G01X374002Y383447D01*
X373977Y383489D01*
G02X374002Y385772I2040J1119D01*
G03X374021Y387313I-1365J787D01*
G01X374002Y387347D01*
X373977Y387389D01*
G02X374002Y389672I2040J1119D01*
G01X374003Y389673D01*
G03X374208Y390334I-1366J786D01*
G03X374020Y391216I-1571J126D01*
G01X373688Y391812D01*
Y401696D01*
X378843Y406851D01*
Y409042D01*
X378666Y409219D01*
Y409306D01*
G01X362497Y380709D02*
X363651Y380044D01*
X363961Y380128D01*
G03X364066Y380566I-1465J583D01*
G03X363862Y381497I-1570J144D01*
G02X363768Y383645I2015J1164D01*
G02X363837Y383780I2105J-991D01*
G01X363862Y383822D01*
G03X364186Y384756I-2274J1312D01*
G01Y394455D01*
X365742Y396011D01*
Y404410D01*
X369042Y407710D01*
Y409296D01*
X368910Y409428D01*
Y409472D01*
G01X372637Y374860D02*
X371483Y374194D01*
X371173Y374278D01*
G02X371072Y374679I1465J582D01*
G02X371253Y375613I1566J181D01*
G01X371272Y375647D01*
X371297Y375689D01*
G03X371272Y377972I-2040J1119D01*
G02X371253Y379513I1365J787D01*
G01X371272Y379547D01*
X371297Y379589D01*
G03X371272Y381872I-2040J1119D01*
G02X371253Y383413I1365J787D01*
G01X371272Y383447D01*
X371297Y383489D01*
G03X371272Y385772I-2040J1119D01*
G02X371253Y387313I1365J787D01*
G01X371272Y387347D01*
X371297Y387389D01*
G03X371272Y389672I-2040J1119D01*
G02X371252Y391211I1365J787D01*
G01X371376Y391430D01*
X371592Y391791D01*
Y402039D01*
X376124Y406571D01*
Y409222D01*
X376304Y409402D01*
G01X365877Y374860D02*
X364723Y374194D01*
X364413Y374278D01*
G02X364319Y374625I1464J583D01*
G02X365833Y376435I1558J235D01*
G01X365962D01*
G03X367917Y379880I-85J2325D01*
G01X367892Y379922D01*
X367873Y379956D01*
G02X367892Y381497I1384J754D01*
G03X367917Y383780I-2015J1164D01*
G01X367892Y383822D01*
G02X367553Y385889I2577J1484D01*
G01X367592Y386084D01*
Y393171D01*
X368992Y394571D01*
Y403100D01*
X373092Y407200D01*
Y409166D01*
X373272Y409346D01*
Y409466D01*
G01X376017Y380709D02*
X374863Y380044D01*
X374553Y380128D01*
G02X374442Y380714I1465J581D01*
G02X374652Y381497I1576J-3D01*
G03X374677Y383780I-2015J1164D01*
G01X374652Y383822D01*
X374633Y383856D01*
G02X374652Y385397I1384J754D01*
G03X374677Y387680I-2015J1164D01*
G01X374652Y387722D01*
X374633Y387756D01*
G02X374652Y389297I1384J754D01*
G03X374957Y390274I-2014J1165D01*
G03X374677Y391579I-2320J185D01*
G01X374438Y392007D01*
Y401385D01*
X379593Y406540D01*
Y409053D01*
X379726Y409186D01*
G01X369970Y409511D02*
Y409395D01*
X369792Y409217D01*
Y407399D01*
X366492Y404099D01*
Y395700D01*
X364936Y394144D01*
Y384705D01*
G02X364510Y383442I-3349J426D01*
G01X364493Y383413D01*
G03X364449Y383327I1380J-761D01*
G03X364512Y381872I1428J-667D01*
G02X364814Y380498I-2015J-1163D01*
G03X365197Y379440I1321J-120D01*
G01X365877Y378760D01*
G01X390192Y406540D02*
Y405766D01*
X388992Y404566D01*
Y403500D01*
X386092Y400600D01*
Y391500D01*
X384492Y389900D01*
Y386324D01*
X382777Y384609D01*
G01X386157Y374860D02*
X387456Y377859D01*
X387522Y377972D01*
G02X389452Y379134I2015J-1163D01*
G01X389537D01*
G03X390888Y379899I0J1575D01*
G01X390901Y379922D01*
G02X392846Y381085I2015J-1162D01*
G01X392975D01*
G03X394300Y383413I-59J1575D01*
G01X394281Y383447D01*
X394256Y383489D01*
G02X394281Y385772I2040J1119D01*
G03X394300Y387313I-1365J787D01*
G01X394281Y387347D01*
X394256Y387389D01*
G02X394281Y389672I2040J1119D01*
G03X394492Y390459I-1363J787D01*
G01Y392500D01*
X396892Y394900D01*
Y403500D01*
X400192Y406800D01*
Y407615D01*
G01X408192Y405358D02*
Y404216D01*
X408692Y403716D01*
Y401800D01*
X405992Y399100D01*
Y386200D01*
X400892Y381100D01*
Y379976D01*
X399676Y378760D01*
G01X396296Y369010D02*
X400402D01*
X402392Y371000D01*
X404692D01*
X407892Y374200D01*
Y381788D01*
X409492Y383388D01*
Y396200D01*
X413592Y400300D01*
Y405292D01*
X414192Y405892D01*
Y406826D01*
G01X392192Y406612D02*
Y405800D01*
X390092Y403700D01*
Y402400D01*
X387642Y399950D01*
Y390750D01*
X386157Y389265D01*
Y386560D01*
G01X389537Y372909D02*
X391488Y375534D01*
X391565Y375670D01*
G02X392916Y376435I1351J-810D01*
G01X393001D01*
G03X394956Y379880I-85J2325D01*
G01X394931Y379922D01*
X394912Y379956D01*
G02X394931Y381497I1384J754D01*
G03X394956Y383780I-2015J1164D01*
G01X394931Y383822D01*
X394912Y383856D01*
G02X394931Y385397I1384J754D01*
G03X394956Y387680I-2015J1164D01*
G01X394931Y387722D01*
X394912Y387756D01*
G02X394931Y389297I1384J754D01*
G02X395861Y390435I3936J-2268D01*
G01X395892Y390466D01*
Y391900D01*
X398092Y394100D01*
Y400200D01*
X400192Y402300D01*
Y404700D01*
X402192Y406700D01*
Y407687D01*
G01X403056Y380709D02*
X407392Y385045D01*
Y398400D01*
X410692Y401700D01*
Y404365D01*
X410192Y404865D01*
Y405805D01*
G01X399676Y374860D02*
X403372D01*
X405492Y376980D01*
Y381460D01*
X408492Y384460D01*
Y397400D01*
X412192Y401100D01*
Y406100D01*
G01X384192Y406734D02*
Y404304D01*
X379192Y399304D01*
Y394211D01*
G02X378892Y392900I-3015J0D01*
G02X378032Y391247I-28098J13568D01*
G01X378013Y391213D01*
G03X378032Y389672I1384J-754D01*
G02X378275Y389071I-2015J-1164D01*
G02X378327Y388792I-2257J-565D01*
G02X378344Y388500I-2310J-281D01*
G03X379397Y386560I2314J0D01*
G01X382777Y372909D02*
X384074Y375905D01*
X384161Y376056D01*
G03X384142Y377597I-1384J754D01*
G02X384117Y379880I2015J1164D01*
G01X384142Y379922D01*
X384161Y379956D01*
G03X384142Y381497I-1384J754D01*
G02X386087Y384985I2015J1163D01*
G01X386216D01*
G03X387732Y386596I-59J1575D01*
G01Y389040D01*
X388742Y390050D01*
Y397150D01*
X393492Y401900D01*
Y405000D01*
X394192Y405700D01*
Y406684D01*
G01X388192Y406629D02*
Y405896D01*
X387512Y405216D01*
Y403820D01*
X382092Y398400D01*
Y390400D01*
G03X381412Y389297I18375J-12089D01*
G03X381393Y387756I1365J-787D01*
G01X381412Y387722D01*
X381437Y387680D01*
G02X381412Y385397I-2040J-1119D01*
G03X381393Y383856I1365J-787D01*
G01X381412Y383822D01*
X381437Y383780D01*
G02X381412Y381497I-2040J-1119D01*
G03X381393Y379956I1365J-787D01*
G01X381412Y379922D01*
X381437Y379880D01*
G02X381412Y377597I-2040J-1119D01*
G03X381204Y376905I1365J-788D01*
G02X379397Y374860I-2061J0D01*
G01X386157Y378760D02*
X387522Y381872D01*
G02X389452Y383034I2015J-1163D01*
G01X389537D01*
G03X390901Y385396I0J1575D01*
G02X390866Y387662I2015J1164D01*
G01X390901Y387722D01*
G03Y389296I-1364J787D01*
G03X390553Y389763I-2180J-1261D01*
G01X390392Y389924D01*
Y391800D01*
X394592Y396000D01*
Y404614D01*
X396192Y406214D01*
Y406935D01*
G01X392916Y374860D02*
X396150Y375234D01*
X396340D01*
G03X397661Y377597I-44J1575D01*
G02X397636Y379880I2015J1164D01*
G01X397661Y379922D01*
X397680Y379956D01*
G03X397661Y381497I-1384J754D01*
G02X397636Y383780I2015J1164D01*
G01X397661Y383822D01*
G03X397872Y384589I-1289J767D01*
G01Y391680D01*
X399492Y393300D01*
Y399900D01*
X401392Y401800D01*
Y403600D01*
X404192Y406400D01*
Y407669D01*
G01X389537Y380709D02*
X391488Y383334D01*
X391552Y383447D01*
X391587Y383507D01*
G03X391552Y385773I-2050J1102D01*
G02Y387347I1364J787D01*
G01X391587Y387407D01*
G03X391552Y389673I-2050J1102D01*
G02X391292Y390643I1679J970D01*
G01Y391400D01*
X395692Y395800D01*
Y403800D01*
X398192Y406300D01*
Y407132D01*
G01X406192Y405734D02*
Y404800D01*
X404692Y403300D01*
Y401600D01*
X405092Y401200D01*
Y388000D01*
X401792Y384700D01*
X400792D01*
X400327Y384235D01*
X399632D01*
G03X398311Y381872I44J-1575D01*
G02X398336Y379589I-2015J-1164D01*
G01X398311Y379547D01*
X398292Y379513D01*
G03X398311Y377972I1384J-754D01*
G02X398336Y375689I-2015J-1164D01*
G01X398311Y375647D01*
X398245Y375531D01*
X396296Y372909D01*
G01X376017Y384609D02*
X377314Y387605D01*
X377401Y387756D01*
G03X377382Y389297I-1384J754D01*
G02Y391623I2015J1163D01*
G03X377992Y393900I-3945J2277D01*
G01Y399864D01*
X382192Y404064D01*
Y407043D01*
G01X424599Y364100D02*
X425878Y362821D01*
X427138D01*
G03X428459Y363609I-44J1575D01*
G02X430404Y364772I2015J-1162D01*
G01X430544D01*
G02X432489Y363609I-70J-2325D01*
G03X435205Y363586I1365J787D01*
G01X435218Y363609D01*
G02X437163Y364772I2015J-1162D01*
G01X437303D01*
G02X439248Y363609I-70J-2325D01*
G03X441978I1365J787D01*
G02X443923Y364772I2015J-1162D01*
G01X444063D01*
G02X446008Y363609I-70J-2325D01*
G03X448738I1365J787D01*
G01X449165Y364036D01*
X451837D01*
X453083Y362790D01*
X454497D01*
X456415Y360872D01*
X458624D01*
X460472Y362720D01*
X461887D01*
X463287Y364120D01*
X465443D01*
X466941Y362622D01*
X468676D01*
X470090Y364036D01*
X471994D01*
X473209Y362821D01*
X475693D01*
X476964Y364092D01*
X478384D01*
X479337Y363139D01*
G03X480105Y362821I768J768D01*
G01X481427D01*
G03X482115Y363106I0J973D01*
G01X482271Y363262D01*
G03X482537Y363609I-1184J1183D01*
G02X484482Y364772I2015J-1162D01*
G01X484611D01*
G03X485917Y365559I-59J1575D01*
G02X487847Y366721I2015J-1163D01*
G01X487976D01*
G03X489506Y368294I-44J1573D01*
G01Y370914D01*
X490819Y372227D01*
G01X425594Y357907D02*
X426028Y358341D01*
X427799D01*
X429320Y356820D01*
X430658D01*
X432571Y354907D01*
X434497D01*
X436300Y356710D01*
X437895D01*
X439594Y355011D01*
X441457D01*
X443090Y356644D01*
X444549D01*
X446391Y354802D01*
X448041D01*
X449806Y356567D01*
X451615D01*
X453275Y354907D01*
X454787D01*
X456333Y356453D01*
X458456D01*
X460228Y354681D01*
X461600D01*
X463451Y356532D01*
X464826D01*
X466486Y354872D01*
X468328D01*
X470296Y356840D01*
X471670D01*
X473390Y358560D01*
X475380D01*
X476943Y360123D01*
X479318D01*
X480519Y358922D01*
X482229D01*
X483648Y360341D01*
X485148D01*
X487148Y362341D01*
X488148D01*
X490148Y364341D01*
G01X424678Y360661D02*
X425008Y360991D01*
G01X425508Y361491D02*
X426087Y362070D01*
X428600D01*
X430270Y360400D01*
X431590D01*
X433068Y358922D01*
X434507D01*
X435765Y360180D01*
X438702D01*
X439960Y358922D01*
X441266D01*
X442584Y360240D01*
X445402D01*
X446720Y358922D01*
X448026D01*
X449694Y360590D01*
X451630D01*
X453298Y358922D01*
X454786D01*
X455986Y360122D01*
X458928D01*
X460128Y358922D01*
X461546D01*
X463324Y360700D01*
X465222D01*
X467000Y358922D01*
X468306D01*
X470074Y360690D01*
X472270D01*
X473651Y362071D01*
X475699D01*
X476897Y360873D01*
X478445D01*
X479643Y362071D01*
X482312D01*
X482395Y362154D01*
G03X483077Y363044I-3031J3029D01*
G01X483187Y363234D01*
G02X484508Y364022I1365J-787D01*
G01X484637D01*
G03X486567Y365184I-85J2325D01*
G02X487873Y365971I1365J-788D01*
G01X488002D01*
G03X490185Y367715I-70J2325D01*
G01X490803Y368333D01*
X492067D01*
X493734Y370000D01*
G01X422594Y220096D02*
Y221427D01*
X422822Y221655D01*
G02X423959Y220884I-228J-1560D01*
G03X425889Y219722I2015J1163D01*
G01X426018D01*
G02X427339Y217359I-44J-1575D01*
G03Y215033I2015J-1163D01*
G02Y213457I-1365J-788D01*
G03Y211131I2015J-1163D01*
G01X427919Y210125D01*
Y205270D01*
X429308Y203881D01*
Y195393D01*
X430422Y194279D01*
Y189163D01*
X436418Y183167D01*
Y180551D01*
X435698Y179831D01*
G01X422594Y227896D02*
Y227897D01*
X424544Y225273D01*
X424609Y225160D01*
G02Y222834I-2015J-1163D01*
G03X425915Y220472I1364J-788D01*
G01X426044D01*
G02X427989Y216984I-70J-2325D01*
G03Y215408I1365J-788D01*
G02Y213082I-2015J-1163D01*
G03Y211506I1365J-788D01*
G01X428669Y210327D01*
Y205581D01*
X430058Y204192D01*
Y195701D01*
X431170Y194589D01*
Y189473D01*
X437166Y183477D01*
Y180875D01*
X438210Y179831D01*
G01X419214Y218147D02*
Y219478D01*
X418986Y219706D01*
G03X419155Y216572I227J-1559D01*
G01X419298D01*
G02X421229Y215411I-83J-2325D01*
G01X421539Y214874D01*
Y209121D01*
X421056Y208638D01*
Y204351D01*
X424018Y201389D01*
Y193262D01*
X425132Y192148D01*
Y186925D01*
X428626Y183431D01*
Y179283D01*
X428781Y179128D01*
Y179041D01*
G01X419214Y225947D02*
Y227278D01*
X419442Y227506D01*
G02X419912Y227359I-229J-1559D01*
G02X420579Y225160I-698J-1412D01*
G03Y222834I2015J-1163D01*
G02Y221260I-1365J-787D01*
G03X422509Y217772I2015J-1163D01*
G01X422638D01*
G02X424169Y216139I-44J-1575D01*
G01Y208792D01*
X423476Y208099D01*
Y205141D01*
X426288Y202329D01*
Y194385D01*
X427402Y193271D01*
Y187912D01*
X432214Y183100D01*
Y179737D01*
X432059Y179582D01*
Y179495D01*
G01X419214Y222047D02*
G02X417552Y219786I-7767J3968D01*
G03X419129Y215822I1577J-1668D01*
G01X419283D01*
G02X420579Y215035I-69J-1575D01*
G01X420789Y214672D01*
Y209432D01*
X420306Y208949D01*
Y204040D01*
X423268Y201078D01*
Y192951D01*
X424382Y191837D01*
Y186614D01*
X427876Y183120D01*
Y179283D01*
X427721Y179128D01*
Y179041D01*
G01X419214Y229847D02*
X420245Y228033D01*
G02X421229Y224784I-1031J-2086D01*
G03Y223210I1365J-787D01*
G02Y220884I-2015J-1163D01*
G03X422550Y218522I1365J-787D01*
G01X422679D01*
G02X424919Y216126I-85J-2325D01*
G01Y208481D01*
X424226Y207788D01*
Y205452D01*
X427038Y202640D01*
Y194696D01*
X428152Y193582D01*
Y188223D01*
X432964Y183411D01*
Y179737D01*
X433119Y179582D01*
Y179495D01*
G01X425974Y222047D02*
Y223378D01*
X426202Y223606D01*
G02X427339Y222834I-228J-1559D01*
G03X429284Y221671I2015J1162D01*
G01X429354D01*
G02X430718Y219309I0J-1575D01*
G01X430683Y219249D01*
G03X430718Y216983I2050J-1102D01*
G02Y215409I-1364J-787D01*
G01X430676Y215336D01*
G03X430718Y213082I2057J-1089D01*
G01X430929Y212717D01*
Y206291D01*
X432328Y204892D01*
Y195601D01*
X433440Y194489D01*
Y190413D01*
X441576Y182277D01*
Y180697D01*
X440710Y179831D01*
G01X425974Y225947D02*
Y224616D01*
X426231Y224359D01*
G02X427989Y223209I-257J-2312D01*
G03X429310Y222421I1365J787D01*
G01X429452D01*
G02X431404Y218994I-98J-2325D01*
G01X431369Y218934D01*
G03Y217360I1364J-787D01*
G02X431404Y215094I-2015J-1164D01*
G01X431369Y215034D01*
X431350Y215000D01*
G03X431369Y213459I1383J-754D01*
G01X431677Y212925D01*
Y206604D01*
X433078Y205203D01*
Y195909D01*
X434188Y194799D01*
Y190723D01*
X442324Y182587D01*
Y180717D01*
X443210Y179831D01*
G01X454692Y184800D02*
X455662Y185770D01*
Y189600D01*
X449992Y195270D01*
Y199300D01*
X443693Y205599D01*
Y210532D01*
X444257Y211543D01*
G03X444276Y213084I-1365J787D01*
G01X444257Y213118D01*
X444232Y213160D01*
G02X444257Y215443I2040J1119D01*
G03X444238Y216984I-1384J754D01*
G02X444213Y219267I2015J1164D01*
G01X444238Y219309D01*
X444257Y219343D01*
G03X444238Y220884I-1384J754D01*
G02X444213Y223167I2015J1164D01*
G01X444238Y223209D01*
X444257Y223243D01*
G03X444238Y224784I-1384J754D01*
G02X444213Y227067I2015J1164D01*
G01X444238Y227109D01*
X444257Y227143D01*
G03X444238Y228684I-1384J754D01*
G02Y231010I2015J1163D01*
G01X444303Y231124D01*
X446253Y233746D01*
G01X457192Y184900D02*
X456412Y185680D01*
Y189912D01*
X450742Y195582D01*
Y199611D01*
X444443Y205910D01*
Y210336D01*
X444913Y211176D01*
G03X444938Y213459I-2015J1164D01*
G01X444913Y213501D01*
X444894Y213535D01*
G02X444913Y215076I1384J754D01*
G03X444888Y217359I-2040J1119D01*
G02X444869Y218900I1365J787D01*
G01X444888Y218934D01*
X444913Y218976D01*
G03X444888Y221259I-2040J1119D01*
G02X444869Y222800I1365J787D01*
G01X444888Y222834D01*
X444913Y222876D01*
G03X444888Y225159I-2040J1119D01*
G02X444869Y226700I1365J787D01*
G01X444888Y226734D01*
X444913Y226776D01*
G03X445099Y228573I-2040J1119D01*
G03X444954Y228946I-2551J-777D01*
G01X444888Y229059D01*
G02X445741Y231337I1365J788D01*
G02X447097Y232415I5692J-5768D01*
G03X447333Y232598I-843J1331D01*
G03X447618Y232959I-1081J1147D01*
G03Y234533I-1365J787D01*
G01X447552Y234647D01*
G03X446304Y236072I-4241J-2455D01*
G01X446194D01*
G02X444869Y238400I59J1575D01*
G01X444956Y238551D01*
X446253Y241547D01*
G01X449692Y183700D02*
X450622Y184630D01*
Y190300D01*
X446842Y194080D01*
Y198090D01*
X440192Y204740D01*
Y208410D01*
X440876Y209590D01*
G03X440858Y211134I-1383J756D01*
G02X440833Y213417I2015J1164D01*
G01X440858Y213459D01*
X440877Y213493D01*
G03X440858Y215034I-1384J754D01*
G01X440833Y215076D01*
G02X440858Y217359I2040J1119D01*
G03X440877Y218900I-1365J787D01*
G01X440858Y218934D01*
X440833Y218976D01*
G02X440858Y221259I2040J1119D01*
G03X440877Y222800I-1365J787D01*
G01X440858Y222834D01*
X440833Y222876D01*
G02X440858Y225159I2040J1119D01*
G03X440877Y226700I-1365J787D01*
G01X440858Y226734D01*
X440833Y226776D01*
G02X440858Y229059I2040J1119D01*
G03X440877Y230600I-1365J787D01*
G01X440858Y230634D01*
G02X440833Y232917I2015J1164D01*
G01X440858Y232959D01*
X440924Y233075D01*
X442873Y235696D01*
G01X452192Y184000D02*
X451496Y184696D01*
Y190488D01*
X447592Y194392D01*
Y198401D01*
X440992Y205001D01*
Y208263D01*
X440997Y208268D01*
X441533Y209226D01*
G03X441508Y211509I-2040J1119D01*
G02X441489Y213050I1365J787D01*
G01X441508Y213084D01*
X441533Y213126D01*
G03X441508Y215409I-2040J1119D01*
G01X441489Y215443D01*
G02X441508Y216984I1384J754D01*
G03X441533Y219267I-2015J1164D01*
G01X441508Y219309D01*
X441489Y219343D01*
G02X441508Y220884I1384J754D01*
G03X441533Y223167I-2015J1164D01*
G01X441508Y223209D01*
X441489Y223243D01*
G02X441508Y224784I1384J754D01*
G03X441533Y227067I-2015J1164D01*
G01X441508Y227109D01*
X441489Y227143D01*
G02X441508Y228684I1384J754D01*
G03Y231010I-2015J1163D01*
G02Y232584I1365J787D01*
G01X441554Y232664D01*
X442117Y233420D01*
G02X443184Y233956I1067J-794D01*
G03X443884Y234246I0J990D01*
G01X443952Y234314D01*
G03X444238Y236484I-1272J1271D01*
G01X444172Y236597D01*
X442873Y239596D01*
G01X460855Y186124D02*
Y186211D01*
X460700Y186366D01*
Y190014D01*
X453592Y197122D01*
Y201730D01*
X450382Y204940D01*
Y208097D01*
X448580Y209899D01*
Y210356D01*
G03X448268Y211509I-2327J-11D01*
G01X448249Y211543D01*
G02X448268Y213084I1384J754D01*
G03X448293Y215367I-2015J1164D01*
G01X448268Y215409D01*
X448249Y215443D01*
G02X448268Y216984I1384J754D01*
G03X448293Y219267I-2015J1164D01*
G01X448268Y219309D01*
X448249Y219343D01*
G02X448268Y220884I1384J754D01*
G03X448293Y223167I-2015J1164D01*
G01X448268Y223209D01*
X448249Y223243D01*
G02X448268Y224784I1384J754D01*
G03X448293Y227067I-2015J1164D01*
G01X448268Y227109D01*
X448249Y227143D01*
G02X448268Y228684I1384J754D01*
G03X448447Y229070I-2013J1168D01*
G03X448574Y230014I-2194J776D01*
G01X448563Y230273D01*
G02X448562Y230320I1109J47D01*
G01Y230398D01*
G02X448794Y230958I792J0D01*
G01X449633Y231797D01*
G01X464764Y186124D02*
Y186211D01*
X464609Y186366D01*
Y192113D01*
X456942Y199780D01*
Y202580D01*
X453240Y206282D01*
Y209252D01*
X451958Y210534D01*
Y212232D01*
X451959Y212233D01*
G03X451648Y213459I-2326J62D01*
G02X451629Y215000I1365J787D01*
G01X451648Y215034D01*
X451673Y215076D01*
G03X451648Y217359I-2040J1119D01*
G02X451629Y218900I1365J787D01*
G01X451648Y218934D01*
X451673Y218976D01*
G03X451648Y221259I-2040J1119D01*
G02X451629Y222800I1365J787D01*
G01X451648Y222834D01*
X451673Y222876D01*
G03X451648Y225159I-2040J1119D01*
G02X451629Y226700I1365J787D01*
G01X451648Y226734D01*
X451673Y226776D01*
G03X451648Y229059I-2040J1119D01*
G02X451629Y230600I1365J787D01*
G01X451648Y230634D01*
G03X451673Y232917I-2015J1164D01*
G01X451648Y232959D01*
G02Y234533I1365J787D01*
G03Y236859I-2015J1163D01*
G02X451629Y238400I1365J787D01*
G01X451648Y238434D01*
X451673Y238476D01*
G03X451648Y240759I-2040J1119D01*
G01X451387Y241210D01*
G03X449633Y243496I-9566J-5524D01*
G01X459795Y186124D02*
Y186211D01*
X459950Y186366D01*
Y189703D01*
X452842Y196811D01*
Y201419D01*
X449632Y204629D01*
Y207786D01*
X447830Y209588D01*
Y210352D01*
X447829Y210353D01*
G03X447618Y211133I-1576J-8D01*
G02Y213459I2015J1163D01*
G03X447637Y215000I-1365J787D01*
G01X447618Y215034D01*
X447593Y215076D01*
G02X447618Y217359I2040J1119D01*
G03X447637Y218900I-1365J787D01*
G01X447618Y218934D01*
X447593Y218976D01*
G02X447618Y221259I2040J1119D01*
G03X447637Y222800I-1365J787D01*
G01X447618Y222834D01*
X447593Y222876D01*
G02X447618Y225159I2040J1119D01*
G03X447637Y226700I-1365J787D01*
G01X447618Y226734D01*
X447593Y226776D01*
G02X447618Y229059I2040J1119D01*
G03X447739Y229321I-1364J789D01*
G03X447825Y229960I-1486J525D01*
G02X448202Y232468I5771J415D01*
G01X448653Y233261D01*
X449280Y234363D01*
G03X449633Y235696I-2342J1333D01*
G01X463704Y186124D02*
Y186211D01*
X463859Y186366D01*
Y191802D01*
X456192Y199469D01*
Y202269D01*
X452490Y205971D01*
Y208941D01*
X451208Y210223D01*
Y212253D01*
G03X450998Y213084I-1575J44D01*
G02X450973Y215367I2015J1164D01*
G01X450998Y215409D01*
X451017Y215443D01*
G03X450998Y216984I-1384J754D01*
G02X450973Y219267I2015J1164D01*
G01X450998Y219309D01*
X451017Y219343D01*
G03X450998Y220884I-1384J754D01*
G02X450973Y223167I2015J1164D01*
G01X450998Y223209D01*
X451017Y223243D01*
G03X450998Y224784I-1384J754D01*
G02X450973Y227067I2015J1164D01*
G01X450998Y227109D01*
X451017Y227143D01*
G03X450998Y228684I-1384J754D01*
G02Y231010I2015J1163D01*
G03Y232584I-1365J787D01*
G01X450973Y232626D01*
G02X450998Y234909I2040J1119D01*
G01X451017Y234943D01*
G03X450998Y236484I-1384J754D01*
G02X450973Y238767I2015J1164D01*
G01X450998Y238809D01*
X451017Y238843D01*
G03X450997Y240384I-1384J753D01*
G03X449861Y241155I-1365J-788D01*
G01X449633Y240927D01*
Y239596D01*
G01X466533Y233746D02*
X464583Y231124D01*
X464518Y231010D01*
G03X466448Y227522I2015J-1163D01*
G01X466577D01*
G02X467898Y226734I-44J-1575D01*
G03X469843Y225571I2015J1162D01*
G01X469913D01*
G02X471277Y223209I0J-1575D01*
G01X471242Y223149D01*
G03X471277Y220883I2050J-1102D01*
G02Y219309I-1364J-787D01*
G01X471242Y219249D01*
G03X471277Y216983I2050J-1102D01*
G02Y215409I-1364J-787D01*
G01X471252Y215367D01*
G03X471277Y213084I2040J-1119D01*
G02X471296Y211543I-1365J-787D01*
G01X471277Y211509D01*
X471252Y211467D01*
G03X471277Y209184I2040J-1119D01*
G02X471296Y207643I-1365J-787D01*
G01X471277Y207609D01*
X471252Y207567D01*
G03X473207Y204122I2040J-1120D01*
G01X473336D01*
G02X474657Y203334I-44J-1575D01*
G01X476051Y201940D01*
X477800D01*
X482292Y197448D01*
Y195894D01*
G01X466533Y241547D02*
X465236Y238551D01*
X465149Y238400D01*
G03X466002Y236163I1384J-753D01*
G02X467723Y234912I-1275J-3563D01*
G03X467898Y234533I2191J782D01*
G02Y232959I-1365J-787D01*
G01X467873Y232917D01*
G02X466069Y231352I-3269J1946D01*
G03X466474Y228272I463J-1506D01*
G01X466603D01*
G02X468548Y227109I-70J-2325D01*
G03X469869Y226321I1365J787D01*
G01X470011D01*
G02X471963Y222894I-98J-2325D01*
G01X471928Y222834D01*
G03Y221260I1364J-787D01*
G02X471963Y218994I-2015J-1164D01*
G01X471928Y218934D01*
G03Y217360I1364J-787D01*
G02X471963Y215094I-2015J-1164D01*
G01X471896Y214978D01*
G03X471927Y213459I1396J-731D01*
G02X471952Y211176I-2015J-1164D01*
G01X471927Y211134D01*
X471908Y211100D01*
G03X471927Y209559I1384J-754D01*
G02X471952Y207276I-2015J-1164D01*
G01X471927Y207234D01*
X471908Y207200D01*
G03X473233Y204872I1384J-753D01*
G01X473362D01*
G02X474943Y204189I-70J-2334D01*
G01X476442Y202690D01*
X478112D01*
X483737Y197065D01*
X483787D01*
G01X463153Y235696D02*
X461204Y233075D01*
X461138Y232959D01*
X461113Y232917D01*
G03X461138Y230634I2040J-1119D01*
G02Y229059I-1363J-787D01*
G03X463083Y225571I2015J-1163D01*
G01X463212D01*
G02X464518Y224784I-59J-1575D01*
G03X466448Y223622I2015J1163D01*
G01X466577D01*
G02X467898Y221259I-44J-1575D01*
G03X467873Y218976I2015J-1164D01*
G01X467898Y218934D01*
X467917Y218900D01*
G02X467898Y217359I-1384J-754D01*
G03X467873Y215076I2015J-1164D01*
G01X467898Y215034D01*
G02X467923Y213505I-1365J-787D01*
G01X467897Y213460D01*
G03X467862Y211194I2015J-1164D01*
G01X467897Y211134D01*
G02Y209560I-1364J-787D01*
G03X467872Y207275I2015J-1165D01*
G01X467897Y207233D01*
G02Y205659I-1364J-787D01*
G03X469827Y202171I2015J-1163D01*
G01X470322D01*
X472602Y199891D01*
Y199060D01*
X476837Y194825D01*
X478029D01*
X479552Y193302D01*
G01X463153Y239596D02*
X464452Y236597D01*
X464518Y236484D01*
G02X464784Y235490I-1725J-994D01*
G01Y235152D01*
G02X463082Y233371I-1783J0D01*
G03X461788Y231010I71J-1574D01*
G02X461854Y228798I-2025J-1167D01*
G01X461788Y228684D01*
G03X463109Y226321I1365J-788D01*
G01X463238D01*
G02X465168Y225159I-85J-2325D01*
G03X466474Y224372I1365J788D01*
G01X466603D01*
G02X468548Y220884I-70J-2325D01*
G03X468529Y219343I1365J-787D01*
G01X468548Y219309D01*
X468573Y219267D01*
G02X468548Y216984I-2040J-1119D01*
G03X468529Y215443I1365J-787D01*
G01X468548Y215409D01*
X468583Y215349D01*
G02X468548Y213083I-2050J-1102D01*
G03Y211509I1364J-787D01*
G01X468583Y211449D01*
G02X468548Y209183I-2050J-1102D01*
G03Y207609I1364J-787D01*
G02Y205283I-2015J-1163D01*
G03X469912Y202921I1364J-787D01*
G01X470633D01*
X473352Y200202D01*
Y199371D01*
X476343Y196380D01*
X479140D01*
X480885Y194635D01*
G01X469913Y231797D02*
G03Y230222I0J-787D01*
G01X469983D01*
G02X471928Y229060I-70J-2326D01*
G01X471941Y229037D01*
G03X473292Y228272I1351J810D01*
G01X473362D01*
G02X475307Y224784I-70J-2325D01*
G03X475288Y223243I1365J-787D01*
G01X475307Y223209D01*
X475332Y223167D01*
G02X475307Y220884I-2040J-1119D01*
G03X475288Y219343I1365J-787D01*
G01X475307Y219309D01*
X475332Y219267D01*
G02X475307Y216984I-2040J-1119D01*
G03X475288Y215443I1365J-787D01*
G01X475307Y215409D01*
X475332Y215367D01*
G02X475307Y213084I-2040J-1119D01*
G03X475288Y211543I1365J-787D01*
G01X475307Y211509D01*
X475332Y211467D01*
G02X475307Y209184I-2040J-1119D01*
G03X476628Y206821I1365J-788D01*
G01X476757D01*
G02X478687Y205659I-85J-2325D01*
G01X479102Y204941D01*
X479382Y204660D01*
X481453D01*
X486282Y199831D01*
X486500Y199832D01*
X486561Y199771D01*
G01X469913Y235696D02*
X469387Y234124D01*
X468573Y232626D01*
X468548Y232584D01*
X468482Y232468D01*
G03X468206Y231850I3030J-1724D01*
G03X469913Y229471I1713J-573D01*
G02X471264Y228706I0J-1575D01*
G01X471277Y228683D01*
G03X473194Y227522I2015J1164D01*
G01X473336D01*
G02X474657Y225159I-44J-1575D01*
G03X474632Y222876I2015J-1164D01*
G01X474657Y222834D01*
X474676Y222800D01*
G02X474657Y221259I-1384J-754D01*
G03X474632Y218976I2015J-1164D01*
G01X474657Y218934D01*
X474676Y218900D01*
G02X474657Y217359I-1384J-754D01*
G03X474632Y215076I2015J-1164D01*
G01X474657Y215034D01*
X474676Y215000D01*
G02X474657Y213459I-1384J-754D01*
G03X474632Y211176I2015J-1164D01*
G01X474657Y211134D01*
X474676Y211100D01*
G02X474657Y209559I-1384J-754D01*
G03X476602Y206071I2015J-1163D01*
G01X476731D01*
G02X478037Y205284I-59J-1575D01*
G01X478501Y204480D01*
X479071Y203910D01*
X481142D01*
X485750Y199302D01*
Y199082D01*
X485812Y199020D01*
G01X469913Y239596D02*
Y240927D01*
X470140Y241154D01*
G02X471276Y240383I-228J-1558D01*
G02X471277Y238809I-1363J-788D01*
G01X471242Y238749D01*
G03X471277Y236483I2050J-1102D01*
G02Y234909I-1364J-787D01*
G03X473222Y231421I2015J-1163D01*
G01X473363D01*
G02X474657Y230634I-71J-1574D01*
G03X476621Y229471I2015J1163D01*
G01X476731D01*
G02X478056Y227143I-59J-1575D01*
G01X478037Y227109D01*
X478012Y227067D01*
G03X478037Y224784I2040J-1119D01*
G02X478056Y223243I-1365J-787D01*
G01X478037Y223209D01*
X478012Y223167D01*
G03X478037Y220884I2040J-1119D01*
G02X478056Y219343I-1365J-787D01*
G01X478037Y219309D01*
X478012Y219267D01*
G03X478037Y216984I2040J-1119D01*
G02X478056Y215443I-1365J-787D01*
G01X478037Y215409D01*
X478012Y215367D01*
G03X478037Y213084I2040J-1119D01*
G02X478056Y211543I-1365J-787D01*
G01X478037Y211509D01*
G03X479967Y208021I2015J-1163D01*
G01X480123D01*
G02X481417Y207234I-71J-1574D01*
G01X483321Y205330D01*
X486882D01*
X488841Y203371D01*
Y203151D01*
X488903Y203089D01*
G01X456393Y235696D02*
X457691Y232699D01*
X457758Y232584D01*
G02Y231010I-1365J-787D01*
G03Y228684I2015J-1163D01*
G02X457777Y227143I-1365J-787D01*
G01X457758Y227109D01*
X457733Y227067D01*
G03X457758Y224784I2040J-1119D01*
G02X457777Y223243I-1365J-787D01*
G01X457758Y223209D01*
X457733Y223167D01*
G03X457758Y220884I2040J-1119D01*
G02X457777Y219343I-1365J-787D01*
G01X457758Y219309D01*
X457733Y219267D01*
G03X457758Y216984I2040J-1119D01*
G02X457777Y215443I-1365J-787D01*
G01X457758Y215409D01*
X457733Y215367D01*
G03X457758Y213084I2040J-1119D01*
G02X457777Y211543I-1365J-787D01*
G01X457758Y211509D01*
G03X457592Y210889I1074J-620D01*
G01Y209560D01*
X466692Y200460D01*
Y197700D01*
X473332Y191060D01*
Y186546D01*
X472384Y185598D01*
G01X456393Y239596D02*
X458342Y236975D01*
X458408Y236859D01*
G02Y234533I-2015J-1163D01*
G03Y232959I1365J-787D01*
G01X458433Y232917D01*
G02X458408Y230634I-2040J-1119D01*
G01X458389Y230600D01*
G03X458408Y229059I1384J-754D01*
G02X458433Y226776I-2015J-1164D01*
G01X458408Y226734D01*
X458389Y226700D01*
G03X458408Y225159I1384J-754D01*
G02X458433Y222876I-2015J-1164D01*
G01X458408Y222834D01*
X458389Y222800D01*
G03X458408Y221259I1384J-754D01*
G02X458433Y218976I-2015J-1164D01*
G01X458408Y218934D01*
X458389Y218900D01*
G03X458408Y217359I1384J-754D01*
G02X458433Y215076I-2015J-1164D01*
G01X458408Y215034D01*
X458389Y215000D01*
G03X458408Y213459I1384J-754D01*
G02Y211133I-2015J-1163D01*
G03X458361Y210958I304J-175D01*
G01Y209961D01*
X467442Y200880D01*
Y198012D01*
X474172Y191282D01*
Y186870D01*
X474884Y186158D01*
G01X467384Y185192D02*
X468412Y186220D01*
Y191608D01*
X463702Y196318D01*
Y198929D01*
X455461Y207170D01*
Y209156D01*
X454353Y211176D01*
G02X454378Y213459I2040J1119D01*
G03X454397Y215000I-1365J787D01*
G01X454378Y215034D01*
X454353Y215076D01*
G02X454378Y217359I2040J1119D01*
G03X454397Y218900I-1365J787D01*
G01X454378Y218934D01*
X454353Y218976D01*
G02X454378Y221259I2040J1119D01*
G03X454397Y222800I-1365J787D01*
G01X454378Y222834D01*
X454353Y222876D01*
G02X454378Y225159I2040J1119D01*
G03X454397Y226700I-1365J787D01*
G01X454378Y226734D01*
X454353Y226776D01*
G02X454378Y229059I2040J1119D01*
G03X454397Y230600I-1365J787D01*
G01X454313Y230746D01*
X453013Y233746D01*
G01X469884Y185408D02*
X469162Y186130D01*
Y191920D01*
X464522Y196560D01*
Y199360D01*
X456292Y207590D01*
Y209301D01*
X455009Y211543D01*
G02X455028Y213084I1384J754D01*
G03X455053Y215367I-2015J1164D01*
G01X455028Y215409D01*
X455009Y215443D01*
G02X455028Y216984I1384J754D01*
G03X455053Y219267I-2015J1164D01*
G01X455028Y219309D01*
X455009Y219343D01*
G02X455028Y220884I1384J754D01*
G03X455053Y223167I-2015J1164D01*
G01X455028Y223209D01*
X455009Y223243D01*
G02X455028Y224784I1384J754D01*
G03X455053Y227067I-2015J1164D01*
G01X455028Y227109D01*
X455009Y227143D01*
G02X455028Y228684I1384J754D01*
G03Y231010I-2015J1163D01*
G02Y232584I1365J787D01*
G01X455053Y232626D01*
G03X455028Y234909I-2040J1119D01*
G01X455009Y234943D01*
G02X455028Y236484I1384J754D01*
G03X455053Y238767I-2015J1164D01*
G01X455028Y238809D01*
X454962Y238925D01*
X453013Y241547D01*
G01X476672Y235696D02*
Y237027D01*
X476900Y237255D01*
G02X478037Y236484I-228J-1560D01*
G03X480001Y235321I2015J1163D01*
G01X480096D01*
G02X481417Y234533I-44J-1575D01*
G03X483347Y233371I2015J1163D01*
G01X483503D01*
G02X484797Y231010I-71J-1574D01*
G03Y228684I2015J-1163D01*
G02X484816Y227143I-1365J-787D01*
G01X484797Y227109D01*
X484772Y227067D01*
G03X484797Y224784I2040J-1119D01*
G02X484816Y223243I-1365J-787D01*
G01X484797Y223209D01*
X484772Y223167D01*
G03X484797Y220884I2040J-1119D01*
G02X484816Y219343I-1365J-787D01*
G01X484797Y219309D01*
X484772Y219267D01*
G03X484797Y216984I2040J-1119D01*
G02X484816Y215443I-1365J-787D01*
G01X484797Y215409D01*
X484772Y215367D01*
G03X486761Y211921I2040J-1120D01*
G01X490650D01*
X496362Y206209D01*
X497066D01*
X498410Y204865D01*
G01X476672Y239596D02*
Y238265D01*
X476928Y238009D01*
G02X478687Y236859I-256J-2312D01*
G03X479993Y236072I1365J788D01*
G01X480103D01*
G02X482067Y234909I-51J-2326D01*
G03X483361Y234122I1365J787D01*
G01X483502D01*
G02X485447Y230634I-70J-2325D01*
G01X485428Y230600D01*
G03X485447Y229059I1384J-754D01*
G02X485472Y226776I-2015J-1164D01*
G01X485447Y226734D01*
X485428Y226700D01*
G03X485447Y225159I1384J-754D01*
G02X485472Y222876I-2015J-1164D01*
G01X485447Y222834D01*
X485428Y222800D01*
G03X485447Y221259I1384J-754D01*
G02X485472Y218976I-2015J-1164D01*
G01X485447Y218934D01*
X485428Y218900D01*
G03X485447Y217359I1384J-754D01*
G02X485472Y215076I-2015J-1164D01*
G01X485447Y215034D01*
X485428Y215000D01*
G03X486753Y212672I1384J-753D01*
G01X490960D01*
X496182Y207450D01*
X498491D01*
G01X473292Y233746D02*
X475421Y233363D01*
X476587Y233371D01*
X476743D01*
G02X478037Y232584I-71J-1574D01*
G03X479982Y231421I2015J1162D01*
G01X480123D01*
G02X481417Y229059I-71J-1574D01*
G03X481392Y226776I2015J-1164D01*
G01X481417Y226734D01*
X481436Y226700D01*
G02X481417Y225159I-1384J-754D01*
G03X481392Y222876I2015J-1164D01*
G01X481417Y222834D01*
X481436Y222800D01*
G02X481417Y221259I-1384J-754D01*
G03X481392Y218976I2015J-1164D01*
G01X481417Y218934D01*
X481436Y218900D01*
G02X481417Y217359I-1384J-754D01*
G03X481392Y215076I2015J-1164D01*
G01X481417Y215034D01*
X481436Y215000D01*
G02X481417Y213459I-1384J-754D01*
G03X483347Y209971I2015J-1163D01*
G01X483476D01*
G02X484797Y209183I-44J-1575D01*
G03X486727Y208021I2015J1163D01*
G01X489921D01*
X495527Y202415D01*
G01X473292Y241547D02*
X474892Y238435D01*
X474969Y235479D01*
X475307Y234909D01*
G03X476601Y234122I1365J787D01*
G01X476742D01*
G02X478687Y232959I-70J-2325D01*
G03X479981Y232172I1365J787D01*
G01X480137D01*
G02X482067Y228684I-85J-2325D01*
G03X482048Y227143I1365J-787D01*
G01X482067Y227109D01*
X482092Y227067D01*
G02X482067Y224784I-2040J-1119D01*
G03X482048Y223243I1365J-787D01*
G01X482067Y223209D01*
X482092Y223167D01*
G02X482067Y220884I-2040J-1119D01*
G03X482048Y219343I1365J-787D01*
G01X482067Y219309D01*
X482092Y219267D01*
G02X482067Y216984I-2040J-1119D01*
G03X482048Y215443I1365J-787D01*
G01X482067Y215409D01*
X482092Y215367D01*
G02X482067Y213084I-2040J-1119D01*
G03X483388Y210721I1365J-788D01*
G01X483517D01*
G02X485447Y209559I-85J-2325D01*
G03X486768Y208771I1365J787D01*
G01X490232D01*
X493903Y205100D01*
X495508D01*
G01X469913Y243496D02*
G02X471670Y241207I-7822J-7823D01*
G01X471928Y240760D01*
G02X471963Y238494I-2015J-1164D01*
G01X471928Y238434D01*
G03Y236860I1364J-787D01*
G02X471953Y234575I-2015J-1165D01*
G01X471928Y234533D01*
G03X473244Y232172I1364J-787D01*
G01X473377D01*
G02X475307Y231010I-85J-2325D01*
G03X476628Y230222I1365J787D01*
G01X476723D01*
G02X478712Y226776I-51J-2326D01*
G01X478687Y226734D01*
X478668Y226700D01*
G03X478687Y225159I1384J-754D01*
G02X478712Y222876I-2015J-1164D01*
G01X478687Y222834D01*
X478668Y222800D01*
G03X478687Y221259I1384J-754D01*
G02X478712Y218976I-2015J-1164D01*
G01X478687Y218934D01*
X478668Y218900D01*
G03X478687Y217359I1384J-754D01*
G02X478712Y215076I-2015J-1164D01*
G01X478687Y215034D01*
X478668Y215000D01*
G03X478687Y213459I1384J-754D01*
G02Y211133I-2015J-1163D01*
G03X479981Y208772I1365J-787D01*
G01X480003Y208771D01*
X480139D01*
G02X482011Y207702I-86J-2324D01*
G01X483632Y206080D01*
X487193D01*
X489373Y203900D01*
X489591Y203901D01*
X489652Y203840D01*
G01X469913Y266896D02*
Y265565D01*
X469685Y265337D01*
G02X469854Y268471I227J1559D01*
G01X469983D01*
G03X471919Y269618I-70J2325D01*
G01X472322Y270381D01*
Y271525D01*
X472672Y271875D01*
Y272925D01*
X472322Y273275D01*
Y275478D01*
X472841Y275997D01*
Y277047D01*
X473191Y277397D01*
Y278447D01*
X472841Y278797D01*
Y279847D01*
X473191Y280197D01*
Y281247D01*
X472841Y281597D01*
Y284934D01*
X473929Y286022D01*
X474986D01*
X475336Y285672D01*
X476386D01*
X476736Y286022D01*
X477864D01*
G03X479807Y287184I-72J2325D01*
G02X481103Y287971I1365J-788D01*
G01X481242D01*
G03X483187Y289134I-70J2325D01*
G02X484481Y289921I1365J-787D01*
G01X484623D01*
G02X485917Y289134I-71J-1574D01*
G03X489947I2015J1162D01*
G02X491241Y289921I1365J-787D01*
G01X491383D01*
G02X492677Y289134I-71J-1574D01*
G03X494622Y287971I2015J1162D01*
G01X494762D01*
G03X496707Y289134I-70J2325D01*
G02X498025Y289922I1365J-787D01*
G02X498119I47J-1575D01*
G02X499437Y289134I-47J-1575D01*
G03X501382Y287971I2015J1162D01*
G01X501522D01*
G03X503467Y289134I-70J2325D01*
G02X504785Y289922I1365J-787D01*
G02X504879I47J-1575D01*
G02X506197Y289134I-47J-1575D01*
G03X508142Y287971I2015J1162D01*
G01X508282D01*
G03X510227Y289134I-70J2325D01*
G02X511521Y289921I1365J-787D01*
G01X511663D01*
G02X512957Y289134I-71J-1574D01*
G03X514902Y287971I2015J1162D01*
G01X515042D01*
G03X516987Y289134I-70J2325D01*
G02X518281Y289921I1365J-787D01*
G01X518400D01*
G02X519716Y289134I-48J-1574D01*
G03X521661Y287971I2015J1162D01*
G01X521801D01*
G03X523746Y289134I-70J2325D01*
G02X525040Y289921I1365J-787D01*
G01X525182D01*
G02X526476Y289134I-71J-1574D01*
G03X528421Y287971I2015J1162D01*
G01X528561D01*
G03X530506Y289134I-70J2325D01*
G02X531800Y289921I1365J-787D01*
G01X531942D01*
G02X533236Y289134I-71J-1574D01*
G03X535181Y287971I2015J1162D01*
G01X535321D01*
G03X537266Y289134I-70J2325D01*
G02X538560Y289921I1365J-787D01*
G01X538702D01*
G02X539996Y289134I-71J-1574D01*
G03X541941Y287971I2015J1162D01*
G01X542081D01*
G03X544026Y289134I-70J2325D01*
G02X545320Y289921I1365J-787D01*
G01X545462D01*
G02X546756Y289134I-71J-1574D01*
G03X548701Y287971I2015J1162D01*
G01X548841D01*
G03X550786Y289134I-70J2325D01*
G02X552080Y289921I1365J-787D01*
G01X554847D01*
X556222Y291296D01*
X556717D01*
X557459Y292038D01*
Y292533D01*
X559175Y294249D01*
Y296674D01*
X559375Y296874D01*
Y296961D01*
G01X469913Y262996D02*
Y264327D01*
X469656Y264584D01*
G02X469828Y269221I257J2312D01*
G01X469970D01*
G03X471264Y269985I-57J1575D01*
G01X471572Y270567D01*
Y275789D01*
X472091Y276308D01*
Y285245D01*
X473618Y286772D01*
X477851D01*
G03X479157Y287559I-59J1575D01*
G02X481088Y288721I2015J-1163D01*
G01X481216D01*
G03X482537Y289509I-44J1575D01*
G02X484454Y290671I2015J-1162D01*
G01X484650D01*
G02X486567Y289509I-98J-2324D01*
G03X489297I1365J787D01*
G02X491214Y290671I2015J-1162D01*
G01X491410D01*
G02X493327Y289509I-98J-2324D01*
G03X494645Y288721I1365J787D01*
G03X494739I47J1575D01*
G03X496057Y289509I-47J1575D01*
G02X498002Y290672I2015J-1162D01*
G01X498142D01*
G02X500087Y289509I-70J-2325D01*
G03X501405Y288721I1365J787D01*
G03X501499I47J1575D01*
G03X502817Y289509I-47J1575D01*
G02X504762Y290672I2015J-1162D01*
G01X504902D01*
G02X506847Y289509I-70J-2325D01*
G03X508165Y288721I1365J787D01*
G03X508259I47J1575D01*
G03X509577Y289509I-47J1575D01*
G02X511494Y290671I2015J-1162D01*
G01X511690D01*
G02X513607Y289509I-98J-2324D01*
G03X514925Y288721I1365J787D01*
G03X515019I47J1575D01*
G03X516337Y289509I-47J1575D01*
G02X518254Y290671I2015J-1162D01*
G01X518450D01*
G02X520367Y289509I-98J-2324D01*
G01X520380Y289486D01*
G03X521684Y288721I1352J810D01*
G03X521778I47J1575D01*
G03X523096Y289509I-47J1575D01*
G02X525013Y290671I2015J-1162D01*
G01X525209D01*
G02X527126Y289509I-98J-2324D01*
G03X528444Y288721I1365J787D01*
G03X528538I47J1575D01*
G03X529856Y289509I-47J1575D01*
G02X531773Y290671I2015J-1162D01*
G01X531969D01*
G02X533886Y289509I-98J-2324D01*
G03X535204Y288721I1365J787D01*
G03X535298I47J1575D01*
G03X536616Y289509I-47J1575D01*
G02X538533Y290671I2015J-1162D01*
G01X538729D01*
G02X540646Y289509I-98J-2324D01*
G03X541964Y288721I1365J787D01*
G03X542058I47J1575D01*
G03X543376Y289509I-47J1575D01*
G02X545293Y290671I2015J-1162D01*
G01X545489D01*
G02X547406Y289509I-98J-2324D01*
G03X548724Y288721I1365J787D01*
G03X548818I47J1575D01*
G03X550136Y289509I-47J1575D01*
G02X552053Y290671I2015J-1162D01*
G01X554536D01*
X558425Y294560D01*
Y296674D01*
X558225Y296874D01*
Y296961D01*
G01X568986Y343327D02*
X564600D01*
G03X561695Y342305I0J-4640D01*
G01X561195Y341805D01*
G02X559102Y340881I-2093J1908D01*
G03X556684Y339922I399J-4533D01*
G02X554166Y340209I-1153J1074D01*
G03X550136I-2015J-1162D01*
G02X547406I-1365J787D01*
G03X543376I-2015J-1162D01*
G02X540646I-1365J787D01*
G03X536616I-2015J-1162D01*
G02X533886I-1365J787D01*
G03X529856I-2015J-1162D01*
G02X527126I-1365J787D01*
G03X525181Y341372I-2015J-1162D01*
G01X525052D01*
G02X523746Y342159I59J1575D01*
G03X521816Y343321I-2015J-1163D01*
G01X521633D01*
G03X519716Y342160I98J-2325D01*
G01X519703Y342137D01*
G02X518352Y341372I-1351J810D01*
G01X518282D01*
G03X516337Y340209I70J-2325D01*
G02X513607I-1365J787D01*
G03X509577I-2015J-1162D01*
G02X506847I-1365J787D01*
G03X502817I-2015J-1162D01*
G02X500087I-1365J787D01*
G03X496057I-2015J-1162D01*
G02X493327I-1365J787D01*
G03X489297I-2015J-1162D01*
G02X486567I-1365J787D01*
G03X482537I-2015J-1162D01*
G02X479807I-1365J787D01*
G03X475777I-2015J-1162D01*
G01X475764Y340186D01*
G02X474413Y339421I-1351J810D01*
G01X474267D01*
G01X477792Y346847D02*
X476639Y346182D01*
X476329Y346266D01*
G02X476219Y346780I1463J582D01*
G02X476428Y347634I1573J68D01*
G01X476463Y347694D01*
G03X476428Y349960I-2050J1102D01*
G02X477792Y352322I1364J787D01*
G01X477877D01*
G03X479807Y353484I-85J2325D01*
G02X481113Y354271I1365J-788D01*
G01X481231D01*
G02X482537Y353484I-59J-1575D01*
G03X484467Y352322I2015J1163D01*
G01X484637D01*
G03X486567Y353484I-85J2325D01*
G02X487873Y354271I1365J-788D01*
G01X487991D01*
G02X489297Y353484I-59J-1575D01*
G03X491227Y352322I2015J1163D01*
G01X491397D01*
G03X493327Y353484I-85J2325D01*
G02X494633Y354271I1365J-788D01*
G01X494751D01*
G02X496057Y353484I-59J-1575D01*
G03X497987Y352322I2015J1163D01*
G01X498157D01*
G03X500087Y353484I-85J2325D01*
G02X501393Y354271I1365J-788D01*
G01X501511D01*
G02X502817Y353484I-59J-1575D01*
G03X504747Y352322I2015J1163D01*
G01X504917D01*
G03X506847Y353484I-85J2325D01*
G02X508153Y354271I1365J-788D01*
G01X508271D01*
G02X509577Y353484I-59J-1575D01*
G03X511507Y352322I2015J1163D01*
G01X511677D01*
G03X513607Y353484I-85J2325D01*
G02X514913Y354271I1365J-788D01*
G01X515031D01*
G02X516337Y353484I-59J-1575D01*
G03X518267Y352322I2015J1163D01*
G01X518450D01*
G03X520367Y353483I-98J2325D01*
G01X520380Y353506D01*
G02X521665Y354271I1352J-810D01*
G02X521789I62J-1575D01*
G02X523096Y353484I-58J-1575D01*
G03X525026Y352322I2015J1163D01*
G01X525196D01*
G03X527126Y353484I-85J2325D01*
G02X528432Y354271I1365J-788D01*
G01X528550D01*
G02X529856Y353484I-59J-1575D01*
G03X531786Y352322I2015J1163D01*
G01X531956D01*
G03X533886Y353484I-85J2325D01*
G02X535192Y354271I1365J-788D01*
G01X535310D01*
G02X536616Y353484I-59J-1575D01*
G03X538546Y352322I2015J1163D01*
G01X538716D01*
G03X540646Y353484I-85J2325D01*
G02X541952Y354271I1365J-788D01*
G01X542070D01*
G02X543376Y353484I-59J-1575D01*
G03X545306Y352322I2015J1163D01*
G01X545476D01*
G03X547406Y353484I-85J2325D01*
G02X548712Y354271I1365J-788D01*
G01X548830D01*
G02X550136Y353484I-59J-1575D01*
G03X552066Y352322I2015J1163D01*
G01X552195D01*
G02X553516Y351534I-44J-1575D01*
G03X555461Y350371I2015J1162D01*
G01X555601D01*
G03X557546Y351534I-70J2325D01*
G02X558867Y352322I1365J-787D01*
G01X559566D01*
G02X560419Y351545I-655J-1575D01*
G03X562370Y350371I1951J1034D01*
G01X567067D01*
X568012Y351316D01*
Y352966D01*
X568212Y353166D01*
Y353253D01*
G01X474413Y344896D02*
X474958Y345441D01*
G03X475467Y346748I-1233J1233D01*
G02X475742Y347949I2326J99D01*
G01X475777Y348009D01*
G03Y349583I-1364J787D01*
G02X477722Y353072I2015J1163D01*
G01X477851D01*
G03X479157Y353859I-59J1575D01*
G02X481087Y355021I2015J-1163D01*
G01X481257D01*
G02X483187Y353859I-85J-2325D01*
G03X484493Y353072I1365J788D01*
G01X484611D01*
G03X485917Y353859I-59J1575D01*
G02X487847Y355021I2015J-1163D01*
G01X488017D01*
G02X489947Y353859I-85J-2325D01*
G03X491253Y353072I1365J788D01*
G01X491371D01*
G03X492677Y353859I-59J1575D01*
G02X494607Y355021I2015J-1163D01*
G01X494777D01*
G02X496707Y353859I-85J-2325D01*
G03X498013Y353072I1365J788D01*
G01X498131D01*
G03X499437Y353859I-59J1575D01*
G02X501367Y355021I2015J-1163D01*
G01X501537D01*
G02X503467Y353859I-85J-2325D01*
G03X504773Y353072I1365J788D01*
G01X504891D01*
G03X506197Y353859I-59J1575D01*
G02X508127Y355021I2015J-1163D01*
G01X508297D01*
G02X510227Y353859I-85J-2325D01*
G03X511533Y353072I1365J788D01*
G01X511651D01*
G03X512957Y353859I-59J1575D01*
G02X514887Y355021I2015J-1163D01*
G01X515057D01*
G02X516987Y353859I-85J-2325D01*
G03X518294Y353073I1364J789D01*
G03X518418I62J1574D01*
G03X519703Y353837I-66J1574D01*
G01X519716Y353860D01*
G02X521633Y355021I2015J-1164D01*
G01X521816D01*
G02X523746Y353859I-85J-2325D01*
G03X525052Y353072I1365J788D01*
G01X525170D01*
G03X526476Y353859I-59J1575D01*
G02X528406Y355021I2015J-1163D01*
G01X528576D01*
G02X530506Y353859I-85J-2325D01*
G03X531812Y353072I1365J788D01*
G01X531930D01*
G03X533236Y353859I-59J1575D01*
G02X535166Y355021I2015J-1163D01*
G01X535336D01*
G02X537266Y353859I-85J-2325D01*
G03X538572Y353072I1365J788D01*
G01X538690D01*
G03X539996Y353859I-59J1575D01*
G02X541926Y355021I2015J-1163D01*
G01X542096D01*
G02X544026Y353859I-85J-2325D01*
G03X545332Y353072I1365J788D01*
G01X545450D01*
G03X546756Y353859I-59J1575D01*
G02X548686Y355021I2015J-1163D01*
G01X548856D01*
G02X550786Y353859I-85J-2325D01*
G03X552092Y353072I1365J788D01*
G01X552221D01*
G02X554166Y351909I-70J-2325D01*
G03X555484Y351121I1365J787D01*
G03X555578I47J1575D01*
G03X556896Y351909I-47J1575D01*
G02X558841Y353072I2015J-1162D01*
G01X559702D01*
G02X561082Y351896I-791J-2325D01*
G03X562370Y351121I1288J683D01*
G01X566756D01*
X567262Y351627D01*
Y352966D01*
X567062Y353166D01*
Y353253D01*
G01X477792Y350747D02*
G03X480030Y350824I1045J2200D01*
G02X481087Y351121I1140J-2028D01*
G01X481257D01*
G02X483187Y349959I-85J-2325D01*
G03X484493Y349172I1365J788D01*
G01X484611D01*
G03X485917Y349959I-59J1575D01*
G02X487847Y351121I2015J-1163D01*
G01X488017D01*
G02X489947Y349959I-85J-2325D01*
G03X491253Y349172I1365J788D01*
G01X491371D01*
G03X492677Y349959I-59J1575D01*
G02X494607Y351121I2015J-1163D01*
G01X494777D01*
G02X496707Y349959I-85J-2325D01*
G03X499437I1365J788D01*
G02X503467I2015J-1163D01*
G03X504773Y349172I1365J788D01*
G01X504891D01*
G03X506197Y349959I-59J1575D01*
G02X508127Y351121I2015J-1163D01*
G01X508297D01*
G02X510227Y349959I-85J-2325D01*
G03X511533Y349172I1365J788D01*
G01X511651D01*
G03X512957Y349959I-59J1575D01*
G02X514887Y351121I2015J-1163D01*
G01X515057D01*
G02X516987Y349959I-85J-2325D01*
G03X518293Y349172I1365J788D01*
G01X518352D01*
G03X519703Y349937I0J1575D01*
G01X519716Y349960D01*
G02X521633Y351121I2015J-1164D01*
G01X521816D01*
G02X523746Y349959I-85J-2325D01*
G03X525052Y349172I1365J788D01*
G01X525170D01*
G03X526476Y349959I-59J1575D01*
G02X528406Y351121I2015J-1163D01*
G01X528576D01*
G02X530506Y349959I-85J-2325D01*
G03X533236I1365J788D01*
G02X535166Y351121I2015J-1163D01*
G01X535336D01*
G02X537266Y349959I-85J-2325D01*
G03X539996I1365J788D01*
G02X541926Y351121I2015J-1163D01*
G01X542096D01*
G02X544026Y349959I-85J-2325D01*
G03X545332Y349172I1365J788D01*
G01X545450D01*
G03X546756Y349959I-59J1575D01*
G02X548686Y351121I2015J-1163D01*
G01X548856D01*
G02X550786Y349959I-85J-2325D01*
G03X552092Y349172I1365J788D01*
G01X552221D01*
G02X554166Y348009I-70J-2325D01*
G03X555487Y347221I1365J787D01*
G01X565061D01*
X565261Y347421D01*
X565348D01*
G01X423714Y389747D02*
X421802D01*
X421389Y390160D01*
Y403334D01*
X425111Y407056D01*
Y417608D01*
X424208Y418511D01*
G01X423714Y393647D02*
X422462D01*
X422139Y393970D01*
Y403026D01*
X425859Y406746D01*
Y417672D01*
X426708Y418521D01*
G01X433854Y383896D02*
X433679D01*
G02X432708Y385194I0J1012D01*
G03X432514Y386967I-2222J654D01*
G02X432390Y387215I1375J842D01*
G02X433261Y389256I1463J582D01*
G01X434074Y390069D01*
G02X434255Y390173I283J-283D01*
G03X435205Y390886I-401J1524D01*
G01X435218Y390909D01*
G02X437163Y392072I2015J-1162D01*
G01X437292D01*
G03X438625Y394385I-59J1575D01*
G01X438288Y394968D01*
Y396541D01*
X438290Y396543D01*
Y403757D01*
X442553Y408020D01*
Y408851D01*
X441818Y409586D01*
Y410424D01*
G01X434885Y389604D02*
G03X433854Y387796I1069J-1808D01*
G01X435038Y389694D02*
X434885Y389604D01*
G01X435038Y389694D02*
G03X435869Y390534I-1184J2002D01*
G01X435882Y390557D01*
G02X437233Y391322I1351J-810D01*
G01X437318D01*
G03X439273Y394767I-85J2325D01*
G01X439038Y395169D01*
Y403447D01*
X443301Y407710D01*
Y408664D01*
X444318Y409681D01*
G01X423714Y378047D02*
X421938D01*
X421391Y378594D01*
Y385518D01*
X418539Y388370D01*
Y404512D01*
X420141Y406114D01*
Y416909D01*
X419208Y417842D01*
G01X423714Y381947D02*
X422386D01*
X422139Y382194D01*
Y385828D01*
X419290Y388677D01*
Y389969D01*
X419289Y389970D01*
Y404204D01*
X420891Y405806D01*
Y417264D01*
X421708Y418081D01*
G01X430474Y381947D02*
X429175Y384946D01*
X429109Y385059D01*
G02X429090Y386600I1365J787D01*
G01X429109Y386634D01*
X429134Y386676D01*
G03X429109Y388959I-2040J1119D01*
G02X429438Y390934I1365J788D01*
G01X430266Y391762D01*
G02X430894Y392128I1008J-1007D01*
G03X431839Y392859I-420J1519D01*
G02X433769Y394021I2015J-1163D01*
G01X433854D01*
G03X435205Y394786I0J1575D01*
G01X435272Y394911D01*
Y405008D01*
X437435Y407171D01*
Y410395D01*
X436808Y411022D01*
G01X430474Y389747D02*
Y390907D01*
X430758Y391191D01*
X431099Y391406D01*
G03X432489Y392484I-622J2237D01*
G02X433795Y393271I1365J-788D01*
G01X433924D01*
G03X435869Y394434I-70J2325D01*
G01X436020Y394718D01*
Y404698D01*
X438183Y406861D01*
Y410410D01*
X439308Y411535D01*
G01X474413Y368296D02*
X473234Y371003D01*
G03X473049Y371409I-2200J-757D01*
G02X472977Y372842I1365J787D01*
G03X472916Y374037I-1197J538D01*
G01X472399Y374933D02*
X472916Y374037D01*
G01X472399Y374933D02*
G02Y377259I2015J1163D01*
G03Y378833I-1365J787D01*
G02Y381159I2015J1163D01*
G03Y382733I-1365J787D01*
G02Y385059I2015J1163D01*
G03Y386633I-1365J787D01*
G02Y388959I2015J1163D01*
G03Y390533I-1365J787D01*
G03X472373Y390576I-1045J-603D01*
G02X472398Y392859I2040J1119D01*
G03X472417Y394400I-1365J787D01*
G01X472398Y394434D01*
X472373Y394476D01*
G02X472398Y396759I2040J1119D01*
G03X472417Y398300I-1365J787D01*
G01X472398Y398334D01*
X472373Y398376D01*
G02X472398Y400659I2040J1119D01*
G03X472417Y402200I-1365J787D01*
G01X472398Y402234D01*
X472373Y402276D01*
G02X474328Y405721I2040J1120D01*
G01X474413D01*
G03X475777Y408083I0J1575D01*
G02X475742Y410349I2015J1164D01*
G01X475777Y410409D01*
G03Y411983I-1364J787D01*
G02X477722Y415472I2015J1163D01*
G01X477851D01*
G03X479157Y416259I-59J1575D01*
G02X481087Y417421I2015J-1163D01*
G01X481216D01*
G03X482537Y418209I-44J1575D01*
G01X482760Y418595D01*
X484848Y420683D01*
Y422289D01*
X484032Y423105D01*
G01X486492Y422864D02*
X485598Y421970D01*
Y420372D01*
X483364Y418138D01*
X483190Y417836D01*
G02X481242Y416671I-2018J1163D01*
G01X481113D01*
G03X479807Y415884I59J-1575D01*
G02X477877Y414722I-2015J1163D01*
G01X477792D01*
G03X476428Y412360I0J-1575D01*
G02X476463Y410094I-2015J-1164D01*
G01X476428Y410034D01*
G03Y408460I1364J-787D01*
G02X474483Y404971I-2014J-1164D01*
G01X474354D01*
G03X473029Y402643I59J-1575D01*
G01X473048Y402609D01*
X473073Y402567D01*
G02X473048Y400284I-2040J-1119D01*
G03X473029Y398743I1365J-787D01*
G01X473048Y398709D01*
X473073Y398667D01*
G02X473048Y396384I-2040J-1119D01*
G03X473029Y394843I1365J-787D01*
G01X473048Y394809D01*
X473073Y394767D01*
G02X473048Y392484I-2040J-1119D01*
G03X473029Y390943I1365J-787D01*
G01X473049Y390909D01*
G02Y388583I-2015J-1163D01*
G03Y387009I1365J-787D01*
G02Y384683I-2015J-1163D01*
G03Y383109I1365J-787D01*
G02Y380783I-2015J-1163D01*
G03Y379209I1365J-787D01*
G02X473224Y378832I-2014J-1164D01*
G01X474413Y376096D01*
G01X471033Y370247D02*
X468894Y373234D01*
G02X469019Y375309I2140J912D01*
G03Y376883I-1365J787D01*
G02Y379209I2015J1163D01*
G03Y380783I-1365J787D01*
G02Y383109I2015J1163D01*
G03Y384683I-1365J787D01*
G02Y387009I2015J1163D01*
G03Y388583I-1365J787D01*
G02Y390909I2015J1163D01*
G03X469037Y390943I-456J263D01*
G03X469018Y392484I-1384J754D01*
G02X468993Y394767I2015J1164D01*
G01X469018Y394809D01*
X469037Y394843D01*
G03X469018Y396384I-1384J754D01*
G02X468993Y398667I2015J1164D01*
G01X469018Y398709D01*
X469037Y398743D01*
G03X469018Y400284I-1384J754D01*
G02X468993Y402567I2015J1164D01*
G01X469018Y402609D01*
X469037Y402643D01*
G03X469018Y404184I-1384J754D01*
G02X470963Y407672I2015J1163D01*
G01X471092D01*
G03X472417Y410000I-59J1575D01*
G01X472398Y410034D01*
X472373Y410076D01*
G02X472398Y412359I2040J1119D01*
G03X472417Y413900I-1365J787D01*
G01X472398Y413934D01*
X472373Y413976D01*
G02X474328Y417421I2040J1120D01*
G01X474413D01*
G03X475764Y418186I0J1575D01*
G01X475777Y418209D01*
G02X477695Y419372I2016J-1161D01*
G01X477793Y419371D01*
X477841D01*
G03X479157Y420158I-48J1574D01*
G01X479748Y421185D01*
Y421994D01*
X479032Y422710D01*
G01X481532Y423140D02*
X480498Y422106D01*
Y420983D01*
X479808Y419783D01*
G02X477890Y418620I-2016J1161D01*
G01X477792Y418621D01*
X477744D01*
G03X476428Y417834I48J-1574D01*
G02X474483Y416671I-2015J1162D01*
G01X474354D01*
G03X473029Y414343I59J-1575D01*
G01X473048Y414309D01*
X473073Y414267D01*
G02X473048Y411984I-2040J-1119D01*
G03X473029Y410443I1365J-787D01*
G01X473048Y410409D01*
X473073Y410367D01*
G02X471118Y406922I-2040J-1120D01*
G01X470989D01*
G03X469668Y404559I44J-1575D01*
G02X469693Y402276I-2015J-1164D01*
G01X469668Y402234D01*
X469649Y402200D01*
G03X469668Y400659I1384J-754D01*
G02X469693Y398376I-2015J-1164D01*
G01X469668Y398334D01*
X469649Y398300D01*
G03X469668Y396759I1384J-754D01*
G02X469693Y394476I-2015J-1164D01*
G01X469668Y394434D01*
X469649Y394400D01*
G03X469668Y392859I1384J-754D01*
G02X469693Y390576I-2015J-1164D01*
G02X469669Y390533I-1555J840D01*
G03Y388959I1365J-787D01*
G02Y386633I-2015J-1163D01*
G03Y385059I1365J-787D01*
G02Y382733I-2015J-1163D01*
G03Y381159I1365J-787D01*
G02Y378833I-2015J-1163D01*
G03Y377259I1365J-787D01*
G02X469904Y376689I-2015J-1164D01*
G01X471033Y374146D01*
G01X427094Y383896D02*
Y382568D01*
X426866Y382340D01*
G02X425729Y384686I228J1559D01*
G03Y387012I-2015J1163D01*
G02Y388586I1365J787D01*
G03Y390912I-2015J1163D01*
G02Y392486I1365J787D01*
G03X426040Y393646I-2015J1162D01*
G01Y401353D01*
X430578Y405891D01*
Y418945D01*
X430733Y419100D01*
Y419187D01*
G01X477792Y370247D02*
Y368916D01*
X477565Y368689D01*
G02X476411Y371005I227J1558D01*
G02X476428Y371034I1367J-782D01*
G01X476427Y371033D01*
G03Y373359I-2015J1163D01*
G02Y374933I1365J787D01*
G03Y377259I-2015J1163D01*
G02Y378833I1365J787D01*
G03Y381159I-2015J1163D01*
G02Y382733I1365J787D01*
G03Y385059I-2015J1163D01*
G02Y386633I1365J787D01*
G03Y388959I-2015J1163D01*
G02X476306Y389226I1448J817D01*
G02X476428Y390534I1486J521D01*
G01X476463Y390594D01*
G03X476428Y392860I-2050J1102D01*
G02Y394434I1364J787D01*
G01X476463Y394494D01*
G03X476428Y396760I-2050J1102D01*
G02Y398334I1364J787D01*
G01X476463Y398394D01*
G03X476428Y400660I-2050J1102D01*
G02X477792Y403022I1364J787D01*
G01X477877D01*
G03X479832Y406467I-85J2325D01*
G01X479807Y406509D01*
X479788Y406543D01*
G02X479807Y408084I1384J754D01*
G03X479832Y410367I-2015J1164D01*
G01X479807Y410409D01*
X479788Y410443D01*
G02X481113Y412771I1384J753D01*
G01X481242D01*
G03X483187Y413934I-70J2325D01*
G02X484508Y414722I1365J-787D01*
G01X484637D01*
G03X486567Y415884I-85J2325D01*
G02X487913Y416672I1365J-788D01*
G01X487983D01*
G03X489947Y417835I-51J2326D01*
G01X490518Y418825D01*
Y420476D01*
X491676Y421634D01*
X491896D01*
X491958Y421696D01*
G01X427094Y391696D02*
G02X428459Y394812I14703J-4584D01*
G01X428689Y395210D01*
X432252Y398773D01*
Y405485D01*
X433278Y406511D01*
Y419295D01*
X433123Y419450D01*
Y419537D01*
G01X477792Y378047D02*
G02X479157Y381161I14795J-4629D01*
G03Y382735I-1365J787D01*
G01X479156Y382736D01*
G02Y385060I2016J1162D01*
G01X479157Y385061D01*
G03Y386635I-1365J787D01*
G02Y388961I2015J1163D01*
G03X479272Y389205I-1408J813D01*
G03X479176Y390500I-1480J541D01*
G01X479157Y390534D01*
X479132Y390576D01*
G02X479157Y392859I2040J1119D01*
G03X479176Y394400I-1365J787D01*
G01X479157Y394434D01*
X479132Y394476D01*
G02X479157Y396759I2040J1119D01*
G03X479176Y398300I-1365J787D01*
G01X479157Y398334D01*
X479132Y398376D01*
G02X481087Y401821I2040J1120D01*
G01X481216D01*
G03X482537Y404184I-44J1575D01*
G02X482512Y406467I2015J1164D01*
G01X482537Y406509D01*
X482556Y406543D01*
G03X482537Y408084I-1384J754D01*
G02X484482Y411572I2015J1163D01*
G01X484611D01*
G03X485917Y412359I-59J1575D01*
G02X487847Y413521I2015J-1163D01*
G01X487976D01*
G03X489297Y414309I-44J1575D01*
G02X491242Y415472I2015J-1162D01*
G01X491381D01*
G03X492521Y416036I-70J1575D01*
G01Y417177D01*
X497594Y422250D01*
X499937D01*
X500092Y422405D01*
X500179D01*
G01X427094Y379996D02*
Y381330D01*
X426838Y381586D01*
G02X425079Y385062I256J2313D01*
G03Y386636I-1365J787D01*
G02Y388962I2015J1163D01*
G03Y390536I-1365J787D01*
G02Y392862I2015J1163D01*
G01Y392861D01*
G03X425290Y393646I-1365J788D01*
G01Y401664D01*
X429828Y406202D01*
Y418945D01*
X429673Y419100D01*
Y419187D01*
G01X477792Y366347D02*
Y367678D01*
X477536Y367934D01*
G02X475752Y371368I256J2313D01*
G01X475777Y371409D01*
G03Y372983I-1365J787D01*
G02Y375309I2015J1163D01*
G03Y376883I-1365J787D01*
G02Y379209I2015J1163D01*
G03Y380783I-1365J787D01*
G02Y383109I2015J1163D01*
G03Y384683I-1365J787D01*
G02Y387009I2015J1163D01*
G03Y388583I-1365J787D01*
G02X475596Y388977I2015J1164D01*
G02X475742Y390849I2196J770D01*
G01X475777Y390909D01*
G03Y392483I-1364J787D01*
G02X475742Y394749I2015J1164D01*
G01X475777Y394809D01*
G03Y396383I-1364J787D01*
G02X475742Y398649I2015J1164D01*
G01X475777Y398709D01*
G03Y400283I-1364J787D01*
G02X477722Y403772I2015J1163D01*
G01X477851D01*
G03X479176Y406100I-59J1575D01*
G01X479157Y406134D01*
X479132Y406176D01*
G02X479157Y408459I2040J1119D01*
G03X479176Y410000I-1365J787D01*
G01X479157Y410034D01*
X479132Y410076D01*
G02X481087Y413521I2040J1120D01*
G01X481216D01*
G03X482537Y414309I-44J1575D01*
G02X484482Y415472I2015J-1162D01*
G01X484611D01*
G03X485917Y416259I-59J1575D01*
G02X487881Y417422I2015J-1163D01*
G01X487951D01*
G03X489297Y418210I-19J1576D01*
G01X489768Y419026D01*
Y420787D01*
X491147Y422166D01*
X491146Y422384D01*
X491207Y422445D01*
G01X427094Y387796D02*
G02X428459Y390910I14795J-4629D01*
G03X428768Y391501I-7007J4040D01*
G03X428851Y392151I-961J453D01*
G03X428808Y393091I-12434J-98D01*
G02X429109Y394437I2301J192D01*
G01X429289Y394749D01*
X433002Y398462D01*
Y405174D01*
X434028Y406200D01*
Y419295D01*
X434183Y419450D01*
Y419537D01*
G01X477792Y374146D02*
G02X479157Y377261I14855J-4653D01*
G03X479354Y378252I-1365J786D01*
G02X479807Y380785I4215J553D01*
G03Y383111I-2015J1163D01*
G02Y384685I1365J787D01*
G03Y387011I-2015J1163D01*
G01Y387010D01*
G02Y388586I1365J788D01*
G03X479993Y388994I-1989J1153D01*
G03X479832Y390867I-2201J754D01*
G01X479807Y390909D01*
X479788Y390943D01*
G02X479807Y392484I1384J754D01*
G03X479832Y394767I-2015J1164D01*
G01X479807Y394809D01*
X479788Y394843D01*
G02X479807Y396384I1384J754D01*
G03X479832Y398667I-2015J1164D01*
G01X479807Y398709D01*
X479788Y398743D01*
G02X481113Y401071I1384J753D01*
G01X481242D01*
G03X483187Y404559I-70J2325D01*
G02X483168Y406100I1365J787D01*
G01X483187Y406134D01*
X483212Y406176D01*
G03X483187Y408459I-2040J1119D01*
G02X484508Y410822I1365J788D01*
G01X484637D01*
G03X486567Y411984I-85J2325D01*
G02X487873Y412771I1365J-788D01*
G01X488002D01*
G03X489947Y413934I-70J2325D01*
G02X491268Y414722I1365J-787D01*
G01X491397D01*
G03X493271Y415792I-85J2325D01*
G01Y416866D01*
X497905Y421500D01*
X499937D01*
X500092Y421345D01*
X500179D01*
G01X454242Y422014D02*
X455200Y421056D01*
Y419990D01*
G02X454177Y417421I-1065J-1064D01*
G01X454048D01*
G03X452093Y413976I85J-2325D01*
G01X452118Y413934D01*
X452137Y413900D01*
G02X452118Y412359I-1384J-754D01*
G03X452093Y410076I2015J-1164D01*
G01X452118Y410034D01*
X452137Y410000D01*
G02X452118Y408459I-1384J-754D01*
G03X452093Y406176I2015J-1164D01*
G01X452118Y406134D01*
X452137Y406100D01*
G02X452118Y404559I-1384J-754D01*
G03X452093Y402276I2015J-1164D01*
G01X452118Y402234D01*
X452137Y402200D01*
G02X452118Y400659I-1384J-754D01*
G03X452093Y398376I2015J-1164D01*
G01X452118Y398334D01*
X452137Y398300D01*
G02X452118Y396759I-1384J-754D01*
G03X452093Y394476I2015J-1164D01*
G01X452118Y394434D01*
X452137Y394400D01*
G02X452194Y393009I-1384J-753D01*
G02X452118Y392861I-1321J585D01*
G03Y390535I2015J-1163D01*
G02Y388961I-1365J-787D01*
G03Y386635I2015J-1163D01*
G02Y385061I-1365J-787D01*
G03Y382735I2015J-1163D01*
G02Y381161I-1365J-787D01*
G03Y378835I2015J-1163D01*
G02Y377261I-1365J-787D01*
G03Y374935I2015J-1163D01*
G01X452635Y374039D01*
G01X454133Y368296D02*
X452995Y370869D01*
G03X452768Y371411I-2242J-621D01*
G02X452696Y372844I1365J787D01*
G03X452635Y374039I-1197J538D01*
G01X456632Y422124D02*
X456148Y421640D01*
Y420159D01*
G02X456173Y417876I-2015J-1164D01*
G02X454203Y416671I-2039J1120D01*
G01X454074D01*
G03X452749Y414343I59J-1575D01*
G01X452768Y414309D01*
X452793Y414267D01*
G02X452768Y411984I-2040J-1119D01*
G03X452749Y410443I1365J-787D01*
G01X452768Y410409D01*
X452793Y410367D01*
G02X452768Y408084I-2040J-1119D01*
G03X452749Y406543I1365J-787D01*
G01X452768Y406509D01*
X452793Y406467D01*
G02X452768Y404184I-2040J-1119D01*
G03X452749Y402643I1365J-787D01*
G01X452768Y402609D01*
X452793Y402567D01*
G02X452768Y400284I-2040J-1119D01*
G03X452749Y398743I1365J-787D01*
G01X452768Y398709D01*
X452793Y398667D01*
G02X452768Y396384I-2040J-1119D01*
G03X452749Y394843I1365J-787D01*
G01X452768Y394809D01*
X452793Y394767D01*
G02X452884Y392713I-2040J-1119D01*
G02X452768Y392485I-2233J993D01*
G03Y390911I1365J-787D01*
G02Y388585I-2015J-1163D01*
G03Y387011I1365J-787D01*
G02Y384685I-2015J-1163D01*
G03Y383111I1365J-787D01*
G02Y380785I-2015J-1163D01*
G03Y379211I1365J-787D01*
G02X453015Y378590I-2016J-1161D01*
G01X454133Y376096D01*
G01X464273Y370247D02*
X462833Y373509D01*
G02X463703Y375617I1440J639D01*
G03X465638Y377261I-1400J3609D01*
G03Y378835I-1365J787D01*
G02Y381161I2015J1163D01*
G03Y382735I-1365J787D01*
G02Y385061I2015J1163D01*
G03Y386635I-1365J787D01*
G02Y388961I2015J1163D01*
G03Y390535I-1365J787D01*
G02Y392861I2015J1163D01*
G02X465657Y392892I597J-344D01*
G03X465638Y394433I-1384J754D01*
G02X465613Y396716I2015J1164D01*
G01X465638Y396758D01*
X465665Y396806D01*
G03X465638Y398332I-1392J739D01*
G02X465603Y400598I2015J1164D01*
G01X465638Y400658D01*
X465657Y400692D01*
G03X465638Y402233I-1384J754D01*
G02Y404559I2015J1163D01*
G03X465657Y406100I-1365J787D01*
G01X465638Y406134D01*
X465613Y406176D01*
G02X465638Y408459I2040J1119D01*
G02X467568Y409621I2015J-1163D01*
G01X467697D01*
G03X469018Y410409I-44J1575D01*
G01X469037Y410443D01*
G03X469018Y411984I-1384J754D01*
G02X468993Y414267I2015J1164D01*
G01X469018Y414309D01*
X469037Y414343D01*
G03X469018Y415884I-1384J754D01*
G02X468993Y418167I1858J1162D01*
G01X469018Y418209D01*
G02X470963Y419372I2015J-1162D01*
G01X471092D01*
G03X472398Y420159I-59J1575D01*
G01X472608Y420524D01*
Y421248D01*
X471732Y422124D01*
G01X464273Y374146D02*
G03X466288Y376885I-11302J10425D01*
G03Y379211I-2015J1163D01*
G02Y380785I1365J787D01*
G03Y383111I-2015J1163D01*
G02Y384685I1365J787D01*
G03Y387011I-2015J1163D01*
G02Y388585I1365J787D01*
G03Y390911I-2015J1163D01*
G02Y392485I1365J787D01*
G02X466313Y392525I574J-331D01*
G03X466288Y394808I-2040J1119D01*
G02X466261Y396334I1365J787D01*
G01X466323Y396442D01*
G03X466288Y398708I-2050J1102D01*
G02X466269Y400249I1365J787D01*
G01X466288Y400283D01*
X466313Y400325D01*
G03X466288Y402608I-2040J1119D01*
G02Y404184I1365J788D01*
G03X466313Y406467I-2015J1164D01*
G01X466288Y406509D01*
X466269Y406543D01*
G02X466288Y408084I1384J754D01*
G02X467594Y408871I1365J-788D01*
G01X467723D01*
G03X469668Y410034I-70J2325D01*
G01X469693Y410076D01*
G03X469668Y412359I-2040J1119D01*
G02X469649Y413900I1365J787D01*
G01X469668Y413934D01*
X469693Y413976D01*
G03X469668Y416259I-2040J1119D01*
G02X469649Y417800I1330J787D01*
G01X469668Y417834D01*
G02X470989Y418622I1365J-787D01*
G01X471118D01*
G03X473048Y419784I-85J2325D01*
G01X473358Y420320D01*
Y421250D01*
X474232Y422124D01*
G01X450753Y370247D02*
X449180Y372433D01*
G02X448738Y375311I1573J1715D01*
G03Y376885I-1365J787D01*
G02Y379211I2015J1163D01*
G03Y380785I-1365J787D01*
G02Y383111I2015J1163D01*
G03Y384685I-1365J787D01*
G02Y387011I2015J1163D01*
G03Y388585I-1365J787D01*
G02Y390911I2015J1163D01*
G01X448757Y390943D01*
G03X448738Y392484I-1384J754D01*
G02X448713Y394767I2015J1164D01*
G01X448738Y394809D01*
X448757Y394843D01*
G03X448738Y396384I-1384J754D01*
G02X448713Y398667I2015J1164D01*
G01X448738Y398709D01*
X448757Y398743D01*
G03X448738Y400284I-1384J754D01*
G02X448713Y402567I2015J1164D01*
G01X448738Y402609D01*
X448757Y402643D01*
G03X448738Y404184I-1384J754D01*
G02X448713Y406467I2015J1164D01*
G01X448738Y406509D01*
X448757Y406543D01*
G03X448738Y408084I-1384J754D01*
G02X448713Y410367I2015J1164D01*
G01X448738Y410409D01*
X448757Y410443D01*
G03X448738Y411984I-1384J754D01*
G02X448713Y414267I2015J1164D01*
G01X448738Y414309D01*
X448757Y414343D01*
G03X448738Y415884I-1384J754D01*
G02X448427Y417047I2015J1162D01*
G01Y417620D01*
X449948Y419141D01*
Y421308D01*
X449132Y422124D01*
G01X450753Y374146D02*
X449636Y376639D01*
G03X449388Y377261I-2263J-542D01*
G02Y378835I1365J787D01*
G03Y381161I-2015J1163D01*
G02Y382735I1365J787D01*
G03Y385061I-2015J1163D01*
G02Y386635I1365J787D01*
G03Y388961I-2015J1163D01*
G02Y390535I1365J787D01*
G02X449413Y390576I847J-488D01*
G03X449388Y392859I-2040J1119D01*
G02X449369Y394400I1365J787D01*
G01X449388Y394434D01*
X449413Y394476D01*
G03X449388Y396759I-2040J1119D01*
G02X449369Y398300I1365J787D01*
G01X449388Y398334D01*
X449413Y398376D01*
G03X449388Y400659I-2040J1119D01*
G02X449369Y402200I1365J787D01*
G01X449388Y402234D01*
X449413Y402276D01*
G03X449388Y404559I-2040J1119D01*
G02X449369Y406100I1365J787D01*
G01X449388Y406134D01*
X449413Y406176D01*
G03X449388Y408459I-2040J1119D01*
G02X449369Y410000I1365J787D01*
G01X449388Y410034D01*
X449413Y410076D01*
G03X449388Y412359I-2040J1119D01*
G02X449369Y413900I1365J787D01*
G01X449388Y413934D01*
X449413Y413976D01*
G03X449388Y416259I-2040J1119D01*
G02X449177Y417046I1365J788D01*
G01Y417309D01*
X450698Y418830D01*
Y421190D01*
X451632Y422124D01*
G01X460893Y368296D02*
X459594Y371296D01*
X459528Y371410D01*
G02Y372984I1365J787D01*
G01X459553Y373026D01*
G03X459528Y375309I-2040J1119D01*
G01X459509Y375343D01*
G02X459528Y376884I1384J754D01*
G02X459918Y377530I16228J-9356D01*
G02X460368Y378130I993J-276D01*
G02X460818Y378280I540J-871D01*
G03X462018Y378880I-161J1821D01*
G03X462258Y379211I-1465J1315D01*
G03Y380785I-1364J787D01*
G02Y383111I2015J1163D01*
G03Y384685I-1365J787D01*
G02Y387011I2015J1163D01*
G03Y388585I-1365J787D01*
G02Y390909I2015J1162D01*
G01X462277Y390943D01*
G03X462258Y392484I-1384J754D01*
G02X462145Y394587I2015J1163D01*
G02X462258Y394808I2249J-1011D01*
G03Y396382I-1365J787D01*
G01X462233Y396424D01*
G02X462258Y398707I2040J1119D01*
G03X462277Y400248I-1365J787D01*
G01X462258Y400282D01*
G02Y402608I2015J1163D01*
G01X462277Y402642D01*
G03X462258Y404183I-1384J754D01*
G02X462223Y406449I2015J1164D01*
G01X462285Y406557D01*
G03X462258Y408083I-1392J739D01*
G02X464203Y411572I2015J1163D01*
G01X464332D01*
G03X465657Y413900I-59J1575D01*
G01X465638Y413934D01*
X465613Y413976D01*
G02X465638Y416259I2040J1119D01*
G03X465849Y417047I-1365J788D01*
G01Y419142D01*
X467498Y420791D01*
Y421358D01*
X466732Y422124D01*
G01X466600Y417047D02*
G02X466288Y415884I-2327J1D01*
G03X466269Y414343I1365J-787D01*
G01X466288Y414309D01*
X466313Y414267D01*
G02X464358Y410822I-2040J-1120D01*
G01X464254D01*
G03X462908Y408459I19J-1576D01*
G02X462943Y406193I-2015J-1164D01*
G01X462881Y406085D01*
G03X462908Y404559I1392J-739D01*
G02X462933Y402274I-2015J-1165D01*
G01X462908Y402232D01*
G03Y400658I1365J-787D01*
G02Y398332I-2015J-1163D01*
G03X462889Y396791I1365J-787D01*
G01X462908Y396757D01*
X462933Y396715D01*
G02X462908Y394432I-2040J-1119D01*
G03X462889Y394400I423J-273D01*
G03X462908Y392859I1384J-754D01*
G02X462933Y390576I-2015J-1164D01*
G01X462908Y390534D01*
X462889Y390500D01*
G03X462908Y388959I1384J-754D01*
G02X462933Y386676I-2015J-1164D01*
G01X462908Y386634D01*
X462889Y386600D01*
G03X462908Y385059I1384J-754D01*
G02X462933Y382776I-2015J-1164D01*
G01X462908Y382734D01*
X462889Y382700D01*
G03X462908Y381159I1384J-754D01*
G02X462933Y378876I-2015J-1164D01*
G01X462908Y378834D01*
X462842Y378718D01*
X462415Y378144D01*
X460893Y376096D01*
G01X457513Y370247D02*
Y368916D01*
X457285Y368688D01*
G02X456129Y371000I228J1559D01*
G01X456148Y371034D01*
G03X456173Y373317I-2015J1164D01*
G01X456148Y373359D01*
G02Y374933I1365J787D01*
G03Y377259I-2015J1163D01*
G02X456129Y378800I1365J787D01*
G01X456148Y378834D01*
X456173Y378876D01*
G03X456148Y381159I-2040J1119D01*
G02X456129Y382700I1365J787D01*
G01X456148Y382734D01*
X456173Y382776D01*
G03X456148Y385059I-2040J1119D01*
G02X456129Y386600I1365J787D01*
G01X456148Y386634D01*
X456173Y386676D01*
G03X456148Y388959I-2040J1119D01*
G02X456129Y390500I1365J787D01*
G01X456148Y390534D01*
X456173Y390576D01*
G03X456148Y392859I-2040J1119D01*
G02X456129Y394400I1365J787D01*
G01X456148Y394434D01*
X456173Y394476D01*
G03X456148Y396759I-2040J1119D01*
G02X456129Y398300I1365J787D01*
G01X456148Y398334D01*
X456173Y398376D01*
G03X456148Y400659I-2040J1119D01*
G02X456129Y402200I1365J787D01*
G01X456148Y402234D01*
X456173Y402276D01*
G03X456148Y404559I-2040J1119D01*
G02X456129Y406100I1365J787D01*
G01X456148Y406134D01*
X456173Y406176D01*
G03X456148Y408459I-2040J1119D01*
G02X456129Y410000I1365J787D01*
G01X456148Y410034D01*
X456173Y410076D01*
G03X456148Y412359I-2040J1119D01*
G02X457469Y414722I1365J788D01*
G01X457611D01*
G03X459840Y417046I-98J2325D01*
G01Y419202D01*
X460198Y419560D01*
Y422145D01*
X460353Y422300D01*
Y422387D01*
G01X457513Y378047D02*
G02X458878Y381161I14795J-4629D01*
G03Y382735I-1365J787D01*
G02Y385061I2015J1163D01*
G03Y386635I-1365J787D01*
G02Y388961I2015J1163D01*
G03Y390535I-1365J787D01*
G02X458742Y392585I2012J1163D01*
G02X458878Y392859I2047J-845D01*
G03X458905Y394385I-1365J787D01*
G01X458843Y394493D01*
G02X458878Y396759I2050J1102D01*
G03X458905Y398285I-1365J787D01*
G01X458843Y398393D01*
G02X458878Y400659I2050J1102D01*
G03X458905Y402185I-1365J787D01*
G01X458843Y402293D01*
G02X458878Y404559I2050J1102D01*
G03X458905Y406085I-1365J787D01*
G03X458843Y406193I-1663J-883D01*
G02X458878Y408459I2050J1102D01*
G03X458905Y409985I-1365J787D01*
G01X458843Y410093D01*
G02X460795Y413520I2050J1102D01*
G01X460912D01*
G03X462258Y415884I-19J1576D01*
G02X462224Y418148I2015J1163D01*
G01X462415Y418482D01*
X462417Y418486D01*
X463148Y419217D01*
Y422895D01*
X462993Y423050D01*
Y423137D01*
G01X457513Y366347D02*
Y367678D01*
X457257Y367934D01*
G02X455498Y371410I256J2313D01*
G03Y372984I-1365J787D01*
G01X455473Y373026D01*
G02X455498Y375309I2040J1119D01*
G01X455517Y375343D01*
G03X455498Y376884I-1384J754D01*
G02X455473Y379167I2015J1164D01*
G01X455498Y379209D01*
X455517Y379243D01*
G03X455498Y380784I-1384J754D01*
G02X455473Y383067I2015J1164D01*
G01X455498Y383109D01*
X455517Y383143D01*
G03X455498Y384684I-1384J754D01*
G02X455473Y386967I2015J1164D01*
G01X455498Y387009D01*
X455517Y387043D01*
G03X455498Y388584I-1384J754D01*
G02X455473Y390867I2015J1164D01*
G01X455498Y390909D01*
X455517Y390943D01*
G03X455498Y392484I-1384J754D01*
G02X455473Y394767I2015J1164D01*
G01X455498Y394809D01*
X455517Y394843D01*
G03X455498Y396384I-1384J754D01*
G02X455473Y398667I2015J1164D01*
G01X455498Y398709D01*
X455517Y398743D01*
G03X455498Y400284I-1384J754D01*
G02X455473Y402567I2015J1164D01*
G01X455498Y402609D01*
X455517Y402643D01*
G03X455498Y404184I-1384J754D01*
G02X455473Y406467I2015J1164D01*
G01X455498Y406509D01*
X455517Y406543D01*
G03X455498Y408084I-1384J754D01*
G02X455473Y410367I2015J1164D01*
G01X455498Y410409D01*
X455517Y410443D01*
G03X455498Y411984I-1384J754D01*
G02X457443Y415472I2015J1163D01*
G01X457593D01*
G03X459090Y417046I-80J1575D01*
G01Y419513D01*
X459448Y419871D01*
Y422145D01*
X459293Y422300D01*
Y422387D01*
G01X457513Y374146D02*
G02X458878Y377261I14855J-4653D01*
G03X459075Y378252I-1365J786D01*
G02X459528Y380785I4215J553D01*
G03Y383111I-2015J1163D01*
G02Y384685I1365J787D01*
G03Y387011I-2015J1163D01*
G02Y388585I1365J787D01*
G03Y390911I-2015J1163D01*
G02X459407Y392220I1371J787D01*
G02X459528Y392484I1473J-515D01*
G03X459553Y394767I-2015J1164D01*
G01X459528Y394809D01*
X459501Y394857D01*
G02X459528Y396383I1392J739D01*
G03X459563Y398649I-2015J1164D01*
G01X459501Y398757D01*
G02X459528Y400283I1392J739D01*
G03X459563Y402549I-2015J1164D01*
G01X459501Y402657D01*
G02X459528Y404183I1392J739D01*
G03X459563Y406449I-2015J1164D01*
G03X459501Y406557I-1966J-1057D01*
G02X459528Y408083I1392J739D01*
G03X459563Y410349I-2015J1164D01*
G01X459501Y410457D01*
G02X460834Y412770I1392J738D01*
G01X460963D01*
G03X462908Y416259I-69J2325D01*
G02X462881Y417785I1365J787D01*
G01X463019Y418027D01*
X463898Y418906D01*
Y422895D01*
X464053Y423050D01*
Y423137D01*
G01X469232Y422124D02*
X468248Y421140D01*
Y420467D01*
X466600Y418819D01*
Y417047D01*
G01X561647Y281922D02*
X561560D01*
X561360Y282122D01*
X558556D01*
G03X557703Y281345I655J-1575D01*
G02X556329Y280171I-2172J1151D01*
G01X555472D01*
G03X554166Y279384I59J-1575D01*
G02X552238Y278222I-2015J1163D01*
G02X552064I-87J2325D01*
G02X550136Y279384I87J2325D01*
G03X548830Y280171I-1365J-788D01*
G01X548712D01*
G03X547406Y279384I59J-1575D01*
G02X545442Y278221I-2015J1163D01*
G01X545347D01*
G03X544026Y277433I44J-1575D01*
G02X542096Y276271I-2015J1163D01*
G01X541926D01*
G02X539996Y277433I85J2325D01*
G03X538675Y278221I-1365J-787D01*
G01X538587D01*
G03X537266Y277433I44J-1575D01*
G02X535336Y276271I-2015J1163D01*
G01X535166D01*
G02X533236Y277433I85J2325D01*
G03X531915Y278221I-1365J-787D01*
G01X531820D01*
G02X529856Y279384I51J2326D01*
G03X528550Y280171I-1365J-788D01*
G01X528432D01*
G03X527126Y279384I59J-1575D01*
G02X525198Y278222I-2015J1163D01*
G02X525024I-87J2325D01*
G02X523096Y279384I87J2325D01*
G03X521789Y280171I-1365J-788D01*
G01X521651D01*
G03X520378Y279406I80J-1575D01*
G01X520380D01*
X520371Y279390D01*
X520369Y279386D01*
X520367Y279383D01*
G02X518422Y278221I-2015J1164D01*
G01X518301D01*
G02X516337Y279384I51J2326D01*
G03X515031Y280171I-1365J-788D01*
G01X514913D01*
G03X513607Y279384I59J-1575D01*
G02X511677Y278222I-2015J1163D01*
G01X511507D01*
G02X509577Y279384I85J2325D01*
G03X508271Y280171I-1365J-788D01*
G01X508153D01*
G03X506847Y279384I59J-1575D01*
G02X504917Y278222I-2015J1163D01*
G01X504747D01*
G02X502817Y279384I85J2325D01*
G03X501511Y280171I-1365J-788D01*
G01X501393D01*
G03X500087Y279384I59J-1575D01*
G02X498157Y278222I-2015J1163D01*
G01X497987D01*
G02X496057Y279384I85J2325D01*
G03X494751Y280171I-1365J-788D01*
G01X494633D01*
G03X493327Y279384I59J-1575D01*
G02X491397Y278222I-2015J1163D01*
G02X491384I-7J2326D01*
G01X491268D01*
G03X489947Y277434I44J-1575D01*
G02X488002Y276271I-2015J1162D01*
G01X487888D01*
G03X486567Y275483I44J-1575D01*
G02X484889Y274344I-2015J1163D01*
G02X484807Y274333I-350J2300D01*
G01X484552Y274078D01*
Y272747D01*
G01X561647Y283072D02*
X561560D01*
X561360Y282872D01*
X558413D01*
G03X557039Y281698I798J-2325D01*
G02X556186Y280921I-1508J798D01*
G01X555446D01*
G03X553516Y279759I85J-2325D01*
G02X552210Y278972I-1365J788D01*
G01X552092D01*
G02X550786Y279759I59J1575D01*
G03X548856Y280921I-2015J-1163D01*
G01X548686D01*
G03X546756Y279759I85J-2325D01*
G02X545450Y278972I-1365J788D01*
G01X545340D01*
G03X543376Y277809I51J-2326D01*
G02X542055Y277021I-1365J787D01*
G01X541967D01*
G02X540646Y277809I44J1575D01*
G03X538682Y278972I-2015J-1163D01*
G01X538580D01*
G03X536616Y277809I51J-2326D01*
G02X535295Y277021I-1365J787D01*
G01X535207D01*
G02X533886Y277809I44J1575D01*
G03X531922Y278972I-2015J-1163D01*
G01X531812D01*
G02X530506Y279759I59J1575D01*
G03X528576Y280921I-2015J-1163D01*
G01X528406D01*
G03X526476Y279759I85J-2325D01*
G02X525170Y278972I-1365J788D01*
G01X525052D01*
G02X523746Y279759I59J1575D01*
G03X521816Y280921I-2015J-1163D01*
G01X521633D01*
G03X519716Y279760I98J-2325D01*
G01X519703Y279737D01*
G02X518399Y278972I-1352J810D01*
G02X518317I-41J1575D01*
G02X516987Y279759I34J1575D01*
G03X515057Y280921I-2015J-1163D01*
G01X514887D01*
G03X512957Y279759I85J-2325D01*
G02X511651Y278972I-1365J788D01*
G01X511533D01*
G02X510227Y279759I59J1575D01*
G03X508297Y280921I-2015J-1163D01*
G01X508127D01*
G03X506197Y279759I85J-2325D01*
G02X504891Y278972I-1365J788D01*
G01X504773D01*
G02X503467Y279759I59J1575D01*
G03X501537Y280921I-2015J-1163D01*
G01X501367D01*
G03X499437Y279759I85J-2325D01*
G02X498131Y278972I-1365J788D01*
G01X498013D01*
G02X496707Y279759I59J1575D01*
G03X494777Y280921I-2015J-1163D01*
G01X494607D01*
G03X492677Y279759I85J-2325D01*
G02X491371Y278972I-1365J788D01*
G01X491242D01*
G03X489297Y277809I70J-2325D01*
G02X487976Y277021I-1365J787D01*
G01X487847D01*
G03X485917Y275859I85J-2325D01*
G02X484780Y275087I-1365J787D01*
G01X484552Y275315D01*
Y276646D01*
G01X556341Y261421D02*
X555446D01*
G03X553516Y260259I85J-2325D01*
G02X552210Y259472I-1365J788D01*
G01X552092D01*
G02X550786Y260259I59J1575D01*
G03X548856Y261421I-2015J-1163D01*
G01X548686D01*
G03X546756Y260259I85J-2325D01*
G02X545450Y259472I-1365J788D01*
G01X545332D01*
G02X544026Y260259I59J1575D01*
G03X542096Y261421I-2015J-1163D01*
G01X541926D01*
G03X539996Y260259I85J-2325D01*
G02X538690Y259472I-1365J788D01*
G01X538572D01*
G02X537266Y260259I59J1575D01*
G03X535336Y261421I-2015J-1163D01*
G01X535166D01*
G03X533236Y260259I85J-2325D01*
G02X531930Y259472I-1365J788D01*
G01X531812D01*
G02X530506Y260259I59J1575D01*
G03X528576Y261421I-2015J-1163D01*
G01X528406D01*
G03X526617Y260476I84J-2325D01*
G01X526265Y260381D01*
X525111Y261047D01*
G01X484500Y271177D02*
G03X485917Y271959I61J1565D01*
G02X487847Y273121I2015J-1163D01*
G01X488017D01*
G02X489947Y271959I-85J-2325D01*
G03X491253Y271172I1365J788D01*
G01X491371D01*
G03X492677Y271959I-59J1575D01*
G02X494607Y273121I2015J-1163D01*
G01X494736D01*
G03X496032Y273867I0J1499D01*
G01X496057Y273909D01*
G02X498002Y275072I2015J-1162D01*
G01X498142D01*
G02X500087Y273909I-70J-2325D01*
G03X502817I1365J787D01*
G02X504762Y275072I2015J-1162D01*
G01X504902D01*
G02X506847Y273909I-70J-2325D01*
G03X509577I1365J787D01*
G02X511522Y275072I2015J-1162D01*
G01X511662D01*
G02X513607Y273909I-70J-2325D01*
G03X516337I1365J787D01*
G02X518282Y275072I2015J-1162D01*
G01X518422D01*
G02X520367Y273909I-70J-2325D01*
G01X520380Y273886D01*
G03X523096Y273909I1351J810D01*
G02X525041Y275072I2015J-1162D01*
G01X525181D01*
G02X527126Y273909I-70J-2325D01*
G03X529856I1365J787D01*
G02X533886I2015J-1162D01*
G03X536616I1365J787D01*
G02X538561Y275072I2015J-1162D01*
G01X538701D01*
G02X540646Y273909I-70J-2325D01*
G03X543376I1365J787D01*
G02X545321Y275072I2015J-1162D01*
G01X545461D01*
G02X547406Y273909I-70J-2325D01*
G03X550136I1365J787D01*
G02X552081Y275072I2015J-1162D01*
G01X552221D01*
G02X554166Y273909I-70J-2325D01*
G03X556896I1365J787D01*
G02X557000Y274074I2018J-1157D01*
G02X557265Y274392I1912J-1324D01*
G01X558224Y275351D01*
X561213D01*
G01X494692Y266896D02*
X496707Y269634D01*
X496732Y269676D01*
G03X496707Y271959I-2040J1119D01*
G02X499437Y273534I1365J787D01*
G03X501382Y272371I2015J1162D01*
G01X501522D01*
G03X503467Y273534I-70J2325D01*
G02X506197I1365J-787D01*
G03X508142Y272371I2015J1162D01*
G01X508282D01*
G03X510227Y273534I-70J2325D01*
G02X512957I1365J-787D01*
G03X514902Y272371I2015J1162D01*
G01X515042D01*
G03X516987Y273534I-70J2325D01*
G02X518281Y274321I1365J-787D01*
G01X518400D01*
G02X519716Y273534I-48J-1574D01*
G03X521661Y272371I2015J1162D01*
G01X521801D01*
G03X523746Y273534I-70J2325D01*
G02X525040Y274321I1365J-787D01*
G01X525182D01*
G02X526476Y273534I-71J-1574D01*
G03X528421Y272371I2015J1162D01*
G01X528561D01*
G03X530506Y273534I-70J2325D01*
G02X533236I1365J-787D01*
G03X535181Y272371I2015J1162D01*
G01X535321D01*
G03X537266Y273534I-70J2325D01*
G02X538560Y274321I1365J-787D01*
G01X538702D01*
G02X539996Y273534I-71J-1574D01*
G03X541941Y272371I2015J1162D01*
G01X542081D01*
G03X544026Y273534I-70J2325D01*
G02X545320Y274321I1365J-787D01*
G01X545462D01*
G02X546756Y273534I-71J-1574D01*
G03X548701Y272371I2015J1162D01*
G01X548841D01*
G03X550786Y273534I-70J2325D01*
G02X552080Y274321I1365J-787D01*
G01X552222D01*
G02X553516Y273534I-71J-1574D01*
G03X555461Y272371I2015J1162D01*
G01X555601D01*
G03X557546Y273534I-70J2325D01*
G02X557796Y273862I1368J-783D01*
G01X558534Y274600D01*
X560900D01*
G01X566368Y258949D02*
X558349D01*
X556921Y257521D01*
X555446D01*
G03X553516Y256359I85J-2325D01*
G02X552210Y255572I-1365J788D01*
G01X552092D01*
G02X550786Y256359I59J1575D01*
G03X548856Y257521I-2015J-1163D01*
G01X548686D01*
G03X546756Y256359I85J-2325D01*
G02X545450Y255572I-1365J788D01*
G01X545332D01*
G02X544026Y256359I59J1575D01*
G03X542096Y257521I-2015J-1163D01*
G01X541926D01*
G03X539996Y256359I85J-2325D01*
G02X537266I-1365J788D01*
G03X535252Y257522I-2014J-1162D01*
G01X535250D01*
G03X533236Y256359I0J-2325D01*
G02X531930Y255572I-1365J788D01*
G01X531812D01*
G02X530506Y256359I59J1575D01*
G03X528576Y257521I-2015J-1163D01*
G01X528345D01*
X525111Y257147D01*
G01X556256Y260644D02*
X555966D01*
X555939Y260671D01*
X555472D01*
G03X554166Y259884I59J-1575D01*
G02X552236Y258722I-2015J1163D01*
G01X552066D01*
G02X550136Y259884I85J2325D01*
G03X548830Y260671I-1365J-788D01*
G01X548712D01*
G03X547406Y259884I59J-1575D01*
G02X545476Y258722I-2015J1163D01*
G01X545306D01*
G02X543376Y259884I85J2325D01*
G03X542070Y260671I-1365J-788D01*
G01X541952D01*
G03X540646Y259884I59J-1575D01*
G02X538716Y258722I-2015J1163D01*
G01X538546D01*
G02X536616Y259884I85J2325D01*
G03X535310Y260671I-1365J-788D01*
G01X535192D01*
G03X533886Y259884I59J-1575D01*
G02X531956Y258722I-2015J1163D01*
G01X531786D01*
G02X529856Y259884I85J2325D01*
G03X528550Y260671I-1365J-788D01*
G01X528432D01*
G03X527254Y260072I60J-1575D01*
G01X527337Y259762D01*
X528491Y259096D01*
G01X563936Y256765D02*
X561941D01*
X560376Y255200D01*
X558000D01*
X556429Y256771D01*
X555472D01*
G03X554166Y255984I59J-1575D01*
G02X552236Y254822I-2015J1163D01*
G01X552066D01*
G02X550136Y255984I85J2325D01*
G03X548830Y256771I-1365J-788D01*
G01X548712D01*
G03X547406Y255984I59J-1575D01*
G02X545476Y254822I-2015J1163D01*
G01X545306D01*
G02X543376Y255984I85J2325D01*
G03X542070Y256771I-1365J-788D01*
G01X541952D01*
G03X540646Y255984I59J-1575D01*
G02X538632Y254821I-2014J1162D01*
G01X538630D01*
G02X536616Y255984I0J2325D01*
G03X533886I-1365J-788D01*
G02X531956Y254822I-2015J1163D01*
G01X531786D01*
G02X529856Y255984I85J2325D01*
G03X528550Y256771I-1365J-788D01*
G01X528432D01*
G03X527126Y255984I59J-1575D01*
G02X525196Y254822I-2015J1163D01*
G01X525026D01*
G02X523096Y255984I85J2325D01*
G03X521790Y256771I-1365J-788D01*
G01X521593D01*
G01X498072Y261047D02*
X496918Y260381D01*
X496824Y260029D01*
G02X496732Y257976I-2131J-933D01*
G01X496707Y257934D01*
X496688Y257900D01*
G03X498013Y255572I1384J-753D01*
G01X498142D01*
G02X500087Y254409I-70J-2325D01*
G03X501408Y253621I1365J787D01*
G01X501537D01*
G02X503467Y252459I-85J-2325D01*
G03X504773Y251672I1365J788D01*
G01X504902D01*
G02X506847Y250509I-70J-2325D01*
G03X508168Y249721I1365J787D01*
G01X508297D01*
G02X510227Y248559I-85J-2325D01*
G03X512957I1365J788D01*
G02X514887Y249721I2015J-1163D01*
G01X515057D01*
G02X516987Y248559I-85J-2325D01*
G03X519684Y248504I1365J788D01*
G01X519716Y248560D01*
G02X521729Y249722I2013J-1163D01*
G01X521732D01*
G02X521816Y249720I-13J-2325D01*
G02X523746Y248559I-84J-2324D01*
G03X526476I1365J788D01*
G02X530506I2015J-1163D01*
G03X533236I1365J788D01*
G02X537266I2015J-1163D01*
G03X539996I1365J788D01*
G02X544026I2015J-1163D01*
G03X546756I1365J788D01*
G02X550786I2015J-1163D01*
G03X553516I1365J788D01*
G02X557546I2015J-1163D01*
G01X557800Y248100D01*
X558100Y247800D01*
X559000Y247703D01*
G01X494692Y259096D02*
X495846Y259762D01*
X496156Y259678D01*
G02X496076Y258343I-1465J-582D01*
G01X496057Y258309D01*
X496032Y258267D01*
G03X497987Y254822I2040J-1120D01*
G01X498116D01*
G02X499437Y254034I-44J-1575D01*
G03X501382Y252871I2015J1162D01*
G01X501511D01*
G02X502817Y252084I-59J-1575D01*
G03X504747Y250922I2015J1163D01*
G01X504876D01*
G02X506197Y250134I-44J-1575D01*
G03X508142Y248971I2015J1162D01*
G01X508271D01*
G02X509577Y248184I-59J-1575D01*
G03X513607I2015J1163D01*
G02X514913Y248971I1365J-788D01*
G01X515031D01*
G02X516337Y248184I-59J-1575D01*
G01X516362Y248142D01*
G03X520367Y248183I1990J1205D01*
G01X520380Y248206D01*
G02X521665Y248970I1351J-810D01*
G02X521789I62J-1575D01*
G02X523096Y248184I-57J-1575D01*
G03X527126I2015J1163D01*
G02X529856I1365J-788D01*
G03X533886I2015J1163D01*
G02X536616I1365J-788D01*
G03X540646I2015J1163D01*
G02X543376I1365J-788D01*
G03X547406I2015J1163D01*
G02X550136I1365J-788D01*
G03X554166I2015J1163D01*
G02X556896I1365J-788D01*
G01X557248Y247448D01*
X557600Y246900D01*
X559000Y246703D01*
G01X564554Y334571D02*
X564467D01*
X564267Y334771D01*
X561793D01*
G02X560419Y335945I798J2325D01*
G03X559566Y336722I-1508J-798D01*
G01X558867D01*
G03X557546Y335934I44J-1575D01*
G02X555601Y334771I-2015J1162D01*
G01X555461D01*
G02X553516Y335934I70J2325D01*
G03X552198Y336722I-1365J-787D01*
G03X552104I-47J-1575D01*
G03X550786Y335934I47J-1575D01*
G02X548841Y334771I-2015J1162D01*
G01X548701D01*
G02X546756Y335934I70J2325D01*
G03X545438Y336722I-1365J-787D01*
G03X545344I-47J-1575D01*
G03X544026Y335934I47J-1575D01*
G02X542081Y334771I-2015J1162D01*
G01X541941D01*
G02X539996Y335934I70J2325D01*
G03X538678Y336722I-1365J-787D01*
G03X538584I-47J-1575D01*
G03X537266Y335934I47J-1575D01*
G02X535321Y334771I-2015J1162D01*
G01X535181D01*
G02X533236Y335934I70J2325D01*
G03X530506I-1365J-787D01*
G02X528561Y334771I-2015J1162D01*
G01X528421D01*
G02X526476Y335934I70J2325D01*
G03X525158Y336722I-1365J-787D01*
G03X525064I-47J-1575D01*
G03X523746Y335934I47J-1575D01*
G02X521801Y334771I-2015J1162D01*
G01X521731D01*
G03X520380Y334006I0J-1575D01*
G01X520367Y333983D01*
G02X518450Y332822I-2015J1164D01*
G01X518308D01*
G03X516987Y332034I44J-1575D01*
G02X515042Y330871I-2015J1162D01*
G01X514913D01*
G03X513607Y330084I59J-1575D01*
G02X511677Y328922I-2015J1163D01*
G01X511548D01*
G03X510227Y328134I44J-1575D01*
G02X508282Y326971I-2015J1162D01*
G01X508153D01*
G03X506847Y326184I59J-1575D01*
G02X504883Y325021I-2015J1163D01*
G01X504788D01*
G03X503467Y324233I44J-1575D01*
G02X501537Y323071I-2015J1163D01*
G01X501408D01*
G03X500087Y322283I44J-1575D01*
G02X498157Y321121I-2015J1163D01*
G01X498001D01*
G03X496707Y320334I71J-1574D01*
G02X494762Y319171I-2015J1162D01*
G01X494633D01*
G03X493327Y318384I59J-1575D01*
G02X491397Y317222I-2015J1163D01*
G01X491268D01*
G03X489947Y316434I44J-1575D01*
G02X488002Y315271I-2015J1162D01*
G01X487873D01*
G03X486567Y314484I59J-1575D01*
G02X484808Y313334I-2015J1162D01*
G01X484552Y313078D01*
Y311747D01*
G01X564554Y335721D02*
X564467D01*
X564267Y335521D01*
X561936D01*
G02X561083Y336298I655J1575D01*
G03X559709Y337472I-2172J-1151D01*
G01X558841D01*
G03X556896Y336309I70J-2325D01*
G02X555578Y335521I-1365J787D01*
G02X555484I-47J1575D01*
G02X554166Y336309I47J1575D01*
G03X552221Y337472I-2015J-1162D01*
G01X552081D01*
G03X550136Y336309I70J-2325D01*
G02X548818Y335521I-1365J787D01*
G02X548724I-47J1575D01*
G02X547406Y336309I47J1575D01*
G03X545461Y337472I-2015J-1162D01*
G01X545321D01*
G03X543376Y336309I70J-2325D01*
G02X542058Y335521I-1365J787D01*
G02X541964I-47J1575D01*
G02X540646Y336309I47J1575D01*
G03X538701Y337472I-2015J-1162D01*
G01X538561D01*
G03X536616Y336309I70J-2325D01*
G02X535298Y335521I-1365J787D01*
G02X535204I-47J1575D01*
G02X533886Y336309I47J1575D01*
G03X529856I-2015J-1162D01*
G02X528538Y335521I-1365J787D01*
G02X528444I-47J1575D01*
G02X527126Y336309I47J1575D01*
G03X525181Y337472I-2015J-1162D01*
G01X525041D01*
G03X523096Y336309I70J-2325D01*
G02X521775Y335521I-1365J787D01*
G01X521633D01*
G03X519716Y334360I98J-2325D01*
G01X519703Y334337D01*
G02X518352Y333572I-1351J810D01*
G01X518282D01*
G03X516337Y332409I70J-2325D01*
G02X515016Y331621I-1365J787D01*
G01X514887D01*
G03X512957Y330459I85J-2325D01*
G02X511651Y329672I-1365J788D01*
G01X511522D01*
G03X509577Y328509I70J-2325D01*
G02X508256Y327721I-1365J787D01*
G01X508127D01*
G03X506197Y326559I85J-2325D01*
G02X504891Y325772I-1365J788D01*
G01X504781D01*
G03X502817Y324609I51J-2326D01*
G02X501496Y323821I-1365J787D01*
G01X501367D01*
G03X499437Y322659I85J-2325D01*
G02X498143Y321872I-1365J787D01*
G01X498002D01*
G03X496057Y320709I70J-2325D01*
G02X494736Y319921I-1365J787D01*
G01X494607D01*
G03X492677Y318759I85J-2325D01*
G02X491371Y317972I-1365J788D01*
G01X491242D01*
G03X489297Y316809I70J-2325D01*
G02X487976Y316021I-1365J787D01*
G01X487847D01*
G03X485917Y314859I85J-2325D01*
G02X484780Y314088I-1365J789D01*
G01X484552Y314316D01*
Y315647D01*
G01X563306Y302279D02*
Y302192D01*
X563106Y301992D01*
Y294865D01*
X554263Y286022D01*
X552107D01*
G03X550786Y285234I44J-1575D01*
G02X546756I-2015J1162D01*
G03X544026I-1365J-787D01*
G02X539996I-2015J1162D01*
G03X537266I-1365J-787D01*
G02X535321Y284071I-2015J1162D01*
G01X535192D01*
G03X533886Y283284I59J-1575D01*
G02X531956Y282122I-2015J1163D01*
G01X531786D01*
G02X529856Y283284I85J2325D01*
G03X528550Y284071I-1365J-788D01*
G01X528421D01*
G02X526476Y285234I70J2325D01*
G03X523746I-1365J-787D01*
G02X519716I-2015J1162D01*
G01X519690Y285279D01*
G03X516987Y285234I-1338J-832D01*
G02X512957I-2015J1162D01*
G03X510227I-1365J-787D01*
G02X506197I-2015J1162D01*
G03X503467I-1365J-787D01*
G02X499437I-2015J1162D01*
G03X496707I-1365J-787D01*
G02X492677I-2015J1162D01*
G03X489947I-1365J-787D01*
G02X488002Y284071I-2015J1162D01*
G01X487862D01*
G02X485917Y285234I70J2325D01*
G03X484599Y286022I-1365J-787D01*
G03X484505I-47J-1575D01*
G03X483187Y285234I47J-1575D01*
G02X481429Y284084I-2015J1162D01*
G01X481172Y283827D01*
Y282496D01*
G01X562156Y302279D02*
Y302192D01*
X562356Y301992D01*
Y300942D01*
X562006Y300592D01*
Y299542D01*
X562356Y299192D01*
Y298142D01*
X562006Y297792D01*
Y296742D01*
X562356Y296392D01*
Y295176D01*
X555932Y288752D01*
X555437D01*
X554694Y288009D01*
Y287514D01*
X553952Y286772D01*
X552081D01*
G03X550136Y285609I70J-2325D01*
G02X547406I-1365J787D01*
G03X543376I-2015J-1162D01*
G02X540646I-1365J787D01*
G03X536616I-2015J-1162D01*
G02X535295Y284821I-1365J787D01*
G01X535166D01*
G03X533236Y283659I85J-2325D01*
G02X531930Y282872I-1365J788D01*
G01X531812D01*
G02X530506Y283659I59J1575D01*
G03X528576Y284821I-2015J-1163D01*
G01X528447D01*
G02X527126Y285609I44J1575D01*
G03X523096I-2015J-1162D01*
G02X520393Y285564I-1365J787D01*
G01X520367Y285609D01*
G03X516337I-2015J-1162D01*
G02X513607I-1365J787D01*
G03X509577I-2015J-1162D01*
G02X506847I-1365J787D01*
G03X502817I-2015J-1162D01*
G02X500087I-1365J787D01*
G03X496057I-2015J-1162D01*
G02X493327I-1365J787D01*
G03X489297I-2015J-1162D01*
G02X487979Y284821I-1365J787D01*
G02X487885I-47J1575D01*
G02X486567Y285609I47J1575D01*
G03X484622Y286772I-2015J-1162D01*
G01X484482D01*
G03X482537Y285609I70J-2325D01*
G02X481400Y284837I-1365J787D01*
G01X481172Y285065D01*
Y286396D01*
G01Y348796D02*
X480018Y349462D01*
X479935Y349772D01*
G02X481113Y350371I1238J-976D01*
G01X481231D01*
G02X482537Y349584I-59J-1575D01*
G03X484467Y348422I2015J1163D01*
G01X484637D01*
G03X486567Y349584I-85J2325D01*
G02X487873Y350371I1365J-788D01*
G01X487991D01*
G02X489297Y349584I-59J-1575D01*
G03X491227Y348422I2015J1163D01*
G01X491397D01*
G03X493327Y349584I-85J2325D01*
G02X494633Y350371I1365J-788D01*
G01X494751D01*
G02X496057Y349584I-59J-1575D01*
G03X500087I2015J1163D01*
G02X502817I1365J-788D01*
G03X504747Y348422I2015J1163D01*
G01X504917D01*
G03X506847Y349584I-85J2325D01*
G02X508153Y350371I1365J-788D01*
G01X508271D01*
G02X509577Y349584I-59J-1575D01*
G03X511507Y348422I2015J1163D01*
G01X511677D01*
G03X513607Y349584I-85J2325D01*
G02X514913Y350371I1365J-788D01*
G01X515031D01*
G02X516337Y349584I-59J-1575D01*
G03X518267Y348422I2015J1163D01*
G01X518450D01*
G03X520367Y349583I-98J2325D01*
G01X520380Y349606D01*
G02X521731Y350371I1351J-810D01*
G01X521790D01*
G02X523096Y349584I-59J-1575D01*
G03X525026Y348422I2015J1163D01*
G01X525196D01*
G03X527126Y349584I-85J2325D01*
G02X528432Y350371I1365J-788D01*
G01X528550D01*
G02X529856Y349584I-59J-1575D01*
G03X533886I2015J1163D01*
G02X535192Y350371I1365J-788D01*
G01X535310D01*
G02X536616Y349584I-59J-1575D01*
G03X540646I2015J1163D01*
G02X541952Y350371I1365J-788D01*
G01X542070D01*
G02X543376Y349584I-59J-1575D01*
G03X545306Y348422I2015J1163D01*
G01X545476D01*
G03X547406Y349584I-85J2325D01*
G02X548712Y350371I1365J-788D01*
G01X548830D01*
G02X550136Y349584I-59J-1575D01*
G03X552066Y348422I2015J1163D01*
G01X552195D01*
G02X553516Y347634I-44J-1575D01*
G03X555461Y346471I2015J1162D01*
G01X556511D01*
X556861Y346121D01*
X557911D01*
X558261Y346471D01*
X559311D01*
X559661Y346121D01*
X560711D01*
X561061Y346471D01*
X565061D01*
X565261Y346271D01*
X565348D01*
G01X481172Y364396D02*
X482469Y367392D01*
X482556Y367543D01*
G03X482537Y369084I-1384J754D01*
G02Y371410I2015J1163D01*
G03X482603Y372868I-1123J781D01*
G01X482537Y372984D01*
X482512Y373026D01*
G02X484501Y376472I2040J1120D01*
G01X484611D01*
G03X485936Y378800I-59J1575D01*
G01X485917Y378834D01*
X485892Y378876D01*
G02X485917Y381159I2040J1119D01*
G03X485936Y382700I-1365J787D01*
G01X485917Y382734D01*
X485892Y382776D01*
G02X485917Y385059I2040J1119D01*
G03X485936Y386600I-1365J787D01*
G01X485917Y386634D01*
X485892Y386676D01*
G02X485917Y388959I2040J1119D01*
G03X485936Y390500I-1365J787D01*
G01X485917Y390534D01*
X485892Y390576D01*
G02X485917Y392859I2040J1119D01*
G03X485936Y394400I-1365J787D01*
G01X485917Y394434D01*
G02X487847Y397922I2015J1163D01*
G01X488003D01*
G03X489297Y400284I-71J1574D01*
G02X489272Y402567I2015J1164D01*
G01X489297Y402609D01*
X489316Y402643D01*
G03X489297Y404184I-1384J754D01*
G02X491242Y407672I2015J1163D01*
G01X491371D01*
G03X492677Y408459I-59J1575D01*
G02X494607Y409621I2015J-1163D01*
G01X494736D01*
G03X496057Y410409I-44J1575D01*
G02X497987Y411571I2015J-1163D01*
G01X500117D01*
X501981Y413435D01*
Y414534D01*
G01X484552Y374146D02*
X486501Y376769D01*
X486567Y376884D01*
G03X486592Y379167I-2015J1164D01*
G01X486567Y379209D01*
X486548Y379243D01*
G02X486567Y380784I1384J754D01*
G03X486592Y383067I-2015J1164D01*
G01X486567Y383109D01*
X486548Y383143D01*
G02X486567Y384684I1384J754D01*
G03X486592Y386967I-2015J1164D01*
G01X486567Y387009D01*
X486548Y387043D01*
G02X486567Y388584I1384J754D01*
G03X486592Y390867I-2015J1164D01*
G01X486567Y390909D01*
X486548Y390943D01*
G02X486567Y392484I1384J754D01*
G03Y394810I-2015J1163D01*
G02X487861Y397171I1365J787D01*
G01X488017D01*
G03X489947Y400659I-85J2325D01*
G02X489928Y402200I1365J787D01*
G01X489947Y402234D01*
X489972Y402276D01*
G03X489947Y404559I-2040J1119D01*
G02X491268Y406922I1365J788D01*
G01X491397D01*
G03X493327Y408084I-85J2325D01*
G02X494633Y408871I1365J-788D01*
G01X494777D01*
G03X496707Y410033I-85J2325D01*
G02X498028Y410821I1365J-787D01*
G01X500428D01*
X502398Y412791D01*
X503774D01*
G01X481172Y368296D02*
X479786Y371447D01*
G02X479807Y372983I1386J749D01*
G03Y375309I-2015J1163D01*
G02X480092Y377243I1365J787D01*
G02X481906Y378602I5140J-4970D01*
G03X482537Y379209I-731J1392D01*
G03Y380783I-1364J787D01*
G02Y383109I2015J1163D01*
G03Y384683I-1365J787D01*
G02Y387009I2015J1163D01*
G03Y388583I-1365J787D01*
G02Y390909I2017J1163D01*
G01X482556Y390943D01*
G03X482537Y392484I-1384J754D01*
G02X482512Y394767I2015J1164D01*
G01X482537Y394809D01*
X482556Y394843D01*
G03X482537Y396384I-1384J754D01*
G02X484482Y399872I2015J1163D01*
G01X484611D01*
G03X485936Y402200I-59J1575D01*
G01X485917Y402234D01*
X485892Y402276D01*
G02X485917Y404559I2040J1119D01*
G03X485936Y406100I-1365J787D01*
G01X485917Y406134D01*
X485892Y406176D01*
G02X487847Y409621I2040J1120D01*
G01X487976D01*
G03X489297Y410409I-44J1575D01*
G02X491242Y411572I2015J-1162D01*
G01X491371D01*
G03X492677Y412359I-59J1575D01*
G02X494607Y413521I2015J-1163D01*
G01X494736D01*
G03X496057Y414309I-44J1575D01*
G01X496668Y415366D01*
X498063Y416761D01*
Y417688D01*
G01X481172Y376096D02*
X482893Y377986D01*
G02X483043Y378498I5621J-1369D01*
G02X483187Y378833I1510J-450D01*
G03Y381159I-2017J1163D01*
G02Y382733I1365J787D01*
G03Y385059I-2015J1163D01*
G02Y386633I1365J787D01*
G03Y388959I-2015J1163D01*
G02X483212Y390576I1365J788D01*
G03X483187Y392859I-2040J1119D01*
G02X483168Y394400I1365J787D01*
G01X483187Y394434D01*
X483212Y394476D01*
G03X483187Y396759I-2040J1119D01*
G02X484508Y399122I1365J788D01*
G01X484637D01*
G03X486592Y402567I-85J2325D01*
G01X486567Y402609D01*
X486548Y402643D01*
G02X486567Y404184I1384J754D01*
G03X486592Y406467I-2015J1164D01*
G01X486567Y406509D01*
X486548Y406543D01*
G02X487873Y408871I1384J753D01*
G01X488002D01*
G03X489947Y410034I-70J2325D01*
G02X491268Y410822I1365J-787D01*
G01X491397D01*
G03X493327Y411984I-85J2325D01*
G02X494633Y412771I1365J-788D01*
G01X494777D01*
G03X496707Y413933I-85J2325D01*
G01X496705Y413935D01*
X497243Y414862D01*
X498380Y416002D01*
X499913D01*
G01X1278900Y-14800D02*
X1273605Y-20095D01*
X719895D01*
X715083Y-15283D01*
Y-9167D01*
X716427Y-7823D01*
X719802D01*
X720750Y-6875D01*
Y333D01*
X720749Y334D01*
Y577D01*
X719102Y2224D01*
Y5598D01*
X715000Y9700D01*
X709500D01*
X708400Y8600D01*
X705250D01*
G01X930987Y267609D02*
X930131Y269891D01*
X929690Y270605D01*
X929622Y270722D01*
G03X927677Y271885I-2015J-1162D01*
G01X927548D01*
G02X926242Y272672I59J1575D01*
G03X924312Y273834I-2015J-1163D01*
G01X924142D01*
G03X922212Y272672I85J-2325D01*
G02X920906Y271885I-1365J788D01*
G01X920777D01*
G03X918832Y270722I70J-2325D01*
G02X917511Y269934I-1365J787D01*
G01X916667D01*
G03X915295Y268761I800J-2325D01*
G02X914444Y267985I-1508J799D01*
G01X912842D01*
X911506Y269321D01*
G01Y266821D02*
X911920Y267235D01*
X914587D01*
G03X915959Y268408I-800J2325D01*
G02X916810Y269184I1508J-799D01*
G01X917537D01*
G03X919482Y270347I-70J2325D01*
G02X920803Y271135I1365J-787D01*
G01X920932D01*
G03X922862Y272297I-85J2325D01*
G02X924168Y273084I1365J-788D01*
G01X924286D01*
G02X925592Y272297I-59J-1575D01*
G03X927522Y271135I2015J1163D01*
G01X927651D01*
G02X928972Y270347I-44J-1575D01*
G01X929186Y269976D01*
X929413Y267686D01*
G03X930943Y266034I1574J-77D01*
G01X931356D01*
X933511Y266983D01*
G02X935732Y266447I856J-1323D01*
G01X935798Y266331D01*
X937747Y263709D01*
G01X915786Y274261D02*
X916112Y273935D01*
X916963Y273934D01*
X917289D01*
X917798Y273971D01*
G03X918683Y274724I-631J1638D01*
G02X919911Y275785I2164J-1264D01*
G01X920906D01*
G03X922212Y276572I-59J1575D01*
G02X926242I2015J-1163D01*
G03X927548Y275785I1365J788D01*
G01X927677D01*
G02X929622Y274622I-70J-2325D01*
G03X930943Y273834I1365J787D01*
G01X931072D01*
G02X933277Y271920I-85J-2325D01*
G01X934367Y269560D01*
G01X915898Y272529D02*
X916553Y273184D01*
X917345D01*
X917951Y273229D01*
G03X919331Y274345I-784J2380D01*
G02X920072Y275035I1516J-885D01*
G01X920932D01*
G03X922862Y276197I-85J2325D01*
G02X924168Y276984I1365J-788D01*
G01X924286D01*
G02X925592Y276197I-59J-1575D01*
G03X927522Y275035I2015J1163D01*
G01X927651D01*
G02X928972Y274247I-44J-1575D01*
G03X930917Y273084I2015J1162D01*
G01X931046D01*
G02X932371Y270756I-59J-1575D01*
G01X932352Y270722D01*
X932327Y270680D01*
G03X932406Y268841I1443J-859D01*
G03X933757Y268108I1433J1030D01*
G03X934323Y267986I609J1453D01*
G01X934511D01*
X937747Y267609D01*
G01X908000Y263180D02*
X908087D01*
X908242Y263335D01*
X914009D01*
G03X915959Y264508I0J2207D01*
G02X916810Y265284I1508J-799D01*
G01X917537D01*
G03X919482Y266447I-70J2325D01*
G02X920803Y267235I1365J-787D01*
G01X920932D01*
G03X922862Y268397I-85J2325D01*
G02X924168Y269184I1365J-788D01*
G01X924286D01*
G02X925592Y268397I-59J-1575D01*
G03X925979Y267793I6585J3793D01*
G01X926496Y267064D01*
X927607Y265660D01*
G01X908000Y264240D02*
X908087D01*
X908242Y264085D01*
X914010D01*
X914009Y264086D01*
G03X915296Y264860I0J1456D01*
G01X915293Y264857D01*
X915295Y264861D01*
G02X916667Y266034I2172J-1152D01*
G01X937747Y333909D02*
X936448Y330910D01*
X936382Y330797D01*
G02X934452Y329635I-2015J1163D01*
G01X934323D01*
G03X933002Y328847I44J-1575D01*
G02X931057Y327684I-2015J1162D01*
G01X930916D01*
G03X929622Y326897I71J-1574D01*
G02X927692Y325735I-2015J1163D01*
G01X927563D01*
G03X926242Y324947I44J-1575D01*
G02X922212I-2015J1163D01*
G03X920891Y325735I-1365J-787D01*
G01X920762D01*
G02X918832Y326897I85J2325D01*
G03X917538Y327684I-1365J-787D01*
G01X916808D01*
G03X916407Y327394I420J-1004D01*
G01X915530Y326385D01*
X914882Y325737D01*
X912660D01*
X910156Y328241D01*
X909557D01*
X908696Y327380D01*
G01X930987Y330009D02*
X929037Y327387D01*
X928972Y327273D01*
G02X927651Y326485I-1365J787D01*
G01X927522D01*
G03X925592Y325323I85J-2325D01*
G02X922862I-1365J787D01*
G03X920932Y326485I-2015J-1163D01*
G01X920803D01*
G02X919482Y327273I44J1575D01*
G03X917552Y328435I-2015J-1163D01*
G01X916669D01*
G03X915295Y327261I798J-2325D01*
G01X914867Y326790D01*
X914562Y326485D01*
X912970D01*
X910466Y328989D01*
X909707D01*
X908816Y329880D01*
G01X937747Y330009D02*
X936447Y327009D01*
X936382Y326897D01*
G02X934452Y325735I-2015J1163D01*
G01X934323D01*
G03X933002Y324947I44J-1575D01*
G02X931038Y323784I-2015J1163D01*
G01X930928D01*
G03X929622Y322997I59J-1575D01*
G02X927692Y321835I-2015J1163D01*
G01X927563D01*
G03X926242Y321047I44J-1575D01*
G02X924297Y319884I-2015J1162D01*
G01X924157D01*
G02X922212Y321047I70J2325D01*
G03X920891Y321835I-1365J-787D01*
G01X920762D01*
G02X918832Y322997I85J2325D01*
G03X917526Y323784I-1365J-788D01*
G01X916499D01*
X915396Y322681D01*
X910327D01*
X909426Y321780D01*
G01X934367Y328060D02*
X932417Y325436D01*
X932352Y325323D01*
G02X931031Y324535I-1365J787D01*
G01X930936D01*
G03X928972Y323372I51J-2326D01*
G02X927666Y322585I-1365J788D01*
G01X927537D01*
G03X925592Y321422I70J-2325D01*
G02X922862I-1365J787D01*
G03X920917Y322585I-2015J-1162D01*
G01X920788D01*
G02X919482Y323372I59J1575D01*
G03X917539Y324534I-2015J-1163D01*
G01X916188D01*
X915083Y323429D01*
X910277D01*
X909426Y324280D01*
G01X934367Y335860D02*
X935521Y336525D01*
X935831Y336441D01*
G02X934426Y334285I-1465J-581D01*
G01X934297D01*
G03X932352Y333122I70J-2325D01*
G02X931031Y332334I-1365J787D01*
G01X930902D01*
G03X928972Y331172I85J-2325D01*
G02X927666Y330385I-1365J788D01*
G01X927537D01*
G03X925592Y329222I70J-2325D01*
G02X924298Y328435I-1365J787D01*
G01X924156D01*
G02X922862Y329222I71J1574D01*
G03X920917Y330385I-2015J-1162D01*
G01X920788D01*
G02X919482Y331172I59J1575D01*
G03X917552Y332334I-2015J-1163D01*
G01X916812D01*
G02X916046Y332965I655J1575D01*
G01Y333024D01*
X915959Y333111D01*
G03X914585Y334285I-2172J-1151D01*
G01X912339D01*
X911879Y333825D01*
X910355D01*
X910200Y333980D01*
X910113D01*
G01Y332920D02*
X910200D01*
X910355Y333075D01*
X912190D01*
X912650Y333535D01*
X914448D01*
G02X915296Y332760I-661J-1575D01*
G01Y332759D01*
X915295Y332758D01*
G03X915419Y332549I2174J1148D01*
G03X916669Y331584I2048J1360D01*
G01X917526D01*
G02X918832Y330797I-59J-1575D01*
G03X920762Y329635I2015J1163D01*
G01X920891D01*
G02X922212Y328847I-44J-1575D01*
G03X924157Y327684I2015J1162D01*
G01X924297D01*
G03X926242Y328847I-70J2325D01*
G02X927563Y329635I1365J-787D01*
G01X927692D01*
G03X929622Y330797I-85J2325D01*
G02X930928Y331584I1365J-788D01*
G01X931057D01*
G03X933002Y332747I-70J2325D01*
G02X934323Y333535I1365J-787D01*
G01X934452D01*
G03X936499Y336793I-85J2325D01*
G01X936593Y337144D01*
X937747Y337809D01*
G01X1170452Y269191D02*
X1169975Y270009D01*
G03X1168030Y271172I-2015J-1162D01*
G01X1167901D01*
G02X1166595Y271959I59J1575D01*
G02X1166576Y273500I1365J787D01*
G01X1166595Y273534D01*
X1166620Y273576D01*
G03X1166595Y275859I-2040J1119D01*
G02Y277433I1365J787D01*
G03Y279759I-2015J1163D01*
G02X1166576Y281300I1365J787D01*
G01X1166595Y281334D01*
X1166620Y281376D01*
G03X1166595Y283659I-2040J1119D01*
G02X1166576Y285200I1365J787D01*
G01X1166595Y285234D01*
X1166620Y285276D01*
G03X1166595Y287559I-2040J1119D01*
G02X1166576Y289100I1365J787D01*
G01X1166595Y289134D01*
X1166620Y289176D01*
G03X1166595Y291459I-2040J1119D01*
G02X1166576Y293000I1365J787D01*
G01X1166595Y293034D01*
X1166620Y293076D01*
G03X1166595Y295359I-2040J1119D01*
G02X1166576Y296900I1365J787D01*
G01X1166595Y296934D01*
X1166620Y296976D01*
G03X1166595Y299259I-2040J1119D01*
G03X1164665Y300421I-2015J-1163D01*
G01X1164536D01*
G02X1163215Y301209I44J1575D01*
G01X1163196Y301243D01*
G02X1163215Y302784I1384J754D01*
G03X1163240Y305067I-2015J1164D01*
G01X1163215Y305109D01*
G03X1161270Y306272I-2015J-1162D01*
G01X1161141D01*
G02X1159835Y307059I59J1575D01*
G02X1159816Y308600I1365J787D01*
G01X1159835Y308634D01*
G03Y310960I-2015J1163D01*
G02Y312534I1365J787D01*
G01X1159860Y312576D01*
G03X1159835Y314859I-2040J1119D01*
G03X1157905Y316021I-2015J-1163D01*
G01X1157776D01*
G02X1156455Y316809I44J1575D01*
G03X1154510Y317972I-2015J-1162D01*
G01X1154381D01*
G02X1153075Y318759I59J1575D01*
G02X1153056Y320300I1365J787D01*
G01X1153075Y320334D01*
X1153100Y320376D01*
G03X1153075Y322659I-2040J1119D01*
G03X1151145Y323821I-2015J-1163D01*
G01X1151016D01*
G02X1149695Y324609I44J1575D01*
G03X1147731Y325772I-2015J-1163D01*
G01X1147621D01*
G02X1146315Y326559I59J1575D01*
G03X1144385Y327721I-2015J-1163D01*
G01X1144256D01*
G02X1142935Y328509I44J1575D01*
G03X1140990Y329672I-2015J-1162D01*
G01X1140861D01*
G02X1139555Y330459I59J1575D01*
G03X1137625Y331621I-2015J-1163D01*
G01X1137496D01*
G02X1136175Y332409I44J1575D01*
G03X1134230Y333572I-2015J-1162D01*
G01X1134101D01*
G02X1132795Y334359I59J1575D01*
G03X1130865Y335521I-2015J-1163D01*
G01X1130736D01*
G02X1129415Y336309I44J1575D01*
G03X1127470Y337472I-2015J-1162D01*
G01X1127400D01*
G02X1126049Y338237I0J1575D01*
G01X1126036Y338260D01*
G03X1124119Y339421I-2015J-1164D01*
G01X1123977D01*
G02X1122656Y340209I44J1575D01*
G03X1120711Y341372I-2015J-1162D01*
G01X1120582D01*
G02X1119276Y342159I59J1575D01*
G03X1117345Y343322I-2016J-1162D01*
G01X1117260Y343321D01*
G02X1115909Y344086I0J1575D01*
G01X1115896Y344109D01*
G03X1113951Y345272I-2015J-1162D01*
G01X1113822D01*
G02X1112516Y346059I59J1575D01*
G03X1110585Y347222I-2016J-1162D01*
G01X1110500Y347221D01*
G02X1109149Y347986I0J1575D01*
G01X1109136Y348009D01*
G03X1107191Y349172I-2015J-1162D01*
G01X1107062D01*
G02X1105756Y349959I59J1575D01*
G03X1103826Y351121I-2015J-1163D01*
G01X1103697D01*
G02X1102376Y351909I44J1575D01*
G03X1100431Y353072I-2015J-1162D01*
G01X1100302D01*
G02X1098996Y353859I59J1575D01*
G03X1097066Y355021I-2015J-1163D01*
G01X1096937D01*
G02X1095616Y355809I44J1575D01*
G03X1093671Y356972I-2015J-1162D01*
G01X1093531D01*
G03X1091586Y355809I70J-2325D01*
G02X1090265Y355021I-1365J787D01*
G01X1090177D01*
G02X1088856Y355809I44J1575D01*
G03X1086911Y356972I-2015J-1162D01*
G01X1086771D01*
G03X1084826Y355809I70J-2325D01*
G01X1084813Y355786D01*
G02X1083462Y355021I-1351J810D01*
G01X1083418D01*
G02X1082097Y355809I44J1575D01*
G03X1080152Y356972I-2015J-1162D01*
G01X1080012D01*
G03X1078067Y355809I70J-2325D01*
G02X1076746Y355021I-1365J787D01*
G01X1076658D01*
G02X1075337Y355809I44J1575D01*
G03X1073392Y356972I-2015J-1162D01*
G01X1063386D01*
X1062631Y357727D01*
X1056529D01*
X1054619Y359637D01*
X1052666D01*
G03X1050649Y358472I0J-2328D01*
G02X1049343Y357685I-1365J788D01*
G01X1049225D01*
G02X1047919Y358472I59J1575D01*
G03X1045989Y359634I-2015J-1163D01*
G01X1045819D01*
G03X1043889Y358472I85J-2325D01*
G02X1042583Y357685I-1365J788D01*
G01X1042524D01*
G02X1041173Y358450I0J1575D01*
G01X1041160Y358473D01*
G03X1039243Y359634I-2015J-1164D01*
G01X1039060D01*
G03X1037130Y358472I85J-2325D01*
G02X1034400I-1365J788D01*
G03X1032470Y359634I-2015J-1163D01*
G01X1032300D01*
G03X1030370Y358472I85J-2325D01*
G02X1029064Y357685I-1365J788D01*
G01X1028935D01*
G03X1026990Y356522I70J-2325D01*
G02X1025669Y355734I-1365J787D01*
G01X1025540D01*
G03X1023610Y354572I85J-2325D01*
G02X1022304Y353785I-1365J788D01*
G01X1022175D01*
G03X1020230Y352622I70J-2325D01*
G02X1018909Y351834I-1365J787D01*
G01X1018780D01*
G03X1016850Y350672I85J-2325D01*
G02X1015544Y349885I-1365J788D01*
G01X1015426D01*
G02X1014120Y350672I59J1575D01*
G03X1012190Y351834I-2015J-1163D01*
G01X1012061D01*
G02X1010740Y352622I44J1575D01*
G03X1008795Y353785I-2015J-1162D01*
G01X1008655D01*
G03X1006710Y352622I70J-2325D01*
G02X1005389Y351834I-1365J787D01*
G01X1005260D01*
G03X1003330Y350672I85J-2325D01*
G02X1002024Y349885I-1365J788D01*
G01X1001895D01*
G03X999950Y348722I70J-2325D01*
G01X999937Y348699D01*
G02X998586Y347934I-1351J810D01*
G01X998501D01*
G03X996571Y346772I85J-2325D01*
G02X995265Y345985I-1365J788D01*
G01X995136D01*
G03X993191Y344822I70J-2325D01*
G02X991870Y344034I-1365J787D01*
G01X991741D01*
G03X989811Y342872I85J-2325D01*
G02X988505Y342085I-1365J788D01*
G01X988376D01*
G03X986431Y340922I70J-2325D01*
G01X986406Y340880D01*
G03X986431Y338597I2040J-1119D01*
G02X986450Y337056I-1365J-787D01*
G01X986431Y337022D01*
X986406Y336980D01*
G03X986431Y334697I2040J-1119D01*
G02X986450Y333156I-1365J-787D01*
G01X986431Y333122D01*
X986406Y333080D01*
G03X986431Y330797I2040J-1119D01*
G02X986450Y329256I-1365J-787D01*
G01X986431Y329222D01*
G02X985137Y328435I-1365J787D01*
G01X984981D01*
G03X983051Y327273I85J-2325D01*
G02X981730Y326485I-1365J787D01*
G01X981601D01*
G03X979671Y325323I85J-2325D01*
G02X978350Y324535I-1365J787D01*
G01X978255D01*
G03X976291Y323372I51J-2326D01*
G02X974985Y322585I-1365J788D01*
G01X974856D01*
G03X972911Y321422I70J-2325D01*
G02X971590Y320634I-1365J787D01*
G01X971461D01*
G03X969531Y319472I85J-2325D01*
G02X968225Y318685I-1365J788D01*
G01X968107D01*
G02X966801Y319472I59J1575D01*
G03X964871Y320634I-2015J-1163D01*
G01X964742D01*
G02X963421Y321422I44J1575D01*
G03X961476Y322585I-2015J-1162D01*
G01X961336D01*
G03X959391Y321422I70J-2325D01*
G02X958070Y320634I-1365J787D01*
G01X957928D01*
G03X956011Y319473I98J-2325D01*
G01X955998Y319450D01*
G02X953282Y319472I-1352J810D01*
G03X951352Y320634I-2015J-1163D01*
G01X951182D01*
G03X949252Y319472I85J-2325D01*
G02X947946Y318685I-1365J788D01*
G01X947828D01*
G02X946522Y319472I59J1575D01*
G03X944592Y320634I-2015J-1163D01*
G01X944422D01*
G03X942492Y319472I85J-2325D01*
G02X941186Y318685I-1365J788D01*
G01X941057D01*
G03X939112Y317522I70J-2325D01*
G02X936382I-1365J787D01*
G03X934437Y318685I-2015J-1162D01*
G01X934297D01*
G03X932352Y317522I70J-2325D01*
G02X929622I-1365J787D01*
G03X927677Y318685I-2015J-1162D01*
G01X927537D01*
G03X925592Y317522I70J-2325D01*
G02X924271Y316734I-1365J787D01*
G01X923327D01*
X921512Y318549D01*
X920364D01*
G01X1167960Y264947D02*
X1169113Y265612D01*
X1169207Y265962D01*
G02X1169324Y268060I2132J933D01*
G03Y269634I-1364J787D01*
G01X1169311Y269657D01*
G03X1167960Y270422I-1351J-810D01*
G01X1167875D01*
G02X1165945Y271584I85J2325D01*
G02X1165920Y273867I2015J1164D01*
G01X1165945Y273909D01*
G03Y275483I-1365J787D01*
G02Y277809I2015J1163D01*
G01X1165964Y277843D01*
G03X1165945Y279384I-1384J754D01*
G02X1165920Y281667I2015J1164D01*
G01X1165945Y281709D01*
X1165964Y281743D01*
G03X1165945Y283284I-1384J754D01*
G02X1165920Y285567I2015J1164D01*
G01X1165945Y285609D01*
X1165964Y285643D01*
G03X1165945Y287184I-1384J754D01*
G02X1165920Y289467I2015J1164D01*
G01X1165945Y289509D01*
X1165964Y289543D01*
G03X1165945Y291084I-1384J754D01*
G02X1165920Y293367I2015J1164D01*
G01X1165945Y293409D01*
X1165964Y293443D01*
G03X1165945Y294984I-1384J754D01*
G02X1165920Y297267I2015J1164D01*
G01X1165945Y297309D01*
X1165964Y297343D01*
G03X1165945Y298884I-1384J754D01*
G03X1164639Y299671I-1365J-788D01*
G01X1164510D01*
G02X1162565Y300834I70J2325D01*
G01X1162540Y300876D01*
G02X1162565Y303159I2040J1119D01*
G03X1162584Y304700I-1365J787D01*
G01X1162565Y304734D01*
G03X1161244Y305522I-1365J-787D01*
G01X1161115D01*
G02X1159185Y306684I85J2325D01*
G02Y309010I2015J1163D01*
G03Y310584I-1365J787D01*
G02X1159160Y312867I2015J1164D01*
G01X1159185Y312909D01*
X1159204Y312943D01*
G03X1159185Y314484I-1384J754D01*
G03X1157879Y315271I-1365J-788D01*
G01X1157750D01*
G02X1155805Y316434I70J2325D01*
G03X1154484Y317222I-1365J-787D01*
G01X1154355D01*
G02X1152425Y318384I85J2325D01*
G02X1152400Y320667I2015J1164D01*
G01X1152425Y320709D01*
G03Y322283I-1365J787D01*
G03X1151104Y323071I-1365J-787D01*
G01X1150975D01*
G02X1149045Y324233I85J2325D01*
G03X1147724Y325021I-1365J-787D01*
G01X1147629D01*
G02X1145665Y326184I51J2326D01*
G03X1144359Y326971I-1365J-788D01*
G01X1144230D01*
G02X1142285Y328134I70J2325D01*
G03X1140964Y328922I-1365J-787D01*
G01X1140835D01*
G02X1138905Y330084I85J2325D01*
G03X1137599Y330871I-1365J-788D01*
G01X1137470D01*
G02X1135525Y332034I70J2325D01*
G03X1134204Y332822I-1365J-787D01*
G01X1134075D01*
G02X1132145Y333984I85J2325D01*
G03X1130839Y334771I-1365J-788D01*
G01X1130710D01*
G02X1128765Y335934I70J2325D01*
G03X1127444Y336722I-1365J-787D01*
G01X1127302D01*
G02X1125385Y337883I98J2325D01*
G01X1125372Y337906D01*
G03X1124021Y338671I-1351J-810D01*
G01X1123951D01*
G02X1122006Y339834I70J2325D01*
G03X1120685Y340622I-1365J-787D01*
G01X1120556D01*
G02X1118626Y341784I85J2325D01*
G03X1117320Y342571I-1365J-788D01*
G01X1117261D01*
X1117191Y342570D01*
G02X1115245Y343734I70J2325D01*
G01X1115232Y343757D01*
G03X1113881Y344522I-1351J-810D01*
G01X1113796D01*
G02X1111866Y345684I85J2325D01*
G03X1110560Y346471I-1365J-788D01*
G01X1110501D01*
X1110431Y346470D01*
G02X1108485Y347634I70J2325D01*
G01X1108472Y347657D01*
G03X1107121Y348422I-1351J-810D01*
G01X1107036D01*
G02X1105106Y349584I85J2325D01*
G03X1103800Y350371I-1365J-788D01*
G01X1103671D01*
G02X1101726Y351534I70J2325D01*
G03X1100405Y352322I-1365J-787D01*
G01X1100276D01*
G02X1098346Y353484I85J2325D01*
G03X1097040Y354271I-1365J-788D01*
G01X1096911D01*
G02X1094966Y355434I70J2325D01*
G03X1093645Y356222I-1365J-787D01*
G01X1093557D01*
G03X1092236Y355434I44J-1575D01*
G02X1090291Y354271I-2015J1162D01*
G01X1090151D01*
G02X1088206Y355434I70J2325D01*
G03X1086885Y356222I-1365J-787D01*
G01X1086841D01*
G03X1085490Y355457I0J-1575D01*
G01X1085477Y355434D01*
G02X1083532Y354271I-2015J1162D01*
G01X1083392D01*
G02X1081447Y355434I70J2325D01*
G03X1080126Y356222I-1365J-787D01*
G01X1080038D01*
G03X1078717Y355434I44J-1575D01*
G02X1076772Y354271I-2015J1162D01*
G01X1076632D01*
G02X1074687Y355434I70J2325D01*
G03X1073366Y356222I-1365J-787D01*
G01X1063075D01*
X1062319Y356978D01*
X1056218D01*
X1054313Y358883D01*
X1052661D01*
G03X1051299Y358097I0J-1573D01*
G02X1049369Y356935I-2015J1163D01*
G01X1049199D01*
G02X1047269Y358097I85J2325D01*
G03X1045963Y358884I-1365J-788D01*
G01X1045845D01*
G03X1044539Y358097I59J-1575D01*
G02X1042609Y356935I-2015J1163D01*
G01X1042426D01*
G02X1040509Y358096I98J2325D01*
G01X1040496Y358119D01*
G03X1039145Y358884I-1351J-810D01*
G01X1039086D01*
G03X1037780Y358097I59J-1575D01*
G02X1033750I-2015J1163D01*
G03X1032444Y358884I-1365J-788D01*
G01X1032326D01*
G03X1031020Y358097I59J-1575D01*
G02X1029090Y356935I-2015J1163D01*
G01X1028961D01*
G03X1027640Y356147I44J-1575D01*
G02X1025695Y354984I-2015J1162D01*
G01X1025566D01*
G03X1024260Y354197I59J-1575D01*
G02X1022330Y353035I-2015J1163D01*
G01X1022201D01*
G03X1020880Y352247I44J-1575D01*
G02X1018935Y351084I-2015J1162D01*
G01X1018806D01*
G03X1017500Y350297I59J-1575D01*
G02X1015570Y349135I-2015J1163D01*
G01X1015400D01*
G02X1013470Y350297I85J2325D01*
G03X1012164Y351084I-1365J-788D01*
G01X1012035D01*
G02X1010090Y352247I70J2325D01*
G03X1008769Y353035I-1365J-787D01*
G01X1008681D01*
G03X1007360Y352247I44J-1575D01*
G02X1005415Y351084I-2015J1162D01*
G01X1005286D01*
G03X1003980Y350297I59J-1575D01*
G02X1002050Y349135I-2015J1163D01*
G01X1001965D01*
G03X1000614Y348370I0J-1575D01*
G01X1000601Y348347D01*
G02X998656Y347184I-2015J1162D01*
G01X998527D01*
G03X997221Y346397I59J-1575D01*
G02X995291Y345235I-2015J1163D01*
G01X995162D01*
G03X993841Y344447I44J-1575D01*
G02X991896Y343284I-2015J1162D01*
G01X991767D01*
G03X990461Y342497I59J-1575D01*
G02X988531Y341335I-2015J1163D01*
G01X988402D01*
G03X987081Y340547I44J-1575D01*
G01X987062Y340513D01*
G03X987081Y338972I1384J-754D01*
G02X987106Y336689I-2015J-1164D01*
G01X987081Y336647D01*
X987062Y336613D01*
G03X987081Y335072I1384J-754D01*
G02X987106Y332789I-2015J-1164D01*
G01X987081Y332747D01*
X987062Y332713D01*
G03X987081Y331172I1384J-754D01*
G02X987106Y328889I-2015J-1164D01*
G01X987081Y328847D01*
G02X985136Y327684I-2015J1162D01*
G01X984995D01*
G03X983701Y326897I71J-1574D01*
G02X981771Y325735I-2015J1163D01*
G01X981642D01*
G03X980321Y324947I44J-1575D01*
G02X978357Y323784I-2015J1163D01*
G01X978247D01*
G03X976941Y322997I59J-1575D01*
G02X975011Y321835I-2015J1163D01*
G01X974882D01*
G03X973561Y321047I44J-1575D01*
G02X971616Y319884I-2015J1162D01*
G01X971487D01*
G03X970181Y319097I59J-1575D01*
G02X968251Y317935I-2015J1163D01*
G01X968081D01*
G02X966151Y319097I85J2325D01*
G03X964845Y319884I-1365J-788D01*
G01X964716D01*
G02X962771Y321047I70J2325D01*
G03X960041I-1365J-787D01*
G02X958096Y319884I-2015J1162D01*
G01X958026D01*
G03X956675Y319119I0J-1575D01*
G01X956662Y319096D01*
G02X954745Y317935I-2015J1164D01*
G01X954562D01*
G02X952632Y319097I85J2325D01*
G03X951326Y319884I-1365J-788D01*
G01X951208D01*
G03X949902Y319097I59J-1575D01*
G02X947972Y317935I-2015J1163D01*
G01X947802D01*
G02X945872Y319097I85J2325D01*
G03X944566Y319884I-1365J-788D01*
G01X944448D01*
G03X943142Y319097I59J-1575D01*
G02X941212Y317935I-2015J1163D01*
G01X941083D01*
G03X939762Y317147I44J-1575D01*
G02X937817Y315984I-2015J1162D01*
G01X937677D01*
G02X935732Y317147I70J2325D01*
G03X933002I-1365J-787D01*
G02X931057Y315984I-2015J1162D01*
G01X930917D01*
G02X928972Y317147I70J2325D01*
G03X926242I-1365J-787D01*
G02X924297Y315984I-2015J1162D01*
G01X923016D01*
X921270Y317730D01*
X920226D01*
G01X917613Y307398D02*
X918779Y306232D01*
X921259D01*
X922031Y305460D01*
G03X923368Y304284I2196J1149D01*
G01X924297D01*
G03X926242Y305447I-70J2325D01*
G02X927563Y306235I1365J-787D01*
G01X927651D01*
G02X928972Y305447I-44J-1575D01*
G03X930917Y304284I2015J1162D01*
G01X931057D01*
G03X933002Y305447I-70J2325D01*
G02X934323Y306235I1365J-787D01*
G01X934411D01*
G02X935732Y305447I-44J-1575D01*
G03X939762I2015J1162D01*
G02X941083Y306235I1365J-787D01*
G01X941212D01*
G03X943142Y307397I-85J2325D01*
G02X944448Y308184I1365J-788D01*
G01X944566D01*
G02X945872Y307397I-59J-1575D01*
G03X947802Y306235I2015J1163D01*
G01X947972D01*
G03X949902Y307397I-85J2325D01*
G02X951208Y308184I1365J-788D01*
G01X951326D01*
G02X952632Y307397I-59J-1575D01*
G03X954562Y306235I2015J1163D01*
G01X954745D01*
G03X956662Y307396I-98J2325D01*
G01X956675Y307419D01*
G02X958026Y308184I1351J-810D01*
G01X958096D01*
G03X960041Y309347I-70J2325D01*
G02X961362Y310135I1365J-787D01*
G01X961450D01*
G02X962771Y309347I-44J-1575D01*
G03X964716Y308184I2015J1162D01*
G01X964845D01*
G02X966151Y307397I-59J-1575D01*
G03X968081Y306235I2015J1163D01*
G01X968251D01*
G03X970181Y307397I-85J2325D01*
G02X971487Y308184I1365J-788D01*
G01X971616D01*
G03X973561Y309347I-70J2325D01*
G02X974882Y310135I1365J-787D01*
G01X975011D01*
G03X976941Y311297I-85J2325D01*
G02X978247Y312084I1365J-788D01*
G01X978376D01*
G03X980321Y313247I-70J2325D01*
G02X981642Y314035I1365J-787D01*
G01X981771D01*
G03X983701Y315197I-85J2325D01*
G02X985007Y315984I1365J-788D01*
G01X985136D01*
G03X987081Y317147I-70J2325D01*
G02X988402Y317935I1365J-787D01*
G01X988531D01*
G03X990461Y319097I-85J2325D01*
G02X991767Y319884I1365J-788D01*
G01X991896D01*
G03X993841Y321047I-70J2325D01*
G02X995162Y321835I1365J-787D01*
G01X995291D01*
G03X997221Y322997I-85J2325D01*
G03Y325323I-2015J1163D01*
G02Y326897I1365J787D01*
G03X997246Y329180I-2015J1164D01*
G01X997221Y329222D01*
X997202Y329256D01*
G02X997221Y330797I1384J754D01*
G03X997246Y333080I-2015J1164D01*
G01X997221Y333122D01*
X997202Y333156D01*
G02X997221Y334697I1384J754D01*
G02X998527Y335484I1365J-788D01*
G01X998656D01*
G03X1000601Y336647I-70J2325D01*
G01X1000614Y336670D01*
G02X1001965Y337435I1351J-810D01*
G01X1002050D01*
G03X1003980Y338597I-85J2325D01*
G02X1005286Y339384I1365J-788D01*
G01X1005415D01*
G03X1007360Y340547I-70J2325D01*
G03X1008725Y343660I-13429J7744D01*
G01X918145Y307930D02*
X919094Y306981D01*
X921570D01*
X922642Y305909D01*
X922695Y305807D01*
G03X923515Y305033I1532J802D01*
G01X923518D01*
X923519Y305034D01*
X924271D01*
G03X925592Y305822I-44J1575D01*
G02X927537Y306985I2015J-1162D01*
G01X927677D01*
G02X929622Y305822I-70J-2325D01*
G03X930943Y305034I1365J787D01*
G01X931031D01*
G03X932352Y305822I-44J1575D01*
G02X934297Y306985I2015J-1162D01*
G01X934437D01*
G02X936382Y305822I-70J-2325D01*
G03X939112I1365J787D01*
G02X941057Y306985I2015J-1162D01*
G01X941186D01*
G03X942492Y307772I-59J1575D01*
G02X944422Y308934I2015J-1163D01*
G01X944592D01*
G02X946522Y307772I-85J-2325D01*
G03X947828Y306985I1365J788D01*
G01X947946D01*
G03X949252Y307772I-59J1575D01*
G02X951182Y308934I2015J-1163D01*
G01X951352D01*
G02X953282Y307772I-85J-2325D01*
G03X954588Y306985I1365J788D01*
G01X954647D01*
G03X955998Y307750I0J1575D01*
G01X956011Y307773D01*
G02X957928Y308934I2015J-1164D01*
G01X958070D01*
G03X959391Y309722I-44J1575D01*
G02X961336Y310885I2015J-1162D01*
G01X961476D01*
G02X963421Y309722I-70J-2325D01*
G03X964742Y308934I1365J787D01*
G01X964871D01*
G02X966801Y307772I-85J-2325D01*
G03X968107Y306985I1365J788D01*
G01X968225D01*
G03X969531Y307772I-59J1575D01*
G02X971461Y308934I2015J-1163D01*
G01X971590D01*
G03X972911Y309722I-44J1575D01*
G02X974856Y310885I2015J-1162D01*
G01X974985D01*
G03X976291Y311672I-59J1575D01*
G02X978221Y312834I2015J-1163D01*
G01X978350D01*
G03X979671Y313622I-44J1575D01*
G02X981616Y314785I2015J-1162D01*
G01X981745D01*
G03X983051Y315572I-59J1575D01*
G02X984981Y316734I2015J-1163D01*
G01X985110D01*
G03X986431Y317522I-44J1575D01*
G02X988376Y318685I2015J-1162D01*
G01X988505D01*
G03X989811Y319472I-59J1575D01*
G02X991741Y320634I2015J-1163D01*
G01X991870D01*
G03X993191Y321422I-44J1575D01*
G02X995136Y322585I2015J-1162D01*
G01X995265D01*
G03X996571Y323372I-59J1575D01*
G03X996590Y324913I-1365J787D01*
G01X996571Y324947D01*
G02Y327273I2015J1163D01*
G03Y328847I-1365J787D01*
G01X996546Y328889D01*
G02X996571Y331172I2040J1119D01*
G03X996590Y332713I-1365J787D01*
G01X996571Y332747D01*
X996546Y332789D01*
G02X996571Y335072I2040J1119D01*
G02X998501Y336234I2015J-1163D01*
G01X998586D01*
G03X999937Y336999I0J1575D01*
G01X999950Y337022D01*
G02X1001895Y338185I2015J-1162D01*
G01X1002024D01*
G03X1003330Y338972I-59J1575D01*
G02X1005260Y340134I2015J-1163D01*
G01X1005389D01*
G03X1006710Y340922I-44J1575D01*
G03X1007164Y343442I-3282J1892D01*
G02X1007341Y344413I1561J217D01*
G01X1007360Y344447D01*
G02X1008681Y345235I1365J-787D01*
G03X1012105Y345609I0J15860D01*
G01X918234Y314522D02*
X921770D01*
X923458Y312834D01*
X924271D01*
G03X925592Y313622I-44J1575D01*
G02X927537Y314785I2015J-1162D01*
G01X927677D01*
G02X929622Y313622I-70J-2325D01*
G03X930943Y312834I1365J787D01*
G01X931031D01*
G03X932352Y313622I-44J1575D01*
G02X934297Y314785I2015J-1162D01*
G01X934437D01*
G02X936382Y313622I-70J-2325D01*
G03X937703Y312834I1365J787D01*
G01X937791D01*
G03X939112Y313622I-44J1575D01*
G02X941057Y314785I2015J-1162D01*
G01X941186D01*
G03X942492Y315572I-59J1575D01*
G02X944422Y316734I2015J-1163D01*
G01X944592D01*
G02X946522Y315572I-85J-2325D01*
G03X947828Y314785I1365J788D01*
G01X947946D01*
G03X949252Y315572I-59J1575D01*
G02X953282I2015J-1163D01*
G03X954588Y314785I1365J788D01*
G01X954647D01*
G03X955998Y315550I0J1575D01*
G01X956011Y315573D01*
G02X957928Y316734I2015J-1164D01*
G01X958070D01*
G03X959391Y317522I-44J1575D01*
G02X961336Y318685I2015J-1162D01*
G01X961476D01*
G02X963421Y317522I-70J-2325D01*
G03X964742Y316734I1365J787D01*
G01X964871D01*
G02X966801Y315572I-85J-2325D01*
G03X968107Y314785I1365J788D01*
G01X968225D01*
G03X969531Y315572I-59J1575D01*
G02X971461Y316734I2015J-1163D01*
G01X971590D01*
G03X972911Y317522I-44J1575D01*
G02X974856Y318685I2015J-1162D01*
G01X974985D01*
G03X976291Y319472I-59J1575D01*
G02X978221Y320634I2015J-1163D01*
G01X978350D01*
G03X979671Y321422I-44J1575D01*
G02X981616Y322585I2015J-1162D01*
G01X981745D01*
G03X983051Y323372I-59J1575D01*
G02X985015Y324535I2015J-1163D01*
G01X985110D01*
G03X986431Y325323I-44J1575D01*
G02X988361Y326485I2015J-1163D01*
G01X988490D01*
G03X989811Y327273I-44J1575D01*
G03Y328847I-1365J787D01*
G01X989786Y328889D01*
G02X989811Y331172I2040J1119D01*
G03X989830Y332713I-1365J787D01*
G01X989811Y332747D01*
X989786Y332789D01*
G02X989811Y335072I2040J1119D01*
G03X989830Y336613I-1365J787D01*
G01X989811Y336647D01*
X989786Y336689D01*
G02X989811Y338972I2040J1119D01*
G02X991741Y340134I2015J-1163D01*
G01X991870D01*
G03X993191Y340922I-44J1575D01*
G02X995136Y342085I2015J-1162D01*
G01X995265D01*
G03X996571Y342872I-59J1575D01*
G02X998501Y344034I2015J-1163D01*
G01X998586D01*
G03X999937Y344799I0J1575D01*
G01X999950Y344822D01*
G02X1001895Y345985I2015J-1162D01*
G01X1002024D01*
G03X1003330Y346772I-59J1575D01*
G02X1005260Y347934I2015J-1163D01*
G01X1005389D01*
G03X1006710Y348722I-44J1575D01*
G02X1008655Y349885I2015J-1162D01*
G01X1008795D01*
G02X1010436Y349025I-62J-2115D01*
G01X1010947Y348330D01*
G03X1012469Y347560I1523J1120D01*
G01X1015485D01*
G01X1005345Y341709D02*
G03X1003980Y342497I-682J394D01*
G02X1002050Y341335I-2015J1163D01*
G01X1001965D01*
G03X1000614Y340570I0J-1575D01*
G01X1000601Y340547D01*
G02X998656Y339384I-2015J1162D01*
G01X998527D01*
G03X997221Y338597I59J-1575D01*
G02X995291Y337435I-2015J1163D01*
G01X995162D01*
G03X993841Y336647I44J-1575D01*
G01X993822Y336613D01*
G03X993841Y335072I1384J-754D01*
G02X993866Y332789I-2015J-1164D01*
G01X993841Y332747D01*
X993822Y332713D01*
G03X993841Y331172I1384J-754D01*
G02X993866Y328889I-2015J-1164D01*
G01X993841Y328847D01*
G03Y327273I1365J-787D01*
G02Y324947I-2015J-1163D01*
G02X991877Y323784I-2015J1163D01*
G01X991767D01*
G03X990461Y322997I59J-1575D01*
G02X988531Y321835I-2015J1163D01*
G01X988402D01*
G03X987081Y321047I44J-1575D01*
G02X985136Y319884I-2015J1162D01*
G01X985007D01*
G03X983701Y319097I59J-1575D01*
G02X981771Y317935I-2015J1163D01*
G01X981642D01*
G03X980321Y317147I44J-1575D01*
G02X978376Y315984I-2015J1162D01*
G01X978247D01*
G03X976941Y315197I59J-1575D01*
G02X975011Y314035I-2015J1163D01*
G01X974882D01*
G03X973561Y313247I44J-1575D01*
G02X971616Y312084I-2015J1162D01*
G01X971487D01*
G03X970181Y311297I59J-1575D01*
G02X968251Y310135I-2015J1163D01*
G01X968081D01*
G02X966151Y311297I85J2325D01*
G03X964845Y312084I-1365J-788D01*
G01X964716D01*
G02X962771Y313247I70J2325D01*
G03X961450Y314035I-1365J-787D01*
G01X961362D01*
G03X960041Y313247I44J-1575D01*
G02X958096Y312084I-2015J1162D01*
G01X958026D01*
G03X956675Y311319I0J-1575D01*
G01X956662Y311296D01*
G02X954745Y310135I-2015J1164D01*
G01X954562D01*
G02X952632Y311297I85J2325D01*
G03X951326Y312084I-1365J-788D01*
G01X951208D01*
G03X949902Y311297I59J-1575D01*
G02X947972Y310135I-2015J1163D01*
G01X947802D01*
G02X945872Y311297I85J2325D01*
G03X944566Y312084I-1365J-788D01*
G01X944448D01*
G03X943142Y311297I59J-1575D01*
G02X941212Y310135I-2015J1163D01*
G01X941083D01*
G03X939762Y309347I44J-1575D01*
G02X937817Y308184I-2015J1162D01*
G01X937677D01*
G02X935732Y309347I70J2325D01*
G03X934411Y310135I-1365J-787D01*
G01X934323D01*
G03X933002Y309347I44J-1575D01*
G02X931057Y308184I-2015J1162D01*
G01X930917D01*
G02X928972Y309347I70J2325D01*
G03X927651Y310135I-1365J-787D01*
G01X927563D01*
G03X926242Y309347I44J-1575D01*
G02X924297Y308184I-2015J1162D01*
G01X923368D01*
G02X922031Y309360I859J2325D01*
G01X895538Y313601D02*
X921242D01*
X922499Y312344D01*
Y310510D01*
G03X923518Y308934I1728J0D01*
G01X924271D01*
G03X925592Y309722I-44J1575D01*
G02X927537Y310885I2015J-1162D01*
G01X927677D01*
G02X929622Y309722I-70J-2325D01*
G03X930943Y308934I1365J787D01*
G01X931031D01*
G03X932352Y309722I-44J1575D01*
G02X934297Y310885I2015J-1162D01*
G01X934437D01*
G02X936382Y309722I-70J-2325D01*
G03X937703Y308934I1365J787D01*
G01X937791D01*
G03X939112Y309722I-44J1575D01*
G02X941057Y310885I2015J-1162D01*
G01X941186D01*
G03X942492Y311672I-59J1575D01*
G02X944422Y312834I2015J-1163D01*
G01X944592D01*
G02X946522Y311672I-85J-2325D01*
G03X947828Y310885I1365J788D01*
G01X947946D01*
G03X949252Y311672I-59J1575D01*
G02X951182Y312834I2015J-1163D01*
G01X951352D01*
G02X953282Y311672I-85J-2325D01*
G03X954588Y310885I1365J788D01*
G01X954647D01*
G03X955998Y311650I0J1575D01*
G01X956011Y311673D01*
G02X957928Y312834I2015J-1164D01*
G01X958070D01*
G03X959391Y313622I-44J1575D01*
G02X961336Y314785I2015J-1162D01*
G01X961476D01*
G02X963421Y313622I-70J-2325D01*
G03X964742Y312834I1365J787D01*
G01X964871D01*
G02X966801Y311672I-85J-2325D01*
G03X968107Y310885I1365J788D01*
G01X968225D01*
G03X969531Y311672I-59J1575D01*
G02X971461Y312834I2015J-1163D01*
G01X971590D01*
G03X972911Y313622I-44J1575D01*
G02X974856Y314785I2015J-1162D01*
G01X974985D01*
G03X976291Y315572I-59J1575D01*
G02X978221Y316734I2015J-1163D01*
G01X978350D01*
G03X979671Y317522I-44J1575D01*
G02X981616Y318685I2015J-1162D01*
G01X981745D01*
G03X983051Y319472I-59J1575D01*
G02X984981Y320634I2015J-1163D01*
G01X985110D01*
G03X986431Y321422I-44J1575D01*
G02X988376Y322585I2015J-1162D01*
G01X988505D01*
G03X989811Y323372I-59J1575D01*
G02X991775Y324535I2015J-1163D01*
G01X991870D01*
G03X993191Y325323I-44J1575D01*
G03Y326897I-1365J787D01*
G02X993166Y329180I2015J1164D01*
G01X993191Y329222D01*
X993210Y329256D01*
G03X993191Y330797I-1384J754D01*
G02X993166Y333080I2015J1164D01*
G01X993191Y333122D01*
X993210Y333156D01*
G03X993191Y334697I-1384J754D01*
G02X993166Y336980I2015J1164D01*
G01X993191Y337022D01*
G02X995136Y338185I2015J-1162D01*
G01X995265D01*
G03X996571Y338972I-59J1575D01*
G02X998501Y340134I2015J-1163D01*
G01X998586D01*
G03X999937Y340899I0J1575D01*
G01X999950Y340922D01*
G02X1001895Y342085I2015J-1162D01*
G01X1002024D01*
G03X1003330Y342872I-59J1575D01*
G02X1005260Y344034I2015J-1163D01*
G01X1005389D01*
G03X1006710Y344822I-44J1575D01*
G02X1008725Y347560I13242J-7634D01*
G01X927607Y238360D02*
X928761Y237694D01*
X928855Y237342D01*
G03X928947Y235289I2131J-933D01*
G01X928972Y235247D01*
X928991Y235213D01*
G02X928972Y233672I-1384J-754D01*
G03Y231346I2015J-1163D01*
G02Y229772I-1365J-787D01*
G01X928947Y229730D01*
G03X928972Y227447I2040J-1119D01*
G01X928991Y227413D01*
G02X928972Y225872I-1384J-754D01*
G03X928947Y223589I2015J-1164D01*
G01X928972Y223547D01*
X928991Y223513D01*
G02X928972Y221972I-1384J-754D01*
G03X928947Y219689I2015J-1164D01*
G01X928972Y219647D01*
X928991Y219613D01*
G02X927666Y217285I-1384J-753D01*
G01X927537D01*
G03X925887Y216525I71J-2325D01*
G03X925686Y216005I572J-520D01*
G01Y215951D01*
G02X925495Y215490I-652J0D01*
G01X925005Y215000D01*
G01X929407Y215372D02*
Y216900D01*
X929408Y217138D01*
X929452Y217444D01*
G03X929647Y219980I-1845J1417D01*
G01X929622Y220022D01*
X929603Y220056D01*
G02X929622Y221597I1384J754D01*
G03X929647Y223880I-2015J1164D01*
G01X929622Y223922D01*
X929603Y223956D01*
G02X929622Y225497I1384J754D01*
G03Y227823I-2015J1163D01*
G02Y229397I1365J787D01*
G01X929647Y229439D01*
G03X929622Y231722I-2040J1119D01*
G01X929603Y231756D01*
G02X929622Y233297I1384J754D01*
G03X929647Y235580I-2015J1164D01*
G01X929622Y235622D01*
X929603Y235656D01*
G02X929523Y236991I1385J753D01*
G01X929833Y237075D01*
X930987Y236409D01*
G01X909886Y239841D02*
X910995D01*
X911376Y240222D01*
Y247322D01*
X912539Y248485D01*
X914146D01*
G03X915452Y249272I-59J1575D01*
G02X917382Y250434I2015J-1163D01*
G01X917511D01*
G03X918832Y251222I-44J1575D01*
G02X920777Y252385I2015J-1162D01*
G01X920906D01*
G03X922212Y253172I-59J1575D01*
G02X924142Y254334I2015J-1163D01*
G01X924271D01*
G03X924909Y254489I-45J1575D01*
G01X925953Y254999D01*
X927306Y255535D01*
X927651D01*
G02X928746Y255049I-44J-1575D01*
G01X929873Y254307D01*
X931675Y253427D01*
G02X932246Y252957I-688J-1418D01*
G01X933239Y251600D01*
X934367Y250060D01*
G01X911081Y237484D02*
Y238816D01*
X912126Y239861D01*
Y247011D01*
X912850Y247735D01*
X914172D01*
G03X916102Y248897I-85J2325D01*
G02X917408Y249684I1365J-788D01*
G01X917537D01*
G03X919482Y250847I-70J2325D01*
G02X920803Y251635I1365J-787D01*
G01X920932D01*
G03X922862Y252797I-85J2325D01*
G02X924168Y253584I1365J-788D01*
G01X924606D01*
X925481Y253297D01*
X926631Y252723D01*
G03X927548Y252385I977J1237D01*
G01X927677D01*
G02X929622Y251222I-70J-2325D01*
G03X930943Y250434I1365J787D01*
G01X931072D01*
G02X933002Y249272I-85J-2325D01*
G03X934308Y248485I1365J788D01*
G01X934509D01*
X937747Y248109D01*
G01X922216Y220111D02*
X923093Y219234D01*
X924271D01*
G03X925464Y219834I-45J1575D01*
G03X925592Y220022I-999J818D01*
G01X925611Y220056D01*
G03X925719Y221315I-1384J753D01*
G03X925592Y221596I-1500J-509D01*
G02Y223922I2015J1163D01*
G03Y225496I-1365J787D01*
G02Y227822I2015J1163D01*
G03Y229396I-1365J787D01*
G02Y231722I2015J1163D01*
G03Y233296I-1365J787D01*
G02Y235622I2015J1163D01*
G03Y237196I-1365J787D01*
G02Y239522I2015J1163D01*
G02X927607Y242259I13269J-7658D01*
G01Y242260D01*
G01X934367Y238360D02*
Y238359D01*
X930484D01*
X928909Y239934D01*
X927563D01*
G03X926242Y237572I44J-1575D01*
G02Y235246I-2015J-1163D01*
G03Y233672I1365J-787D01*
G02Y231346I-2015J-1163D01*
G03Y229772I1365J-787D01*
G02Y227446I-2015J-1163D01*
G03Y225872I1365J-787D01*
G02Y223546I-2015J-1163D01*
G03Y221972I1365J-787D01*
G02X926267Y219689I-2015J-1164D01*
G01X926242Y219647D01*
G02X926101Y219430I-2830J1684D01*
G02X924297Y218484I-1873J1379D01*
G01X923089D01*
X922216Y217611D01*
G01X904900Y190501D02*
X906055Y191656D01*
X907291D01*
X912744Y197109D01*
X917405D01*
X921460Y201164D01*
X922214Y202471D01*
X922212Y202472D01*
G02X924176Y203635I2015J-1163D01*
G01X924271D01*
G03X925592Y204423I-44J1575D01*
G02X927522Y205585I2015J-1163D01*
G01X928259D01*
X929540Y205437D01*
X930987Y205210D01*
G01Y209109D02*
X932141Y208444D01*
X932235Y208092D01*
G03X932327Y206039I2131J-933D01*
G03X932352Y205997I619J340D01*
G02X930035Y203955I-1365J-787D01*
G01X928799Y204588D01*
X928262Y204784D01*
X927856Y204834D01*
X927536D01*
G03X926242Y204047I71J-1574D01*
G02X924278Y202884I-2015J1163D01*
G01X924168D01*
G03X922862Y202097I59J-1575D01*
G01X922059Y200705D01*
X917714Y196360D01*
X913055D01*
X907817Y191122D01*
Y188367D01*
G01X905849Y245039D02*
X907136D01*
X907956Y245859D01*
Y248972D01*
X911369Y252385D01*
X914444D01*
G03X915295Y253161I-657J1575D01*
G02X916667Y254334I2172J-1152D01*
G01X917511D01*
G03X918832Y255122I-44J1575D01*
G02X920777Y256285I2015J-1162D01*
G01X920906D01*
G03X922212Y257072I-59J1575D01*
G02X924142Y258234I2015J-1163D01*
G01X924890D01*
X927555Y257926D01*
X927607Y257860D01*
G01X908017Y243671D02*
Y244862D01*
X908706Y245551D01*
Y248661D01*
X911680Y251635D01*
X914587D01*
G03X915959Y252808I-800J2325D01*
G02X916810Y253584I1508J-799D01*
G01X917537D01*
G03X919482Y254747I-70J2325D01*
G02X920803Y255535I1365J-787D01*
G01X920932D01*
G03X922862Y256697I-85J2325D01*
G02X924168Y257484I1365J-788D01*
G01X924683D01*
G02X926513Y256726I0J-2588D01*
G03X927548Y256285I1095J1134D01*
G01X927749D01*
X930987Y255909D01*
G01X903303Y249585D02*
X904289D01*
X910989Y256285D01*
X914444D01*
G03X915295Y257061I-657J1575D01*
G02X916667Y258234I2172J-1152D01*
G01X917511D01*
G03X918832Y259022I-44J1575D01*
G02X920777Y260185I2015J-1162D01*
G01X920906D01*
G03X922212Y260972I-59J1575D01*
G02X924142Y262134I2015J-1163D01*
G01X924373D01*
X927607Y261760D01*
G01X905281Y248007D02*
Y249519D01*
X911297Y255535D01*
X914587D01*
G03X915959Y256708I-800J2325D01*
G02X916810Y257484I1508J-799D01*
G01X917537D01*
G03X919482Y258647I-70J2325D01*
G02X920803Y259435I1365J-787D01*
G01X920932D01*
G03X922862Y260597I-85J2325D01*
G02X924168Y261384I1365J-788D01*
G01X924286D01*
G02X925592Y260597I-59J-1575D01*
G03X926306Y260185I714J413D01*
G01X927677D01*
G02X929622Y259022I-70J-2325D01*
G03X930943Y258234I1365J787D01*
G01X931133D01*
X934367Y257860D01*
G01X913532Y236385D02*
X914677D01*
X914890Y236598D01*
X915452Y237572D01*
G03X915471Y239113I-1365J787D01*
G01X915452Y239147D01*
X915427Y239189D01*
G02X915452Y241472I2040J1119D01*
G03X915471Y243013I-1365J787D01*
G01X915452Y243047D01*
X915427Y243089D01*
G02X917382Y246534I2040J1120D01*
G01X917511D01*
G03X918832Y247322I-44J1575D01*
G02X920777Y248485I2015J-1162D01*
G01X920906D01*
G03X922212Y249272I-59J1575D01*
G02X924142Y250434I2015J-1163D01*
G01X924831D01*
G03X926406Y251087I-1J2228D01*
G01X926463Y251143D01*
G02X928972Y250847I1144J-1083D01*
G01X929038Y250731D01*
X930987Y248109D01*
G01X937747Y244209D02*
X935798Y246831D01*
X935732Y246947D01*
G03X934411Y247735I-1365J-787D01*
G01X934061D01*
G03X933601Y247656I1J-1383D01*
G01X932034Y246817D01*
X931456Y246534D01*
X930943D01*
G02X929622Y247322I44J1575D01*
G03X927677Y248485I-2015J-1162D01*
G01X927548D01*
G02X926536Y248904I59J1575D01*
G01X926304Y249136D01*
G03X924981Y249684I-1323J-1323D01*
G01X924168D01*
G03X922862Y248897I59J-1575D01*
G02X920932Y247735I-2015J1163D01*
G01X920803D01*
G03X919482Y246947I44J-1575D01*
G02X917537Y245784I-2015J1162D01*
G01X917408D01*
G03X916083Y243456I59J-1575D01*
G01X916102Y243422D01*
X916127Y243380D01*
G02X916102Y241097I-2040J-1119D01*
G03X916083Y239556I1365J-787D01*
G01X916102Y239522D01*
X916127Y239480D01*
G02X916102Y237197I-2040J-1119D01*
G01X916100Y237198D01*
X915489Y236139D01*
X914572Y235222D01*
Y233875D01*
G01X937747Y259809D02*
X936593Y260475D01*
X936241Y260380D01*
G02X934452Y259435I-1873J1380D01*
G01X934282D01*
G02X932352Y260597I85J2325D01*
G03X931046Y261384I-1365J-788D01*
G01X930917D01*
G02X928972Y262547I70J2325D01*
G03X927651Y263335I-1365J-787D01*
G01X927522D01*
G02X925592Y264497I85J2325D01*
G03X924286Y265284I-1365J-788D01*
G01X924168D01*
G03X922862Y264497I59J-1575D01*
G02X920932Y263335I-2015J1163D01*
G01X920803D01*
G03X919482Y262547I44J-1575D01*
G02X917537Y261384I-2015J1162D01*
G01X916810D01*
G03X915959Y260608I657J-1575D01*
G02X914587Y259435I-2172J1152D01*
G01X911605D01*
X911450Y259280D01*
X911363D01*
G01X927607Y246160D02*
X926385Y246545D01*
X926038Y246401D01*
G02X925560Y246203I-553144J1334692D01*
G01Y246202D01*
G02X925163Y245980I-1328J1909D01*
G02X924281Y245784I-936J2129D01*
G01X924158D01*
G03X922866Y245004I69J-1575D01*
G02X920891Y243834I-1975J1082D01*
G01X920778D01*
G03X919482Y241471I69J-1575D01*
G02Y239147I-2015J-1162D01*
G03X919480Y237575I1365J-788D01*
G02X919481Y235191I-2013J-1193D01*
G01X918460Y233384D01*
X913269Y228193D01*
X912653D01*
X911666Y227206D01*
Y225599D01*
X909954Y223887D01*
Y223669D01*
X909892Y223607D01*
G01X922311Y230644D02*
Y230731D01*
X922156Y230886D01*
Y232217D01*
X922652Y232713D01*
Y236834D01*
X922862Y237196D01*
G03Y239521I-2015J1162D01*
G02X924158Y241884I1365J788D01*
G01X924281D01*
G03X926242Y243047I-54J2325D01*
G02X927604Y243834I1362J-785D01*
G01X927610D01*
G02X928972Y243047I0J-1572D01*
G03X930933Y241884I2015J1162D01*
G01X931056D01*
G02X932352Y241097I-69J-1575D01*
G03X934295Y239935I2015J1163D01*
G01X934439D01*
G03X936241Y240880I-71J2326D01*
G01X936593Y240975D01*
X937747Y240309D01*
G01X934367Y261760D02*
X935521Y261094D01*
X935604Y260784D01*
G02X934426Y260185I-1238J976D01*
G01X934308D01*
G02X933002Y260972I59J1575D01*
G03X931072Y262134I-2015J-1163D01*
G01X930943D01*
G02X929622Y262922I44J1575D01*
G03X927661Y264085I-2015J-1162D01*
G01X927548D01*
G02X926242Y264872I59J1575D01*
G03X924312Y266034I-2015J-1163D01*
G01X924142D01*
G03X922212Y264872I85J-2325D01*
G02X920906Y264085I-1365J788D01*
G01X920777D01*
G03X918832Y262922I70J-2325D01*
G02X917511Y262134I-1365J787D01*
G01X916667D01*
G03X915295Y260961I800J-2325D01*
G02X914444Y260185I-1508J799D01*
G01X911605D01*
X911450Y260340D01*
X911363D01*
G01X909142Y224357D02*
X909204Y224419D01*
X909424D01*
X910916Y225911D01*
Y227517D01*
X912342Y228943D01*
X912958D01*
X917857Y233842D01*
X918832Y235567D01*
G03Y237196I-1365J815D01*
G02Y239522I2015J1163D01*
G03Y241096I-1365J787D01*
G02X920762Y244584I2015J1163D01*
G01X920891D01*
G03X922212Y245372I0J1501D01*
G02X924142Y246534I2015J-1163D01*
G01X924271D01*
G03X924861Y246667I-45J1575D01*
G03X925190Y246862I-633J1443D01*
G03X927002Y247614I-552605J1334103D01*
G02X928972Y246946I605J-1455D01*
G03X930987Y244209I13218J7621D01*
G01X934367Y242260D02*
X935521Y241594D01*
X935604Y241284D01*
G02X934426Y240685I-1238J976D01*
G01X934308D01*
G02X933002Y241472I59J1575D01*
G03X931072Y242634I-2015J-1163D01*
G01X930943D01*
G02X929622Y243422I44J1575D01*
G03X927609Y244584I-2011J-1160D01*
G01X927603D01*
G03X925592Y243422I0J-2322D01*
G02X924271Y242634I-1365J787D01*
G01X924142D01*
G03X922212Y239146I85J-2325D01*
G02Y237572I-1365J-787D01*
G01X921902Y237036D01*
Y233024D01*
X921406Y232528D01*
Y230886D01*
X921251Y230731D01*
Y230644D01*
G01X937747Y349509D02*
X936382Y346397D01*
G02X934452Y345235I-2015J1163D01*
G01X934323D01*
G03X933002Y344447I44J-1575D01*
G02X931057Y343284I-2015J1162D01*
G01X930928D01*
G03X929622Y342497I59J-1575D01*
G02X927692Y341335I-2015J1163D01*
G01X927522D01*
G02X925592Y342497I85J2325D01*
G03X924286Y343284I-1365J-788D01*
G01X924157D01*
G02X922212Y344447I70J2325D01*
G03X920891Y345235I-1365J-787D01*
G01X920762D01*
G02X918832Y346397I85J2325D01*
G03X917526Y347184I-1365J-788D01*
G01X917397D01*
G02X915452Y348347I70J2325D01*
G03X914131Y349135I-1365J-787D01*
G01X912501D01*
X910856Y350780D01*
Y352141D01*
X906256Y356741D01*
X904895D01*
G01X906556Y358616D02*
Y357499D01*
X911604Y352451D01*
Y351090D01*
X912809Y349885D01*
X914157D01*
G02X916102Y348722I-70J-2325D01*
G03X917423Y347934I1365J787D01*
G01X917552D01*
G02X919482Y346772I-85J-2325D01*
G03X920788Y345985I1365J788D01*
G01X920917D01*
G02X922862Y344822I-70J-2325D01*
G03X924183Y344034I1365J787D01*
G01X924312D01*
G02X926242Y342872I-85J-2325D01*
G03X927548Y342085I1365J788D01*
G01X927666D01*
G03X928972Y342872I-59J1575D01*
G02X930902Y344034I2015J-1163D01*
G01X931031D01*
G03X932352Y344822I-44J1575D01*
G02X932836Y345411I2015J-1162D01*
G01X934367Y347560D01*
G01X930987Y341709D02*
X929688Y338710D01*
X929622Y338597D01*
G02X927692Y337435I-2015J1163D01*
G01X927522D01*
G02X925592Y338597I85J2325D01*
G03X924286Y339384I-1365J-788D01*
G01X924157D01*
G02X922212Y340547I70J2325D01*
G03X920891Y341335I-1365J-787D01*
G01X920762D01*
G02X918832Y342497I85J2325D01*
G03X917526Y343284I-1365J-788D01*
G01X917397D01*
G02X915452Y344447I70J2325D01*
G03X914131Y345235I-1365J-787D01*
G01X912262D01*
X910456Y347041D01*
X904000D01*
X902941Y348100D01*
X901966D01*
G01X927607Y339760D02*
X924373Y340134D01*
X924183D01*
G02X922862Y340922I44J1575D01*
G03X920917Y342085I-2015J-1162D01*
G01X920788D01*
G02X919482Y342872I59J1575D01*
G03X917552Y344034I-2015J-1163D01*
G01X917423D01*
G02X916102Y344822I44J1575D01*
G03X914141Y345985I-2015J-1162D01*
G01X912570D01*
X910766Y347789D01*
X904412D01*
X903400Y348801D01*
Y349333D01*
X902716Y350017D01*
G01X934367Y339760D02*
X932418Y337138D01*
X932352Y337022D01*
G02X931031Y336234I-1365J787D01*
G01X930902D01*
G03X928972Y335072I85J-2325D01*
G02X927666Y334285I-1365J788D01*
G01X926306D01*
G02X925592Y334697I0J825D01*
G03X924286Y335484I-1365J-788D01*
G01X924157D01*
G02X922212Y336647I70J2325D01*
G03X920891Y337435I-1365J-787D01*
G01X920762D01*
G02X918832Y338597I85J2325D01*
G03X917526Y339384I-1365J-788D01*
G01X917397D01*
G02X915452Y340547I70J2325D01*
G03X914131Y341335I-1365J-787D01*
G01X912762D01*
X912356Y341741D01*
X905856D01*
X905056Y340941D01*
G01X927607Y335860D02*
X924373Y336234D01*
X924183D01*
G02X922862Y337022I44J1575D01*
G03X920917Y338185I-2015J-1162D01*
G01X920788D01*
G02X919482Y338972I59J1575D01*
G03X917552Y340134I-2015J-1163D01*
G01X917423D01*
G02X916102Y340922I44J1575D01*
G03X914157Y342085I-2015J-1162D01*
G01X913073D01*
X912669Y342489D01*
X906008D01*
X905056Y343441D01*
G01X937747Y353409D02*
X935798Y350788D01*
X935732Y350672D01*
G02X934426Y349885I-1365J788D01*
G01X934297D01*
G03X932352Y348722I70J-2325D01*
G01X931704Y347598D01*
G02X930987Y347184I-717J414D01*
G01X930928D01*
G03X929622Y346397I59J-1575D01*
G02X927692Y345235I-2015J1163D01*
G01X927522D01*
G02X925592Y346397I85J2325D01*
G03X924286Y347184I-1365J-788D01*
G01X924157D01*
G02X922212Y348347I70J2325D01*
G03X920891Y349135I-1365J-787D01*
G01X920762D01*
G02X918832Y350297I85J2325D01*
G03X917526Y351084I-1365J-788D01*
G01X916669D01*
G02X915295Y354561I798J2325D01*
G01X915694Y355307D01*
Y357003D01*
X914456Y358241D01*
X911956D01*
X909556Y360641D01*
X908067D01*
G01X930987Y349509D02*
X929038Y346888D01*
X928972Y346772D01*
G02X927666Y345985I-1365J788D01*
G01X927548D01*
G02X926242Y346772I59J1575D01*
G03X924312Y347934I-2015J-1163D01*
G01X924183D01*
G02X922862Y348722I44J1575D01*
G03X920917Y349885I-2015J-1162D01*
G01X920788D01*
G02X919482Y350672I59J1575D01*
G03X917552Y351834I-2015J-1163D01*
G01X916812D01*
G02X915959Y354208I655J1575D01*
G01X916442Y355119D01*
Y357313D01*
X914766Y358989D01*
X912266D01*
X909800Y361455D01*
Y362444D01*
G01X904992Y336929D02*
X905079D01*
X905234Y337084D01*
X910399D01*
X910750Y337435D01*
X914144D01*
G02X915452Y336647I-57J-1575D01*
G03X917397Y335484I2015J1162D01*
G01X917526D01*
G02X918832Y334697I-59J-1575D01*
G03X920762Y333535I2015J1163D01*
G01X920891D01*
G02X922212Y332747I-44J-1575D01*
G03X924157Y331584I2015J1162D01*
G01X925425D01*
X927607Y331960D01*
G01X934367Y355360D02*
X935521Y356025D01*
X935831Y355941D01*
G02X934426Y353785I-1465J-581D01*
G01X934297D01*
G03X932352Y352622I70J-2325D01*
G02X931031Y351834I-1365J787D01*
G01X930902D01*
G03X928972Y350672I85J-2325D01*
G02X927666Y349885I-1365J788D01*
G01X927548D01*
G02X926242Y350672I59J1575D01*
G03X924312Y351834I-2015J-1163D01*
G01X924183D01*
G02X922862Y352622I44J1575D01*
G03X920917Y353785I-2015J-1162D01*
G01X920778D01*
G02X919482Y354572I69J1575D01*
G01X919176Y355105D01*
Y355961D01*
X919792Y356577D01*
Y362205D01*
X918156Y363841D01*
X913376D01*
X912074Y365144D01*
Y365364D01*
X912012Y365426D01*
G01X909605Y371718D02*
X909667Y371656D01*
X909889D01*
X915754Y365791D01*
X919545D01*
X921902Y363434D01*
Y356685D01*
X922212Y356147D01*
G03X924157Y354984I2015J1162D01*
G01X924286D01*
G02X925592Y354197I-59J-1575D01*
G03X927522Y353035I2015J1163D01*
G01X927651D01*
G02X928844Y352435I-45J-1575D01*
G01X928761Y352125D01*
X927607Y351460D01*
G01X930987Y333909D02*
X928711Y333548D01*
X927188Y333529D01*
X925046Y332334D01*
X924183D01*
G02X922862Y333122I44J1575D01*
G03X920917Y334285I-2015J-1162D01*
G01X920788D01*
G02X919482Y335072I59J1575D01*
G03X917552Y336234I-2015J-1163D01*
G01X917410D01*
G02X916102Y337022I57J1575D01*
G03X914171Y338185I-2015J-1162D01*
G01X910439D01*
X910088Y337834D01*
X905234D01*
X905079Y337989D01*
X904992D01*
G01X911261Y364674D02*
X911323Y364612D01*
X911545D01*
X913065Y363091D01*
X917845D01*
X919042Y361894D01*
Y356888D01*
X918426Y356272D01*
Y354905D01*
X918831Y354199D01*
X918832Y354197D01*
G03X920762Y353035I2015J1163D01*
G01X920891D01*
G02X922212Y352247I-44J-1575D01*
G03X924157Y351084I2015J1162D01*
G01X924286D01*
G02X925592Y350297I-59J-1575D01*
G03X927522Y349135I2015J1163D01*
G01X927692D01*
G03X929622Y350297I-85J2325D01*
G02X930928Y351084I1365J-788D01*
G01X931057D01*
G03X933002Y352247I-70J2325D01*
G02X934323Y353035I1365J-787D01*
G01X934452D01*
G03X936499Y356293I-85J2325D01*
G01X936593Y356644D01*
X937747Y357309D01*
G01X910355Y372469D02*
X910417Y372407D01*
Y372189D01*
X916065Y366541D01*
X919856D01*
X922652Y363745D01*
Y356886D01*
X922862Y356522D01*
G03X924183Y355734I1365J787D01*
G01X924312D01*
G02X926242Y354572I-85J-2325D01*
G03X927548Y353785I1365J788D01*
G01X927677D01*
G02X929481Y352839I-69J-2325D01*
G01X929833Y352744D01*
X930987Y353409D01*
G01X928972Y361550D02*
G02Y362372I712J411D01*
G03X928991Y363913I-1365J787D01*
G01X928972Y363947D01*
X928947Y363989D01*
G02X928972Y366272I2040J1119D01*
G03X928991Y367813I-1365J787D01*
G01X928972Y367847D01*
G02X928947Y370130I2015J1164D01*
G01X928972Y370172D01*
G03X927651Y372534I-1365J787D01*
G01X927556D01*
G02X925592Y373697I51J2326D01*
G03X924286Y374484I-1365J-788D01*
G01X920013D01*
X913624Y380873D01*
X912787D01*
G01X930987Y361209D02*
X929690Y364205D01*
X929603Y364356D01*
G02X929622Y365897I1384J754D01*
G03Y368223I-2015J1163D01*
G02Y369797I1365J787D01*
G01X929647Y369839D01*
G03X927658Y373285I-2040J1120D01*
G01X927548D01*
G02X926242Y374072I59J1575D01*
G03X924312Y375234I-2015J-1163D01*
G01X920321D01*
X914566Y380989D01*
Y382652D01*
G01X927607Y355360D02*
X926308Y358359D01*
X926242Y358472D01*
G02X926158Y359880I1365J788D01*
G03X926093Y361129I-1305J558D01*
G01X925592Y361997D01*
G02X925567Y364280I2015J1164D01*
G01X925592Y364322D01*
X925611Y364356D01*
G03X924286Y366684I-1384J753D01*
G01X923214D01*
X917757Y372141D01*
X915756D01*
X908256Y379641D01*
X906947D01*
G01X927607Y359260D02*
G03X926743Y361504I-7568J-1626D01*
G01X926242Y362372D01*
G02X926223Y363913I1365J787D01*
G01X926242Y363947D01*
X926267Y363989D01*
G03X924278Y367435I-2040J1120D01*
G01X923525D01*
X922441Y368519D01*
X922437D01*
X918067Y372889D01*
X916066D01*
X908656Y380299D01*
Y381468D01*
G01X930987Y388509D02*
X929037Y391134D01*
X928972Y391247D01*
G03X927678Y392034I-1365J-787D01*
G01X927537D01*
G02X925592Y393197I70J2325D01*
G03X924298Y393984I-1365J-787D01*
G01X924142D01*
G02X922212Y395146I85J2325D01*
G03X920891Y395934I-1365J-787D01*
G01X915863D01*
X913153Y398644D01*
X911958D01*
G01X910394Y187856D02*
X911731D01*
X917627Y193752D01*
X919220D01*
X919221Y193751D01*
X919222D01*
X925041Y199570D01*
X925592Y200523D01*
G02X927537Y201686I2015J-1162D01*
G01X928156D01*
G03X930037Y202566I-1123J4850D01*
G02X930928Y202884I951J-1257D01*
G01X931123D01*
X934367Y203260D01*
G01Y211060D02*
X933068Y208060D01*
X933002Y207946D01*
G03Y206372I1365J-787D01*
G03X933408Y205909I1365J787D01*
G01X935319Y204533D01*
X935561Y204344D01*
X935732Y204047D01*
X935751Y204013D01*
G02X935732Y202472I-1384J-754D01*
G02X934448Y201686I-1365J788D01*
G01X934297D01*
G03X932352Y200523I70J-2325D01*
G02X931046Y199735I-1365J786D01*
G01X930928D01*
G02X930047Y200045I59J1574D01*
G01X927956Y200935D01*
X927548D01*
G03X926242Y200147I59J-1574D01*
G01X925640Y199110D01*
X919532Y193003D01*
X917938D01*
X912152Y187217D01*
Y186099D01*
G01X933025Y184392D02*
X934767D01*
X946116Y195741D01*
Y197737D01*
X945872Y198197D01*
G02X945847Y200480I2015J1164D01*
G01X945872Y200522D01*
X945891Y200556D01*
G03X945872Y202097I-1384J754D01*
G02Y204423I2015J1163D01*
G03X944735Y206769I-1365J787D01*
G01X944507Y206541D01*
Y205210D01*
G01X934727Y182551D02*
Y183292D01*
X946866Y195431D01*
Y198050D01*
X946573Y198492D01*
G02X946503Y200113I1311J869D01*
G01X946522Y200147D01*
X946547Y200189D01*
G03X946522Y202472I-2040J1119D01*
G02X946503Y204013I1365J787D01*
G01X946522Y204047D01*
G03X944763Y207522I-2015J1163D01*
G01X944507Y207778D01*
Y209109D01*
G01X941127Y203260D02*
X942458D01*
X942686Y203032D01*
G02X942598Y202694I-1560J226D01*
G02X942492Y202472I-1445J554D01*
G03X942467Y200189I2015J-1164D01*
G01X942492Y200147D01*
X942511Y200113D01*
G02X942492Y198572I-1384J-754D01*
G01X942106Y197904D01*
Y196020D01*
X935727Y189641D01*
X932816D01*
X931133Y187958D01*
X929519D01*
G01X931242Y186145D02*
Y187006D01*
X933127Y188891D01*
X936038D01*
X942856Y195709D01*
Y197704D01*
X943142Y198197D01*
G03X943167Y200480I-2015J1164D01*
G01X943142Y200522D01*
X943123Y200556D01*
G02X943142Y202097I1384J754D01*
G03Y204423I-2015J1163D01*
G01Y204424D01*
G02X942679Y206891I3278J1892D01*
G03X942492Y207948I-1552J270D01*
G01X941127Y211060D01*
G01X918572Y187316D02*
X918634Y187378D01*
Y187598D01*
X926487Y195451D01*
X933929D01*
X935978Y197500D01*
X936382Y198197D01*
G03X936694Y199341I-2014J1164D01*
G01X937747Y201309D01*
G01X923127Y185209D02*
X923189Y185271D01*
Y185491D01*
X929958Y192260D01*
X935139D01*
X939387Y196508D01*
Y199497D01*
X939787Y200189D01*
G03X939762Y202472I-2040J1119D01*
G02X939743Y204013I1365J787D01*
G01X939762Y204047D01*
G03X939787Y206330I-2015J1164D01*
G01X939762Y206372D01*
G02Y207946I1365J787D01*
G03X938003Y211422I-2015J1163D01*
G01X937747Y211678D01*
Y213009D01*
G01X917821Y188065D02*
X917883Y188127D01*
X918102D01*
X926176Y196201D01*
X933618D01*
X935378Y197961D01*
X935732Y198573D01*
G03X935942Y199347I-1367J786D01*
G03X935831Y199941I-1577J13D01*
G02X935856Y200841I1837J399D01*
G02X936382Y202097I5183J-1432D01*
G01X937056Y203141D01*
X937747Y205210D01*
G01Y209109D02*
Y210440D01*
X937975Y210668D01*
G02X939131Y208356I-228J-1559D01*
G01X939112Y208322D01*
G03X939087Y206039I2015J-1164D01*
G01X939112Y205997D01*
G02Y204423I-1365J-787D01*
G03Y202097I2015J-1163D01*
G02X939131Y200556I-1365J-787D01*
G01X938637Y199699D01*
Y196819D01*
X934828Y193010D01*
X929647D01*
X922658Y186021D01*
X922439D01*
X922377Y185959D01*
G01X934367Y386560D02*
X932418Y389181D01*
X932352Y389297D01*
G02Y391623I2015J1163D01*
G03X931058Y393984I-1365J787D01*
G01X930902D01*
G02X928972Y395146I85J2325D01*
G03X927651Y395934I-1365J-787D01*
G01X927556D01*
G02X925592Y397097I51J2326D01*
G03X924286Y397884I-1365J-788D01*
G01X924157D01*
G02X922212Y399047I70J2325D01*
G01X922037Y399350D01*
X918152Y403235D01*
X916533D01*
G01X934367Y394359D02*
X931129Y394735D01*
X930916D01*
G02X929622Y395522I71J1574D01*
G03X927658Y396685I-2015J-1163D01*
G01X927548D01*
G02X926242Y397472I59J1575D01*
G03X924312Y398634I-2015J-1163D01*
G01X924185D01*
X924183Y398632D01*
X924170D01*
G02X922860Y399421I57J1577D01*
G01X922636Y399809D01*
X918356Y404089D01*
Y404948D01*
G01X930987Y392410D02*
X927751Y392785D01*
X927536D01*
G02X926242Y393572I71J1574D01*
G03X924297Y394735I-2015J-1162D01*
G01X924156D01*
G02X922862Y395522I71J1574D01*
G03X920898Y396685I-2015J-1163D01*
G01X916175D01*
X913826Y399034D01*
Y400312D01*
G01X941127Y386560D02*
X939828Y389559D01*
X939762Y389672D01*
G02X939743Y391213I1365J787D01*
G01X939762Y391247D01*
G03X939787Y393530I-2015J1164D01*
G01X939762Y393572D01*
G02X940551Y395826I1365J787D01*
G03X942492Y397472I-1439J3664D01*
G03X942511Y399013I-1365J787D01*
G01X942309Y399374D01*
X939140Y402543D01*
X936154D01*
X931813Y406884D01*
Y407954D01*
X931566Y408201D01*
X930606D01*
G01X941127Y394359D02*
G02X942386Y396021I11539J-7434D01*
G03X943076Y396982I-4364J3861D01*
G01X943142Y397097D01*
G03X943167Y399380I-2015J1164D01*
G01X943100Y399493D01*
X942911Y399831D01*
X939451Y403291D01*
X936464D01*
X932561Y407194D01*
Y409796D01*
G01X937747Y388509D02*
Y387178D01*
X937519Y386950D01*
G02X936382Y389297I228J1559D01*
G03Y391623I-2015J1163D01*
G02Y393197I1365J787D01*
G01X936407Y393239D01*
G03X934418Y396685I-2040J1120D01*
G01X934308D01*
G02X933002Y397472I59J1575D01*
G03X931072Y398634I-2015J-1163D01*
G01X930943D01*
G02X929623Y399420I44J1575D01*
G01X929246Y400072D01*
X925708Y403610D01*
X924725D01*
X919331Y409004D01*
X919332Y409222D01*
X919271Y409283D01*
G01X923101Y409313D02*
X923163Y409251D01*
X923383D01*
X928193Y404441D01*
X929237D01*
X931943Y401734D01*
X931939Y401738D01*
X932340Y401016D01*
X932343Y401011D01*
X932348Y401003D01*
X932352Y400996D01*
G03X934269Y399834I2015J1162D01*
G01X934438D01*
G02X935732Y399047I-71J-1574D01*
G03X937218Y397944I2015J1162D01*
G02X937747Y396309I-2262J-1635D01*
G01X918521Y408533D02*
X918583Y408471D01*
X918803D01*
X924414Y402860D01*
X925397D01*
X928646Y399611D01*
X928973Y399044D01*
G03X930933Y397884I2013J1165D01*
G01X931046D01*
G02X932352Y397097I-59J-1575D01*
G03X934316Y395934I2015J1163D01*
G01X934411D01*
G02X935732Y393572I-44J-1575D01*
G01X935707Y393530D01*
G03X935732Y391247I2040J-1119D01*
G01X935751Y391213D01*
G02X935732Y389672I-1384J-754D01*
G03X937490Y386197I2015J-1163D01*
G01X937747Y385940D01*
Y384609D01*
G01X923851Y410063D02*
X923912Y410002D01*
X923911Y409784D01*
X928504Y405191D01*
X929548D01*
X932547Y402192D01*
X932969Y401441D01*
X932992Y401401D01*
X932994Y401396D01*
X932997Y401391D01*
X933001Y401384D01*
X933003Y401381D01*
X933011Y401365D01*
G03X934287Y400584I1356J783D01*
G01X934465D01*
G02X936382Y399422I-98J-2324D01*
G03X937389Y398675I1365J787D01*
G02X938168Y398242I-369J-1581D01*
G01X938939Y397471D01*
G01X944507Y388509D02*
X942557Y391134D01*
X942492Y391247D01*
G02X944437Y394735I2015J1163D01*
G01X944578D01*
G03X945872Y397097I-71J1574D01*
G02X945847Y399380I2015J1164D01*
G01X945913Y399492D01*
X946404Y400370D01*
Y403393D01*
X944415Y405382D01*
X943315D01*
G01X944507Y392410D02*
X946457Y395032D01*
X946522Y395146D01*
G03Y397472I-2015J1163D01*
G02X946503Y399013I1365J787D01*
G01X947152Y400175D01*
Y403703D01*
X944781Y406074D01*
Y407266D01*
G01X994645Y198346D02*
Y200293D01*
X992856Y202082D01*
Y203841D01*
X993191Y204423D01*
G03Y205997I-1365J787D01*
G01X993166Y206039D01*
G02X993191Y208322I2040J1119D01*
G01X993210Y208356D01*
G03X993191Y209897I-1384J754D01*
G02X993166Y212180I2015J1164D01*
G01X993191Y212222D01*
X993210Y212256D01*
G03X993191Y213797I-1384J754D01*
G02X993166Y216080I2015J1164D01*
G01X993191Y216122D01*
X993510Y216682D01*
G02X995059Y218713I8321J-4740D01*
G01X995206Y218860D01*
G01X964786Y263709D02*
X964779Y263694D01*
G02X963421Y260596I-14719J4605D01*
G03X963402Y259056I1365J-787D01*
G01X963421Y259022D01*
X963446Y258980D01*
G02X963421Y256697I-2040J-1119D01*
G03X963402Y255156I1365J-787D01*
G01X963421Y255122D01*
X963446Y255080D01*
G02X963421Y252797I-2040J-1119D01*
G03X963402Y251256I1365J-787D01*
G01X963421Y251222D01*
X963446Y251180D01*
G02X963421Y248897I-2040J-1119D01*
G03X963402Y247356I1365J-787D01*
G01X963421Y247322D01*
X963446Y247280D01*
G02X963421Y244997I-2040J-1119D01*
G03X963402Y243456I1365J-787D01*
G01X963421Y243422D01*
X963446Y243380D01*
G02X963421Y241097I-2040J-1119D01*
G03X963402Y239556I1365J-787D01*
G01X963421Y239522D01*
X963446Y239480D01*
G02X963421Y237197I-2040J-1119D01*
G03X963402Y235656I1365J-787D01*
G01X963421Y235622D01*
X963446Y235580D01*
G02X963421Y233297I-2040J-1119D01*
G03X963402Y231756I1365J-787D01*
G01X963421Y231722D01*
G02X963446Y229439I-2015J-1164D01*
G01X963421Y229397D01*
G03Y227823I1365J-787D01*
G02Y225497I-2015J-1163D01*
G03X963402Y223956I1365J-787D01*
G01X963421Y223922D01*
X963446Y223880D01*
G02X963421Y221597I-2040J-1119D01*
G03X963402Y220056I1365J-787D01*
G01X963421Y220022D01*
X963446Y219980D01*
G02X963421Y217697I-2040J-1119D01*
G03X963402Y216156I1365J-787D01*
G01X963421Y216122D01*
X963446Y216080D01*
G02X963421Y213797I-2040J-1119D01*
G03X963402Y212256I1365J-787D01*
G01X963421Y212222D01*
X963446Y212180D01*
G02X963421Y209897I-2040J-1119D01*
G01X963206Y209524D01*
Y208122D01*
X963914Y207414D01*
X964386D01*
X964851Y206949D01*
Y204215D01*
X964426Y203790D01*
Y194492D01*
X964581Y194337D01*
Y194250D01*
G01X964786Y275409D02*
Y274078D01*
X965042Y273822D01*
G02X966826Y270389I-256J-2313D01*
G01X966801Y270347D01*
X966782Y270313D01*
G03X966801Y268772I1384J-754D01*
G02X966826Y266489I-2015J-1164D01*
G01X966801Y266447D01*
X966782Y266413D01*
G03X966801Y264872I1384J-754D01*
G02Y262546I-2015J-1163D01*
G03Y260972I1365J-787D01*
G02X966826Y258689I-2018J-1164D01*
G01X966801Y258647D01*
X966782Y258613D01*
G03X966801Y257072I1384J-754D01*
G02X966826Y254789I-2015J-1164D01*
G01X966801Y254747D01*
X966782Y254713D01*
G03X966801Y253172I1384J-754D01*
G02X966826Y250889I-2015J-1164D01*
G01X966801Y250847D01*
X966782Y250813D01*
G03X966801Y249272I1384J-754D01*
G02X966826Y246989I-2015J-1164D01*
G01X966801Y246947D01*
X966782Y246913D01*
G03X966801Y245372I1384J-754D01*
G02X966826Y243089I-2015J-1164D01*
G01X966801Y243047D01*
X966782Y243013D01*
G03X966801Y241472I1384J-754D01*
G02X966826Y239189I-2015J-1164D01*
G01X966801Y239147D01*
X966782Y239113D01*
G03X966801Y237572I1384J-754D01*
G02X966826Y235289I-2015J-1164D01*
G01X966801Y235247D01*
X966782Y235213D01*
G03X966801Y233672I1384J-754D01*
G02Y231346I-2015J-1163D01*
G03Y229772I1365J-787D01*
G01X966826Y229730D01*
G02X966801Y227447I-2040J-1119D01*
G01X966782Y227413D01*
G03X966801Y225872I1384J-754D01*
G02X966826Y223589I-2015J-1164D01*
G01X966801Y223547D01*
X966782Y223513D01*
G03X966801Y221972I1384J-754D01*
G02X966826Y219689I-2015J-1164D01*
G01X966801Y219647D01*
G03Y218073I1365J-787D01*
G01X967236Y217319D01*
Y207954D01*
X968816Y206374D01*
Y199709D01*
X969894Y198631D01*
Y196855D01*
X970049Y196700D01*
Y196613D01*
G01X964786Y267609D02*
X964779Y267594D01*
G02X963421Y264496I-14719J4605D01*
G03X963260Y263317I1365J-787D01*
G02X962771Y260972I-3808J-429D01*
G03X962746Y258689I2016J-1164D01*
G01X962771Y258647D01*
X962790Y258613D01*
G02X962771Y257072I-1384J-754D01*
G03X962746Y254789I2015J-1164D01*
G01X962771Y254747D01*
X962790Y254713D01*
G02X962771Y253172I-1384J-754D01*
G03X962746Y250889I2015J-1164D01*
G01X962771Y250847D01*
X962790Y250813D01*
G02X962771Y249272I-1384J-754D01*
G03X962746Y246989I2015J-1164D01*
G01X962771Y246947D01*
X962790Y246913D01*
G02X962771Y245372I-1384J-754D01*
G03X962746Y243089I2015J-1164D01*
G01X962771Y243047D01*
X962790Y243013D01*
G02X962771Y241472I-1384J-754D01*
G03X962746Y239189I2015J-1164D01*
G01X962771Y239147D01*
X962790Y239113D01*
G02X962771Y237572I-1384J-754D01*
G03X962746Y235289I2015J-1164D01*
G01X962771Y235247D01*
X962790Y235213D01*
G02X962771Y233672I-1384J-754D01*
G03Y231346I2015J-1163D01*
G02Y229772I-1365J-787D01*
G01X962746Y229730D01*
G03X962771Y227447I2040J-1119D01*
G01X962790Y227413D01*
G02X962771Y225872I-1384J-754D01*
G03X962746Y223589I2015J-1164D01*
G01X962771Y223547D01*
X962790Y223513D01*
G02X962771Y221972I-1384J-754D01*
G03X962746Y219689I2015J-1164D01*
G01X962771Y219647D01*
X962790Y219613D01*
G02X962771Y218072I-1384J-754D01*
G03X962746Y215789I2015J-1164D01*
G01X962771Y215747D01*
X962790Y215713D01*
G02X962771Y214172I-1384J-754D01*
G03X962746Y211889I2015J-1164D01*
G01X962771Y211847D01*
X962790Y211813D01*
G02X962771Y210272I-1384J-754D01*
G01X962456Y209726D01*
Y207811D01*
X964101Y206166D01*
Y204526D01*
X963676Y204101D01*
Y194492D01*
X963521Y194337D01*
Y194250D01*
G01X968989Y196613D02*
Y196700D01*
X969144Y196855D01*
Y198320D01*
X968066Y199398D01*
Y206063D01*
X966486Y207643D01*
Y217118D01*
X966151Y217698D01*
G02Y220022I2015J1162D01*
G01X966170Y220056D01*
G03X966151Y221597I-1384J754D01*
G02X966126Y223880I2015J1164D01*
G01X966151Y223922D01*
X966170Y223956D01*
G03X966151Y225497I-1384J754D01*
G02Y227823I2015J1163D01*
G03Y229397I-1365J787D01*
G01X966126Y229439D01*
G02X966151Y231722I2040J1119D01*
G01X966170Y231756D01*
G03X966151Y233297I-1384J754D01*
G02X966126Y235580I2015J1164D01*
G01X966151Y235622D01*
X966170Y235656D01*
G03X966151Y237197I-1384J754D01*
G02X966126Y239480I2015J1164D01*
G01X966151Y239522D01*
X966170Y239556D01*
G03X966151Y241097I-1384J754D01*
G02X966126Y243380I2015J1164D01*
G01X966151Y243422D01*
X966170Y243456D01*
G03X966151Y244997I-1384J754D01*
G02X966126Y247280I2015J1164D01*
G01X966151Y247322D01*
X966170Y247356D01*
G03X966151Y248897I-1384J754D01*
G02X966126Y251180I2015J1164D01*
G01X966151Y251222D01*
X966170Y251256D01*
G03X966151Y252797I-1384J754D01*
G02X966126Y255080I2015J1164D01*
G01X966151Y255122D01*
X966170Y255156D01*
G03X966151Y256697I-1384J754D01*
G02X966126Y258980I2015J1164D01*
G01X966151Y259022D01*
X966170Y259056D01*
G03X966151Y260596I-1382J753D01*
G02Y262922I2015J1163D01*
G03Y264496I-1365J787D01*
G02X966126Y266780I2016J1164D01*
G01X966151Y266822D01*
X966170Y266856D01*
G03X966151Y268397I-1384J754D01*
G02X966126Y270680I2015J1164D01*
G01X966151Y270722D01*
X966170Y270756D01*
G03X965014Y273068I-1384J753D01*
G01X964786Y272840D01*
Y271509D01*
G01X961406Y265660D02*
G03X960498Y264585I10671J-9934D01*
G03X959407Y262950I12078J-9241D01*
G01X959391Y262922D01*
G03Y260596I2015J-1163D01*
G02X959410Y259056I-1363J-787D01*
G01X959391Y259022D01*
X959366Y258980D01*
G03X959391Y256697I2040J-1119D01*
G02X959410Y255156I-1365J-787D01*
G01X959391Y255122D01*
X959366Y255080D01*
G03X959391Y252797I2040J-1119D01*
G02X959410Y251256I-1365J-787D01*
G01X959391Y251222D01*
X959366Y251180D01*
G03X959391Y248897I2040J-1119D01*
G02X959410Y247356I-1365J-787D01*
G01X959391Y247322D01*
X959366Y247280D01*
G03X959391Y244997I2040J-1119D01*
G02X959410Y243456I-1365J-787D01*
G01X959391Y243422D01*
X959366Y243380D01*
G03X959391Y241097I2040J-1119D01*
G02X959410Y239556I-1365J-787D01*
G01X959391Y239522D01*
X959366Y239480D01*
G03X959391Y237197I2040J-1119D01*
G02X959410Y235656I-1365J-787D01*
G01X959391Y235622D01*
X959366Y235580D01*
G03X959391Y233297I2040J-1119D01*
G02X959410Y231756I-1365J-787D01*
G01X959391Y231722D01*
G03X959366Y229439I2015J-1164D01*
G01X959391Y229397D01*
G02Y227823I-1365J-787D01*
G03Y225497I2015J-1163D01*
G02X959410Y223956I-1365J-787D01*
G01X959391Y223922D01*
X959366Y223880D01*
G03X959391Y221597I2040J-1119D01*
G02X959410Y220056I-1365J-787D01*
G01X959391Y220022D01*
X959366Y219980D01*
G03X959391Y217697I2040J-1119D01*
G02X959410Y216156I-1365J-787D01*
G01X959391Y216122D01*
X959366Y216080D01*
G03X959391Y213797I2040J-1119D01*
G02X959410Y212256I-1365J-787D01*
G01X959391Y212222D01*
X959366Y212180D01*
G03X959391Y209897I2040J-1119D01*
G01X959438Y209815D01*
Y202279D01*
X959609Y202108D01*
Y199994D01*
X958926Y199311D01*
Y198211D01*
X958056Y197341D01*
G01X961406Y273460D02*
X960041Y270346D01*
G03X960802Y268104I1365J-787D01*
G02X962656Y266618I-1636J-3940D01*
G02X961980Y264192I-1250J-959D01*
G03X960041Y262546I1328J-3530D01*
G03Y260972I1365J-787D01*
G02X960066Y258689I-2018J-1164D01*
G01X960041Y258647D01*
X960022Y258613D01*
G03X960041Y257072I1384J-754D01*
G02X960066Y254789I-2015J-1164D01*
G01X960041Y254747D01*
X960022Y254713D01*
G03X960041Y253172I1384J-754D01*
G02X960066Y250889I-2015J-1164D01*
G01X960041Y250847D01*
X960022Y250813D01*
G03X960041Y249272I1384J-754D01*
G02X960066Y246989I-2015J-1164D01*
G01X960041Y246947D01*
X960022Y246913D01*
G03X960041Y245372I1384J-754D01*
G02X960066Y243089I-2015J-1164D01*
G01X960041Y243047D01*
X960022Y243013D01*
G03X960041Y241472I1384J-754D01*
G02X960066Y239189I-2015J-1164D01*
G01X960041Y239147D01*
X960022Y239113D01*
G03X960041Y237572I1384J-754D01*
G02X960066Y235289I-2015J-1164D01*
G01X960041Y235247D01*
X960022Y235213D01*
G03X960041Y233672I1384J-754D01*
G02Y231346I-2015J-1163D01*
G03Y229772I1365J-787D01*
G01X960066Y229730D01*
G02X960041Y227447I-2040J-1119D01*
G01X960022Y227413D01*
G03X960041Y225872I1384J-754D01*
G02X960066Y223589I-2015J-1164D01*
G01X960041Y223547D01*
X960022Y223513D01*
G03X960041Y221972I1384J-754D01*
G02X960066Y219689I-2015J-1164D01*
G01X960041Y219647D01*
X960022Y219613D01*
G03X960041Y218072I1384J-754D01*
G02X960066Y215789I-2015J-1164D01*
G01X960041Y215747D01*
X960022Y215713D01*
G03X960041Y214172I1384J-754D01*
G02X960066Y211889I-2015J-1164D01*
G01X960041Y211847D01*
X960022Y211813D01*
G03X960041Y210272I1384J-754D01*
G01X960188Y210017D01*
Y202587D01*
X960359Y202416D01*
Y199660D01*
X959676Y198977D01*
Y198221D01*
X960556Y197341D01*
G01X977756Y197291D02*
X978556Y198091D01*
Y198341D01*
X976202Y200695D01*
Y206447D01*
X972526Y210123D01*
Y219361D01*
X973122Y219957D01*
Y220809D01*
G03X972911Y221597I-1577J0D01*
G02X972886Y223880I2015J1164D01*
G01X972911Y223922D01*
X972930Y223956D01*
G03X972911Y225497I-1384J754D01*
G02Y227823I2015J1163D01*
G03Y229397I-1365J787D01*
G01X972886Y229439D01*
G02X972911Y231722I2040J1119D01*
G01X972930Y231756D01*
G03X972911Y233297I-1384J754D01*
G02X972886Y235580I2015J1164D01*
G01X972911Y235622D01*
X972930Y235656D01*
G03X972911Y237197I-1384J754D01*
G02X972886Y239480I2015J1164D01*
G01X972911Y239522D01*
X972930Y239556D01*
G03X972911Y241097I-1384J754D01*
G02X972886Y243380I2015J1164D01*
G01X972911Y243422D01*
X972930Y243456D01*
G03X972911Y244997I-1384J754D01*
G02X972886Y247280I2015J1164D01*
G01X972911Y247322D01*
X972930Y247356D01*
G03X972911Y248897I-1384J754D01*
G02X972886Y251180I2015J1164D01*
G01X972911Y251222D01*
X972930Y251256D01*
G03X972911Y252797I-1384J754D01*
G02X972886Y255080I2015J1164D01*
G01X972911Y255122D01*
X972930Y255156D01*
G03X972911Y256697I-1384J754D01*
G02X972886Y258980I2015J1164D01*
G01X972911Y259022D01*
X972930Y259056D01*
G03X972911Y260597I-1384J754D01*
G02X972886Y262880I2015J1164D01*
G01X972911Y262922D01*
X972930Y262956D01*
G03X972911Y264497I-1384J754D01*
G01X972845Y264610D01*
X971546Y267609D01*
G01X980256Y197291D02*
X979306Y198241D01*
Y198693D01*
X976952Y201047D01*
Y206799D01*
X973277Y210474D01*
Y218978D01*
X973873Y219574D01*
Y220809D01*
G03X973561Y221972I-2327J-1D01*
G02X973542Y223513I1365J787D01*
G01X973561Y223547D01*
X973586Y223589D01*
G03X973561Y225872I-2040J1119D01*
G02X973542Y227413I1365J787D01*
G01X973561Y227447D01*
G03X973586Y229730I-2015J1164D01*
G01X973561Y229772D01*
G02Y231346I1365J787D01*
G03Y233672I-2015J1163D01*
G02X973542Y235213I1365J787D01*
G01X973561Y235247D01*
X973586Y235289D01*
G03X973561Y237572I-2040J1119D01*
G02X973542Y239113I1365J787D01*
G01X973561Y239147D01*
X973586Y239189D01*
G03X973561Y241472I-2040J1119D01*
G02X973542Y243013I1365J787D01*
G01X973561Y243047D01*
X973586Y243089D01*
G03X973561Y245372I-2040J1119D01*
G02X973542Y246913I1365J787D01*
G01X973561Y246947D01*
X973586Y246989D01*
G03X973561Y249272I-2040J1119D01*
G02X973542Y250813I1365J787D01*
G01X973561Y250847D01*
X973586Y250889D01*
G03X973561Y253172I-2040J1119D01*
G02X973542Y254713I1365J787D01*
G01X973561Y254747D01*
X973586Y254789D01*
G03X973561Y257072I-2040J1119D01*
G02X973542Y258613I1365J787D01*
G01X973561Y258647D01*
X973586Y258689D01*
G03X973561Y260972I-2040J1119D01*
G02X973542Y262513I1365J787D01*
G01X973561Y262547D01*
X973586Y262589D01*
G03X973561Y264872I-2040J1119D01*
G02X973352Y265638I1377J787D01*
G01Y268321D01*
X972811Y268862D01*
X971546Y271509D01*
G01X958026Y267609D02*
X957795Y267360D01*
G03X956027Y264900I11400J-10059D01*
G01X956011Y264872D01*
G03Y262546I2015J-1163D01*
G02Y260972I-1364J-787D01*
G03X955976Y258707I2017J-1164D01*
G01X956011Y258647D01*
G02Y257073I-1364J-787D01*
G03X955976Y254807I2015J-1164D01*
G01X956011Y254747D01*
G02Y253173I-1364J-787D01*
G03X955976Y250907I2015J-1164D01*
G01X956011Y250847D01*
G02Y249273I-1364J-787D01*
G03X955976Y247007I2015J-1164D01*
G01X956011Y246947D01*
G02Y245373I-1364J-787D01*
G03X955976Y243107I2015J-1164D01*
G01X956011Y243047D01*
G02Y241473I-1364J-787D01*
G03X955976Y239207I2015J-1164D01*
G01X956011Y239147D01*
G02Y237573I-1364J-787D01*
G03X955976Y235307I2015J-1164D01*
G01X956011Y235247D01*
G02Y233673I-1364J-787D01*
G03X955986Y231388I2015J-1165D01*
G01X956011Y231346D01*
G02Y229772I-1364J-787D01*
G01X955986Y229730D01*
G03X956011Y227447I2040J-1119D01*
G02Y225873I-1364J-787D01*
G03X955976Y223607I2015J-1164D01*
G01X956011Y223547D01*
G02Y221973I-1364J-787D01*
G03X955976Y219707I2015J-1164D01*
G01X956011Y219647D01*
G02Y218073I-1364J-787D01*
G03X955976Y215807I2015J-1164D01*
G01X956011Y215747D01*
G02Y214173I-1364J-787D01*
G03X955976Y211907I2015J-1164D01*
G01X956011Y211847D01*
G02X956222Y211060I-1364J-787D01*
G01Y203501D01*
X953934Y201213D01*
Y198219D01*
X953056Y197341D01*
G01X956973Y209837D02*
Y203190D01*
X954684Y200901D01*
Y198213D01*
X955556Y197341D01*
G01X968166Y265660D02*
X969320Y264994D01*
X969414Y264642D01*
G03X969506Y262589I2131J-933D01*
G03X969531Y262546I896J492D01*
G02Y260972I-1365J-787D01*
G03X969506Y258689I2018J-1164D01*
G01X969531Y258647D01*
X969550Y258613D01*
G02X969531Y257072I-1384J-754D01*
G03X969506Y254789I2015J-1164D01*
G01X969531Y254747D01*
X969550Y254713D01*
G02X969531Y253172I-1384J-754D01*
G03X969506Y250889I2015J-1164D01*
G01X969531Y250847D01*
X969550Y250813D01*
G02X969531Y249272I-1384J-754D01*
G03X969506Y246989I2015J-1164D01*
G01X969531Y246947D01*
X969550Y246913D01*
G02X969531Y245372I-1384J-754D01*
G03X969506Y243089I2015J-1164D01*
G01X969531Y243047D01*
X969550Y243013D01*
G02X969531Y241472I-1384J-754D01*
G03X969506Y239189I2015J-1164D01*
G01X969531Y239147D01*
X969550Y239113D01*
G02X969531Y237572I-1384J-754D01*
G03X969506Y235289I2015J-1164D01*
G01X969531Y235247D01*
X969550Y235213D01*
G02X969531Y233672I-1384J-754D01*
G03Y231346I2015J-1163D01*
G02Y229772I-1365J-787D01*
G01X969506Y229730D01*
G03X969531Y227447I2040J-1119D01*
G01X969550Y227413D01*
G02X969531Y225872I-1384J-754D01*
G03X969506Y223589I2015J-1164D01*
G01X969531Y223547D01*
X969550Y223513D01*
G02X969531Y221972I-1384J-754D01*
G03X969506Y219689I2015J-1164D01*
G02X969643Y219410I-1351J-836D01*
G02X969741Y218869I-1444J-541D01*
G01Y217659D01*
X969506Y217424D01*
Y208905D01*
X971967Y206444D01*
Y202801D01*
X971444Y201888D01*
Y200207D01*
X973450Y198201D01*
Y197385D01*
X972756Y196691D01*
G01X975256Y196651D02*
X974266Y197641D01*
Y198479D01*
X972194Y200551D01*
Y201656D01*
X972717Y202569D01*
Y206784D01*
X970256Y209245D01*
Y217092D01*
X970491Y217327D01*
Y218870D01*
G03X970352Y219658I-2301J0D01*
G03X970162Y220052I-2058J-750D01*
G02X970180Y221598I1384J757D01*
G01X970181Y221597D01*
G03X970206Y223880I-2015J1164D01*
G01X970181Y223922D01*
X970162Y223956D01*
G02X970181Y225497I1384J754D01*
G03Y227823I-2015J1163D01*
G02Y229397I1365J787D01*
G01X970206Y229439D01*
G03X970181Y231722I-2040J1119D01*
G01X970162Y231756D01*
G02X970181Y233297I1384J754D01*
G03X970206Y235580I-2015J1164D01*
G01X970181Y235622D01*
X970162Y235656D01*
G02X970181Y237197I1384J754D01*
G03X970206Y239480I-2015J1164D01*
G01X970181Y239522D01*
X970162Y239556D01*
G02X970181Y241097I1384J754D01*
G03X970206Y243380I-2015J1164D01*
G01X970181Y243422D01*
X970162Y243456D01*
G02X970181Y244997I1384J754D01*
G03X970206Y247280I-2015J1164D01*
G01X970181Y247322D01*
X970162Y247356D01*
G02X970181Y248897I1384J754D01*
G03X970206Y251180I-2015J1164D01*
G01X970181Y251222D01*
X970162Y251256D01*
G02X970181Y252797I1384J754D01*
G03X970206Y255080I-2015J1164D01*
G01X970181Y255122D01*
X970162Y255156D01*
G02X970181Y256697I1384J754D01*
G03X970206Y258980I-2015J1164D01*
G01X970181Y259022D01*
X970162Y259056D01*
G02X970181Y260596I1382J753D01*
G03Y262922I-2015J1163D01*
G02Y264496I1365J787D01*
G03Y266822I-2015J1163D01*
G02X969718Y269289I3278J1892D01*
G03X969531Y270346I-1552J270D01*
G02X969345Y270754I2014J1165D01*
G01X968166Y273460D01*
G01X991826Y224709D02*
X993969Y221255D01*
X995842Y220303D01*
G02X995889Y217441I-636J-1442D01*
G03X995299Y216956I697J-1449D01*
G01X995252Y216909D01*
G02X994580Y216433I-1731J1732D01*
G03X993822Y215713I736J-1534D01*
G03X993841Y214172I1384J-754D01*
G02X993866Y211889I-2015J-1164D01*
G01X993841Y211847D01*
X993822Y211813D01*
G03X993841Y210272I1384J-754D01*
G02Y207946I-2015J-1163D01*
G03Y206372I1365J-787D01*
G01X993866Y206330D01*
G02X994073Y204607I-2040J-1119D01*
G02X993842Y204048I-2247J601D01*
G03X993606Y203165I1535J-883D01*
G01Y202394D01*
X996184Y199816D01*
Y198054D01*
G01X988446Y222760D02*
X987149Y219764D01*
X987062Y219613D01*
G03X987081Y218072I1384J-754D01*
G02X987106Y215789I-2015J-1164D01*
G01X987081Y215747D01*
G03X986871Y215001I1365J-787D01*
G01X986860Y214580D01*
Y202240D01*
X989709Y199391D01*
Y197885D01*
G01X991826Y213009D02*
X990529Y210013D01*
X990442Y209862D01*
G03X990461Y208321I1384J-754D01*
G02X990486Y206038I-2015J-1164D01*
G01X990461Y205996D01*
X990434Y205948D01*
G03X990461Y204422I1392J-739D01*
G02X990963Y202545I-3257J-1877D01*
G01Y202082D01*
X993094Y199951D01*
Y198703D01*
G01X988446Y214960D02*
X989811Y211846D01*
G02X989830Y210305I-1365J-787D01*
G01X989811Y210271D01*
X989786Y210229D01*
G03X989811Y207946I2040J-1119D01*
G02X989838Y206420I-1365J-787D01*
G01X989776Y206312D01*
G03X989811Y204046I2050J-1102D01*
G01X989830Y204012D01*
G02X990109Y203002I-1802J-1041D01*
G01Y201409D01*
X991268Y200250D01*
Y197909D01*
G01X958026Y271509D02*
X958200Y271065D01*
X959106Y268756D01*
G02X958634Y266138I-1088J-1155D01*
G01X958625Y266135D01*
G03X956662Y264496I1191J-3422D01*
G03Y262922I1364J-787D01*
G02Y260596I-2015J-1163D01*
G03Y259022I1364J-787D01*
G01X956697Y258962D01*
G02X956662Y256696I-2050J-1102D01*
G03Y255122I1364J-787D01*
G01X956697Y255062D01*
G02X956662Y252796I-2050J-1102D01*
G03Y251222I1364J-787D01*
G01X956697Y251162D01*
G02X956662Y248896I-2050J-1102D01*
G03Y247322I1364J-787D01*
G01X956697Y247262D01*
G02X956662Y244996I-2050J-1102D01*
G03Y243422I1364J-787D01*
G01X956697Y243362D01*
G02X956662Y241096I-2050J-1102D01*
G03Y239522I1364J-787D01*
G01X956697Y239462D01*
G02X956662Y237196I-2050J-1102D01*
G03Y235622I1364J-787D01*
G01X956697Y235562D01*
G02X956662Y233296I-2050J-1102D01*
G03Y231722I1364J-787D01*
G02X956687Y229439I-2015J-1164D01*
G01X956662Y229397D01*
G03Y227823I1364J-787D01*
G01X956687Y227781D01*
G02X956662Y225496I-2040J-1120D01*
G03Y223922I1364J-787D01*
G01X956697Y223862D01*
G02X956662Y221596I-2050J-1102D01*
G03Y220022I1364J-787D01*
G01X956697Y219962D01*
G02X956662Y217696I-2050J-1102D01*
G03Y216122I1364J-787D01*
G01X956697Y216062D01*
G02X956662Y213796I-2050J-1102D01*
G03Y212222I1364J-787D01*
G01X956697Y212162D01*
G02X956974Y211060I-2050J-1101D01*
G01X956973Y209837D01*
G01X930987Y263709D02*
G02X928972Y266446I11203J10358D01*
G03X927554Y267234I-1365J-787D01*
G01X926478Y268461D01*
G02X926307Y268669I1127J1101D01*
G02X926242Y268772I1299J892D01*
G03X924299Y269934I-2015J-1163D01*
G01X924155D01*
G03X922212Y268772I72J-2325D01*
G02X920906Y267985I-1365J788D01*
G01X920777D01*
G03X918832Y266822I70J-2325D01*
G02X917511Y266034I-1365J787D01*
G01X916667D01*
G01X968166Y328060D02*
Y326729D01*
X967938Y326501D01*
G02X966801Y328847I228J1559D01*
G01X966826Y328889D01*
G03X966801Y331172I-2040J1119D01*
G02X966782Y332713I1365J787D01*
G01X966801Y332747D01*
X966826Y332789D01*
G03X966801Y335072I-2040J1119D01*
G02X966782Y336613I1365J787D01*
G01X966801Y336647D01*
X966826Y336689D01*
G03X966801Y338972I-2040J1119D01*
G02X966782Y340513I1365J787D01*
G01X966801Y340547D01*
X966826Y340589D01*
G03X966801Y342872I-2040J1119D01*
G02X966782Y344413I1365J787D01*
G01X966801Y344447D01*
X966826Y344489D01*
G03X966801Y346772I-2040J1119D01*
G02X966782Y348313I1365J787D01*
G01X966801Y348347D01*
X966826Y348389D01*
G03X966801Y350672I-2040J1119D01*
G02X966782Y352213I1365J787D01*
G01X966801Y352247D01*
X966826Y352289D01*
G03X966801Y354572I-2040J1119D01*
G02X966782Y356113I1365J787D01*
G01X966801Y356147D01*
X966826Y356189D01*
G03X966801Y358472I-2040J1119D01*
G02X966782Y360013I1365J787D01*
G01X966801Y360047D01*
X966826Y360089D01*
G03X966801Y362372I-2040J1119D01*
G02X966782Y363913I1365J787D01*
G01X966801Y363947D01*
X966826Y363989D01*
G03X966801Y366272I-2040J1119D01*
G02X966782Y367813I1365J787D01*
G01X966801Y367847D01*
G03X966826Y370130I-2015J1164D01*
G01X966801Y370172D01*
G02Y371746I1365J787D01*
G03Y374072I-2015J1163D01*
G02X966782Y375613I1365J787D01*
G01X966801Y375647D01*
X966826Y375689D01*
G03X966801Y377972I-2040J1119D01*
G02X966782Y379513I1365J787D01*
G01X966801Y379547D01*
X966826Y379589D01*
G03X966801Y381872I-2040J1119D01*
G02X966782Y383413I1365J787D01*
G01X966801Y383447D01*
X966826Y383489D01*
G03X966801Y385772I-2040J1119D01*
G02X966782Y387313I1365J787D01*
G01X966801Y387347D01*
X966826Y387389D01*
G03X966801Y389672I-2040J1119D01*
G02Y391248I1365J788D01*
G03X966816Y393544I-2015J1161D01*
G01X966814Y393547D01*
X966412Y394245D01*
X965688Y394969D01*
Y405357D01*
X965843Y405512D01*
G01X968166Y335860D02*
X969226Y338460D01*
X969531Y338972D01*
G03X969550Y340513I-1365J787D01*
G01X969531Y340547D01*
X969506Y340589D01*
G02X969531Y342872I2040J1119D01*
G03X969550Y344413I-1365J787D01*
G01X969531Y344447D01*
X969506Y344489D01*
G02X969531Y346772I2040J1119D01*
G03X969550Y348313I-1365J787D01*
G01X969531Y348347D01*
X969506Y348389D01*
G02X969531Y350672I2040J1119D01*
G03X969550Y352213I-1365J787D01*
G01X969531Y352247D01*
X969506Y352289D01*
G02X969531Y354572I2040J1119D01*
G03X969550Y356113I-1365J787D01*
G01X969531Y356147D01*
X969506Y356189D01*
G02X969531Y358472I2040J1119D01*
G03X969550Y360013I-1365J787D01*
G01X969531Y360047D01*
X969506Y360089D01*
G02X969531Y362372I2040J1119D01*
G03X969550Y363913I-1365J787D01*
G01X969531Y363947D01*
X969506Y363989D01*
G02X969531Y366272I2040J1119D01*
G03X969550Y367813I-1365J787D01*
G01X969531Y367847D01*
G02X969506Y370130I2015J1164D01*
G01X969531Y370172D01*
G03Y371746I-1365J787D01*
G02Y374072I2015J1163D01*
G03X969550Y375613I-1365J787D01*
G01X969531Y375647D01*
X969506Y375689D01*
G02X969531Y377972I2040J1119D01*
G03X969550Y379513I-1365J787D01*
G01X969531Y379547D01*
X969526Y379555D01*
X969522Y379561D01*
X969517Y379571D01*
X969506Y379589D01*
G02X969531Y381872I2040J1119D01*
G01X969756Y382265D01*
Y395180D01*
X968091Y396845D01*
Y402808D01*
X968941Y404278D01*
Y408945D01*
X968786Y409100D01*
Y409187D01*
G01X964783Y405512D02*
X964938Y405357D01*
Y394658D01*
X965811Y393785D01*
X966163Y393174D01*
G02X966151Y391623I-1377J-765D01*
G03Y389297I2015J-1163D01*
G02X966170Y387756I-1365J-787D01*
G01X966151Y387722D01*
X966126Y387680D01*
G03X966151Y385397I2040J-1119D01*
G02X966170Y383856I-1365J-787D01*
G01X966151Y383822D01*
X966126Y383780D01*
G03X966151Y381497I2040J-1119D01*
G02X966170Y379956I-1365J-787D01*
G01X966151Y379922D01*
X966126Y379880D01*
G03X966151Y377597I2040J-1119D01*
G02X966170Y376056I-1365J-787D01*
G01X966151Y376022D01*
X966126Y375980D01*
G03X966151Y373697I2040J-1119D01*
G02X966170Y372156I-1365J-787D01*
G01X966151Y372122D01*
G03X966126Y369839I2015J-1164D01*
G01X966151Y369797D01*
G02Y368223I-1365J-787D01*
G03Y365897I2015J-1163D01*
G02X966170Y364356I-1365J-787D01*
G01X966151Y364322D01*
X966126Y364280D01*
G03X966151Y361997I2040J-1119D01*
G02X966170Y360456I-1365J-787D01*
G01X966151Y360422D01*
X966126Y360380D01*
G03X966151Y358097I2040J-1119D01*
G02X966170Y356556I-1365J-787D01*
G01X966151Y356522D01*
X966126Y356480D01*
G03X966151Y354197I2040J-1119D01*
G02X966170Y352656I-1365J-787D01*
G01X966151Y352622D01*
X966126Y352580D01*
G03X966151Y350297I2040J-1119D01*
G02X966170Y348756I-1365J-787D01*
G01X966151Y348722D01*
X966126Y348680D01*
G03X966151Y346397I2040J-1119D01*
G02X966170Y344856I-1365J-787D01*
G01X966151Y344822D01*
X966126Y344780D01*
G03X966151Y342497I2040J-1119D01*
G02X966170Y340956I-1365J-787D01*
G01X966151Y340922D01*
X966126Y340880D01*
G03X966151Y338597I2040J-1119D01*
G02X966170Y337056I-1365J-787D01*
G01X966151Y337022D01*
X966126Y336980D01*
G03X966151Y334697I2040J-1119D01*
G02X966170Y333156I-1365J-787D01*
G01X966151Y333122D01*
X966126Y333080D01*
G03X966151Y330797I2040J-1119D01*
G02X966170Y329256I-1365J-787D01*
G01X966151Y329222D01*
X966126Y329180D01*
G03X967910Y325747I2040J-1120D01*
G01X968166Y325491D01*
Y324160D01*
G01Y331960D02*
G02X969531Y335076I14845J-4646D01*
G03X969728Y336067I-1365J786D01*
G01Y337700D01*
G02X970181Y338597I8201J-3579D01*
G03X970206Y340880I-2015J1164D01*
G01X970181Y340922D01*
X970162Y340956D01*
G02X970181Y342497I1384J754D01*
G03X970206Y344780I-2015J1164D01*
G01X970181Y344822D01*
X970162Y344856D01*
G02X970181Y346397I1384J754D01*
G03X970206Y348680I-2015J1164D01*
G01X970181Y348722D01*
X970162Y348756D01*
G02X970181Y350297I1384J754D01*
G03X970206Y352580I-2015J1164D01*
G01X970181Y352622D01*
X970162Y352656D01*
G02X970181Y354197I1384J754D01*
G03X970206Y356480I-2015J1164D01*
G01X970181Y356522D01*
X970162Y356556D01*
G02X970181Y358097I1384J754D01*
G03X970206Y360380I-2015J1164D01*
G01X970181Y360422D01*
X970162Y360456D01*
G02X970181Y361997I1384J754D01*
G03X970206Y364280I-2015J1164D01*
G01X970181Y364322D01*
X970162Y364356D01*
G02X970181Y365897I1384J754D01*
G03Y368223I-2015J1163D01*
G02Y369797I1365J787D01*
G01X970206Y369839D01*
G03X970181Y372122I-2040J1119D01*
G01X970162Y372156D01*
G02X970181Y373697I1384J754D01*
G03X970206Y375980I-2015J1164D01*
G01X970181Y376022D01*
X970162Y376056D01*
G02X970181Y377597I1384J754D01*
G03X970206Y379880I-2015J1164D01*
G01X970163Y379952D01*
X970161Y379955D01*
X970162Y379956D01*
G02X970181Y381497I1384J754D01*
G01X970506Y382060D01*
Y395491D01*
X968841Y397156D01*
Y402606D01*
X969691Y404076D01*
Y408945D01*
X969846Y409100D01*
Y409187D01*
G01X964786Y326110D02*
X962837Y328731D01*
X962771Y328847D01*
X962746Y328889D01*
G02X962771Y331172I2040J1119D01*
G03X962790Y332713I-1365J787D01*
G01X962771Y332747D01*
X962746Y332789D01*
G02X962771Y335072I2040J1119D01*
G03X962790Y336613I-1365J787D01*
G01X962771Y336647D01*
X962746Y336689D01*
G02X962771Y338972I2040J1119D01*
G03X962790Y340513I-1365J787D01*
G01X962771Y340547D01*
X962746Y340589D01*
G02X962771Y342872I2040J1119D01*
G03X962790Y344413I-1365J787D01*
G01X962771Y344447D01*
X962746Y344489D01*
G02X962771Y346772I2040J1119D01*
G03X962790Y348313I-1365J787D01*
G01X962771Y348347D01*
X962746Y348389D01*
G02X962771Y350672I2040J1119D01*
G03X962790Y352213I-1365J787D01*
G01X962771Y352247D01*
X962746Y352289D01*
G02X962771Y354572I2040J1119D01*
G03X962790Y356113I-1365J787D01*
G01X962771Y356147D01*
X962746Y356189D01*
G02X962771Y358472I2040J1119D01*
G03X962790Y360013I-1365J787D01*
G01X962771Y360047D01*
X962746Y360089D01*
G02X962771Y362372I2040J1119D01*
G03X962790Y363913I-1365J787D01*
G01X962771Y363947D01*
X962746Y363989D01*
G02X962771Y366272I2040J1119D01*
G03X962790Y367813I-1365J787D01*
G01X962771Y367847D01*
G02X962746Y370130I2015J1164D01*
G01X962771Y370172D01*
G03Y371746I-1365J787D01*
G02Y374072I2015J1163D01*
G03X962790Y375613I-1365J787D01*
G01X962771Y375647D01*
X962746Y375689D01*
G02X962771Y377972I2040J1119D01*
G03X962790Y379513I-1365J787D01*
G01X962771Y379547D01*
X962746Y379589D01*
G02X962771Y381872I2040J1119D01*
G03X962790Y383413I-1365J787D01*
G01X962771Y383447D01*
X962746Y383489D01*
G02X962771Y385772I2040J1119D01*
G03X962790Y387313I-1365J787D01*
G01X962024Y388684D01*
Y393973D01*
X960356Y395641D01*
Y399541D01*
X959433Y400464D01*
G01X964786Y333909D02*
X963489Y336905D01*
X963402Y337056D01*
G02X963421Y338597I1384J754D01*
G03X963446Y340880I-2015J1164D01*
G01X963421Y340922D01*
X963402Y340956D01*
G02X963421Y342497I1384J754D01*
G03X963446Y344780I-2015J1164D01*
G01X963421Y344822D01*
X963402Y344856D01*
G02X963421Y346397I1384J754D01*
G03X963446Y348680I-2015J1164D01*
G01X963421Y348722D01*
X963402Y348756D01*
G02X963421Y350297I1384J754D01*
G03X963446Y352580I-2015J1164D01*
G01X963421Y352622D01*
X963402Y352656D01*
G02X963421Y354197I1384J754D01*
G03X963446Y356480I-2015J1164D01*
G01X963421Y356522D01*
X963402Y356556D01*
G02X963421Y358097I1384J754D01*
G03X963446Y360380I-2015J1164D01*
G01X963421Y360422D01*
X963402Y360456D01*
G02X963421Y361997I1384J754D01*
G03X963446Y364280I-2015J1164D01*
G01X963421Y364322D01*
X963402Y364356D01*
G02X963421Y365897I1384J754D01*
G03Y368223I-2015J1163D01*
G02Y369797I1365J787D01*
G01X963446Y369839D01*
G03X963421Y372122I-2040J1119D01*
G01X963402Y372156D01*
G02X963421Y373697I1384J754D01*
G03X963446Y375980I-2015J1164D01*
G01X963421Y376022D01*
X963402Y376056D01*
G02X963421Y377597I1384J754D01*
G03X963446Y379880I-2015J1164D01*
G01X963421Y379922D01*
X963402Y379956D01*
G02X963421Y381497I1384J754D01*
G03X963446Y383780I-2015J1164D01*
G01X963421Y383822D01*
X963402Y383856D01*
G02X963421Y385397I1384J754D01*
G03X963446Y387680I-2015J1164D01*
G01X962772Y388879D01*
Y394283D01*
X961104Y395951D01*
Y399483D01*
X961933Y400312D01*
G01X961406Y328060D02*
X959457Y330681D01*
X959391Y330797D01*
G02X959366Y333080I2015J1164D01*
G01X959391Y333122D01*
X959410Y333156D01*
G03X959391Y334697I-1384J754D01*
G02X959366Y336980I2015J1164D01*
G01X959391Y337022D01*
X959410Y337056D01*
G03X959391Y338597I-1384J754D01*
G02X959366Y340880I2015J1164D01*
G01X959391Y340922D01*
X959410Y340956D01*
G03X959391Y342497I-1384J754D01*
G02X959366Y344780I2015J1164D01*
G01X959391Y344822D01*
X959410Y344856D01*
G03X959391Y346397I-1384J754D01*
G02X959366Y348680I2015J1164D01*
G01X959391Y348722D01*
X959410Y348756D01*
G03X959391Y350297I-1384J754D01*
G02X959366Y352580I2015J1164D01*
G01X959391Y352622D01*
X959410Y352656D01*
G03X959391Y354197I-1384J754D01*
G02X959366Y356480I2015J1164D01*
G01X959391Y356522D01*
X959410Y356556D01*
G03X959391Y358097I-1384J754D01*
G02X959366Y360380I2015J1164D01*
G01X959391Y360422D01*
X959410Y360456D01*
G03X959391Y361997I-1384J754D01*
G02X959366Y364280I2015J1164D01*
G01X959391Y364322D01*
X959410Y364356D01*
G03X959391Y365897I-1384J754D01*
G02Y368223I2015J1163D01*
G03Y369797I-1365J787D01*
G01X959366Y369839D01*
G02X959391Y372122I2040J1119D01*
G01X959410Y372156D01*
G03X959391Y373697I-1384J754D01*
G02X959366Y375980I2015J1164D01*
G01X959391Y376022D01*
X959410Y376056D01*
G03X959391Y377597I-1384J754D01*
G02X959366Y379880I2015J1164D01*
G01X959391Y379922D01*
X959410Y379956D01*
G03X959391Y381497I-1384J754D01*
G02X959366Y383780I2015J1164D01*
G01X959391Y383822D01*
X959410Y383856D01*
G03X959391Y385397I-1384J754D01*
G02X959366Y387680I2015J1164D01*
G01X959601Y388075D01*
Y389424D01*
X956355Y392670D01*
Y395242D01*
X954956Y396641D01*
Y399339D01*
X954133Y400162D01*
G01X961406Y331960D02*
X960107Y334959D01*
G01D02*
X960041Y335072D01*
G02X960022Y336613I1365J787D01*
G01X960041Y336647D01*
X960066Y336689D01*
G03X960041Y338972I-2040J1119D01*
G02X960022Y340513I1365J787D01*
G01X960041Y340547D01*
X960066Y340589D01*
G03X960041Y342872I-2040J1119D01*
G02X960022Y344413I1365J787D01*
G01X960041Y344447D01*
X960066Y344489D01*
G03X960041Y346772I-2040J1119D01*
G02X960022Y348313I1365J787D01*
G01X960041Y348347D01*
X960066Y348389D01*
G03X960041Y350672I-2040J1119D01*
G02X960022Y352213I1365J787D01*
G01X960041Y352247D01*
X960066Y352289D01*
G03X960041Y354572I-2040J1119D01*
G02X960022Y356113I1365J787D01*
G01X960041Y356147D01*
X960066Y356189D01*
G03X960041Y358472I-2040J1119D01*
G02X960022Y360013I1365J787D01*
G01X960041Y360047D01*
X960066Y360089D01*
G03X960041Y362372I-2040J1119D01*
G02X960022Y363913I1365J787D01*
G01X960041Y363947D01*
X960066Y363989D01*
G03X960041Y366272I-2040J1119D01*
G02X960022Y367813I1365J787D01*
G01X960041Y367847D01*
G03X960066Y370130I-2015J1164D01*
G01X960041Y370172D01*
G02Y371746I1365J787D01*
G03Y374072I-2015J1163D01*
G02X960022Y375613I1365J787D01*
G01X960041Y375647D01*
X960066Y375689D01*
G03X960041Y377972I-2040J1119D01*
G02X960022Y379513I1365J787D01*
G01X960041Y379547D01*
X960066Y379589D01*
G03X960041Y381872I-2040J1119D01*
G02X960022Y383413I1365J787D01*
G01X960041Y383447D01*
X960066Y383489D01*
G03X960041Y385772I-2040J1119D01*
G02X960022Y387313I1365J787D01*
G01X960066Y387392D01*
X960349Y387868D01*
Y389734D01*
X957103Y392980D01*
Y395552D01*
X955704Y396951D01*
Y399383D01*
X956633Y400312D01*
G01X971546Y326110D02*
X970248Y329107D01*
X970181Y329222D01*
X970162Y329256D01*
G02X970181Y330797I1384J754D01*
G03X970206Y333080I-2015J1164D01*
G01X970181Y333122D01*
X970162Y333156D01*
G02X970904Y335348I1384J753D01*
G01D02*
X971536Y335693D01*
X972709Y336672D01*
X972930Y337056D01*
G03X972911Y338597I-1384J754D01*
G02X972886Y340880I2015J1164D01*
G01X972911Y340922D01*
X972930Y340956D01*
G03X972911Y342497I-1384J754D01*
G02X972886Y344780I2015J1164D01*
G01X972911Y344822D01*
X972930Y344856D01*
G03X972911Y346397I-1384J754D01*
G02X972886Y348680I2015J1164D01*
G01X972911Y348722D01*
X972930Y348756D01*
G03X972911Y350297I-1384J754D01*
G02X972886Y352580I2015J1164D01*
G01X972911Y352622D01*
X972930Y352656D01*
G03X972911Y354197I-1384J754D01*
G02X972886Y356480I2015J1164D01*
G01X972911Y356522D01*
X972930Y356556D01*
G03X972911Y358097I-1384J754D01*
G02X972886Y360380I2015J1164D01*
G01X972911Y360422D01*
X972930Y360456D01*
G03X972911Y361997I-1384J754D01*
G02X972886Y364280I2015J1164D01*
G01X972911Y364322D01*
X972930Y364356D01*
G03X972911Y365897I-1384J754D01*
G02Y368223I2015J1163D01*
G03Y369797I-1365J787D01*
G01X972886Y369839D01*
G02X972911Y372122I2040J1119D01*
G01X972930Y372156D01*
G03X972911Y373697I-1384J754D01*
G02X972886Y375980I2015J1164D01*
G01X972911Y376022D01*
X972930Y376056D01*
G03X972911Y377597I-1384J754D01*
G02X972886Y379880I2015J1164D01*
G01X973301Y380617D01*
Y384696D01*
X972556Y385441D01*
Y396041D01*
X971556Y397041D01*
Y400841D01*
X973540Y402825D01*
Y403096D01*
X972712Y403924D01*
G01X971546Y333909D02*
G03X973216Y336041I-6368J6708D01*
G01X973561Y336647D01*
X973586Y336689D01*
G03X973561Y338972I-2040J1119D01*
G02X973542Y340513I1365J787D01*
G01X973561Y340547D01*
X973586Y340589D01*
G03X973561Y342872I-2040J1119D01*
G02X973542Y344413I1365J787D01*
G01X973561Y344447D01*
X973586Y344489D01*
G03X973561Y346772I-2040J1119D01*
G02X973542Y348313I1365J787D01*
G01X973561Y348347D01*
X973586Y348389D01*
G03X973561Y350672I-2040J1119D01*
G02X973542Y352213I1365J787D01*
G01X973561Y352247D01*
X973586Y352289D01*
G03X973561Y354572I-2040J1119D01*
G02X973542Y356113I1365J787D01*
G01X973561Y356147D01*
X973586Y356189D01*
G03X973561Y358472I-2040J1119D01*
G02X973542Y360013I1365J787D01*
G01X973561Y360047D01*
X973586Y360089D01*
G03X973561Y362372I-2040J1119D01*
G02X973542Y363913I1365J787D01*
G01X973561Y363947D01*
X973586Y363989D01*
G03X973561Y366272I-2040J1119D01*
G02X973542Y367813I1365J787D01*
G01X973561Y367847D01*
G03X973586Y370130I-2015J1164D01*
G01X973561Y370172D01*
G02Y371746I1365J787D01*
G03Y374072I-2015J1163D01*
G02X973542Y375613I1365J787D01*
G01X973561Y375647D01*
X973586Y375689D01*
G03X973561Y377972I-2040J1119D01*
G02X973542Y379513I1365J787D01*
G01X974049Y380420D01*
Y385006D01*
X973304Y385751D01*
Y396351D01*
X972304Y397351D01*
Y400531D01*
X974288Y402515D01*
Y402938D01*
X975212Y403862D01*
G01X934367Y359260D02*
X931133Y359634D01*
X930943D01*
G02X929622Y360422I44J1575D01*
G01X928972Y361550D01*
G01X937747Y392410D02*
G02X939112Y395524I14795J-4629D01*
G03Y397098I-1365J787D01*
G01D02*
X938939Y397471D01*
G01X974926Y328060D02*
X973627Y331059D01*
X973561Y331172D01*
G02X974544Y333489I1365J788D01*
G01X975564Y334173D01*
X975791Y334377D01*
X976126Y334787D01*
X976291Y335072D01*
G03X976310Y336613I-1365J787D01*
G01X976291Y336647D01*
X976266Y336689D01*
G02X976291Y338972I2040J1119D01*
G03X976310Y340513I-1365J787D01*
G01X976291Y340547D01*
X976266Y340589D01*
G02X976291Y342872I2040J1119D01*
G03X976310Y344413I-1365J787D01*
G01X976291Y344447D01*
X976266Y344489D01*
G02X976291Y346772I2040J1119D01*
G03X976310Y348313I-1365J787D01*
G01X976291Y348347D01*
X976266Y348389D01*
G02X976291Y350672I2040J1119D01*
G03X976310Y352213I-1365J787D01*
G01X976291Y352247D01*
X976266Y352289D01*
G02X976291Y354572I2040J1119D01*
G03X976310Y356113I-1365J787D01*
G01X976291Y356147D01*
X976266Y356189D01*
G02X976291Y358472I2040J1119D01*
G03X976310Y360013I-1365J787D01*
G01X976291Y360047D01*
X976266Y360089D01*
G02X976291Y362372I2040J1119D01*
G03X976310Y363913I-1365J787D01*
G01X976291Y363947D01*
X976266Y363989D01*
G02X976291Y366272I2040J1119D01*
G03X976310Y367813I-1365J787D01*
G01X976291Y367847D01*
G02X976266Y370130I2015J1164D01*
G01X976291Y370172D01*
G03Y371746I-1365J787D01*
G02Y374072I2015J1163D01*
G03X976310Y375613I-1365J787D01*
G01X976291Y375647D01*
X976266Y375689D01*
G02X976291Y377972I2040J1119D01*
G01X978856Y382412D01*
Y405077D01*
X978216Y405717D01*
G01X974926Y331960D02*
X975032Y331976D01*
X976567Y334040D01*
X976941Y334697D01*
G03X976966Y336980I-2015J1164D01*
G01X976941Y337022D01*
X976922Y337056D01*
G02X976941Y338597I1384J754D01*
G03X976966Y340880I-2015J1164D01*
G01X976941Y340922D01*
X976922Y340956D01*
G02X976941Y342497I1384J754D01*
G03X976966Y344780I-2015J1164D01*
G01X976941Y344822D01*
X976922Y344856D01*
G02X976941Y346397I1384J754D01*
G03X976966Y348680I-2015J1164D01*
G01X976941Y348722D01*
X976922Y348756D01*
G02X976941Y350297I1384J754D01*
G03X976966Y352580I-2015J1164D01*
G01X976941Y352622D01*
X976922Y352656D01*
G02X976941Y354197I1384J754D01*
G03X976966Y356480I-2015J1164D01*
G01X976941Y356522D01*
X976922Y356556D01*
G02X976941Y358097I1384J754D01*
G03X976966Y360380I-2015J1164D01*
G01X976941Y360422D01*
X976922Y360456D01*
G02X976941Y361997I1384J754D01*
G03X976966Y364280I-2015J1164D01*
G01X976941Y364322D01*
X976922Y364356D01*
G02X976941Y365897I1384J754D01*
G03Y368223I-2015J1163D01*
G02Y369797I1365J787D01*
G01X976966Y369839D01*
G03X976941Y372122I-2040J1119D01*
G01X976922Y372156D01*
G02X976941Y373697I1384J754D01*
G03X976966Y375980I-2015J1164D01*
G01X976941Y376022D01*
X976922Y376056D01*
G02X976941Y377597I1384J754D01*
G01X976940Y377599D01*
X979604Y382209D01*
Y405013D01*
X980512Y405921D01*
G01X988446Y374860D02*
X989745Y377859D01*
X989811Y377972D01*
G03X989830Y379513I-1365J787D01*
G01X989811Y379547D01*
X989786Y379589D01*
G02X989811Y381872I2040J1119D01*
G03X989830Y383413I-1365J787D01*
G01X989811Y383447D01*
X989786Y383489D01*
G02X989811Y385772I2040J1119D01*
G03X989830Y387313I-1365J787D01*
G01X989811Y387347D01*
X989786Y387389D01*
G02X989639Y387714I2040J1119D01*
G01X989260Y388140D01*
X989150Y388250D01*
Y398586D01*
X990354Y399790D01*
Y401003D01*
G01X988446Y370959D02*
X990395Y373582D01*
X990461Y373697D01*
G03X990486Y375980I-2015J1164D01*
G01X990461Y376022D01*
X990442Y376056D01*
G02X990461Y377597I1384J754D01*
G03X990486Y379880I-2015J1164D01*
G01X990461Y379922D01*
X990442Y379956D01*
G02X990461Y381497I1384J754D01*
G03X990486Y383780I-2015J1164D01*
G01X990461Y383822D01*
X990442Y383856D01*
G02X990461Y385397I1384J754D01*
G03X990486Y387680I-2015J1164D01*
G01X990461Y387722D01*
X990442Y387756D01*
G02X990261Y388320I1384J755D01*
G01X989900Y389321D01*
Y397400D01*
X992354Y399854D01*
Y400788D01*
G01X988446Y378760D02*
X987147Y381759D01*
X987081Y381872D01*
G02X987062Y383413I1365J787D01*
G01X987081Y383447D01*
X987106Y383489D01*
G03X987179Y385583I-2040J1119D01*
G01X987145Y385617D01*
G02X986872Y386276I659J659D01*
G01Y387212D01*
X988354Y388694D01*
Y400454D01*
G01X995206Y378760D02*
X993907Y381759D01*
X993841Y381872D01*
G02X993822Y383413I1365J787D01*
G01X993841Y383447D01*
X993866Y383489D01*
G03X993841Y385772I-2040J1119D01*
G02X993822Y387313I1365J787D01*
G01X993841Y387347D01*
X993866Y387389D01*
G03X993841Y389672I-2040J1119D01*
G02X993822Y391213I1365J787D01*
G01X993840Y391248D01*
X993841Y391247D01*
G02X993840Y391249I1405J704D01*
G01X994574Y392520D01*
X994576Y392522D01*
Y393876D01*
X996398Y395698D01*
Y397118D01*
G01X991826Y372909D02*
X993123Y375905D01*
X993210Y376056D01*
G03X993191Y377597I-1384J754D01*
G02X993166Y379880I2015J1164D01*
G01X993191Y379922D01*
X993210Y379956D01*
G03X993191Y381497I-1384J754D01*
G02X993166Y383780I2015J1164D01*
G01X993191Y383822D01*
X993210Y383856D01*
G03X993191Y385397I-1384J754D01*
G02X993166Y387680I2015J1164D01*
G01X993191Y387722D01*
X993210Y387756D01*
G03X993191Y389297I-1384J754D01*
G02X993026Y391271I2015J1162D01*
G02X993012Y391317I2219J701D01*
G01X993458Y392089D01*
Y394644D01*
X994398Y395584D01*
Y396937D01*
G01X1025625Y216909D02*
X1024471Y217575D01*
X1024161Y217491D01*
G03X1024050Y216931I1465J-581D01*
G03X1024241Y216156I1576J-23D01*
G01X1024260Y216122D01*
X1024285Y216080D01*
G02X1024260Y213797I-2040J-1119D01*
G03X1024241Y212256I1365J-787D01*
G01X1024260Y212222D01*
X1024285Y212180D01*
G02X1024260Y209897I-2040J-1119D01*
G03X1024241Y208356I1365J-787D01*
G01X1024257Y208327D01*
X1024260Y208322D01*
G02Y205996I-2015J-1163D01*
G01X1024006Y205556D01*
Y202516D01*
X1030341Y196181D01*
Y191286D01*
X1030490Y191137D01*
Y191050D01*
G01X1022245Y218860D02*
X1022686Y218420D01*
G02X1023298Y216941I-1479J-1478D01*
G03X1023585Y215789I2326J-32D01*
G01X1023610Y215747D01*
X1023629Y215713D01*
G02X1023610Y214172I-1384J-754D01*
G03X1023585Y211889I2015J-1164D01*
G01X1023610Y211847D01*
X1023629Y211813D01*
G02X1023610Y210272I-1384J-754D01*
G03X1023584Y207993I2015J-1163D01*
G01X1023604Y207958D01*
X1023610Y207947D01*
G02Y206372I-1365J-787D01*
G01X1023256Y205757D01*
Y202205D01*
X1029591Y195870D01*
Y191331D01*
X1029430Y191170D01*
G01X995206Y230559D02*
X997156Y227937D01*
X997221Y227824D01*
G02Y225498I-2015J-1163D01*
G03Y223924I1365J-787D01*
G02Y221598I-2015J-1163D01*
G03Y220024I1365J-787D01*
G02Y217698I-2015J-1163D01*
G03X996766Y216254I3028J-1748D01*
G02X996775Y214812I-7071J-765D01*
G02X996571Y214174I-1569J150D01*
G03Y211848I2015J-1163D01*
G02Y210274I-1364J-787D01*
G03Y207948I2015J-1163D01*
G02Y206374I-1364J-787D01*
G03Y204048I2015J-1163D01*
G01X996806Y203641D01*
Y201193D01*
X997796Y200203D01*
Y198224D01*
G01X998586Y216909D02*
X997454Y214361D01*
G02X997221Y213798I-2248J601D01*
G03Y212224I1365J-787D01*
G02Y209898I-2015J-1163D01*
G03Y208324I1365J-787D01*
G02Y205998I-2015J-1163D01*
G03Y204424I1365J-787D01*
G01X997353Y204195D01*
X997600Y203948D01*
Y202400D01*
X999796Y200204D01*
Y198928D01*
G01X1015485Y218860D02*
X1015073Y218447D01*
G03X1014432Y216901I1546J-1547D01*
G02X1014145Y215789I-2326J7D01*
G01X1014120Y215747D01*
X1014101Y215713D01*
G03X1014120Y214172I1384J-754D01*
G01X1014756Y213071D01*
Y205148D01*
X1013866Y203608D01*
Y201865D01*
X1021353Y194378D01*
Y191247D01*
X1020789Y190683D01*
Y189211D01*
X1020954Y189046D01*
G01X1022245Y222760D02*
X1021091Y223426D01*
X1020781Y223342D01*
G03X1020880Y221974I1464J-582D01*
G02Y219648I-2015J-1163D01*
G03Y218074I1365J-787D01*
G02Y215748I-2015J-1163D01*
G03Y214174I1365J-787D01*
G02X1020881Y211849I-2015J-1163D01*
G01X1020880D01*
G03X1020669Y211016I1365J-789D01*
G01Y202114D01*
X1026250Y196533D01*
Y192850D01*
X1027350Y191750D01*
Y189250D01*
X1027554Y189046D01*
G01X1015485Y222760D02*
X1014331Y223425D01*
X1014021Y223341D01*
G03X1013910Y222785I1465J-581D01*
G03X1015426Y221185I1576J-25D01*
G01X1015555D01*
G02X1017500Y217697I-70J-2325D01*
G03X1017481Y216156I1365J-787D01*
G01X1017528Y216072D01*
X1017525Y216080D01*
G02X1017501Y213798I-2040J-1120D01*
G01X1017267Y213394D01*
X1017266Y212399D01*
Y207623D01*
X1017900Y206989D01*
Y201499D01*
X1023700Y195699D01*
Y192001D01*
X1024086Y191615D01*
Y189014D01*
X1024254Y188846D01*
G01X1019894Y188926D02*
Y189013D01*
X1020039Y189158D01*
Y190994D01*
X1020603Y191558D01*
Y194067D01*
X1013116Y201554D01*
Y203810D01*
X1014006Y205350D01*
Y212869D01*
X1013470Y213797D01*
G02X1013445Y216080I2015J1164D01*
G01X1013470Y216122D01*
X1013489Y216156D01*
G03X1013680Y216904I-1385J752D01*
G03X1013569Y217491I-1576J6D01*
G01X1013259Y217575D01*
X1012105Y216909D01*
G01X1018865Y224709D02*
X1019315Y224259D01*
G02X1019918Y222803I-1456J-1456D01*
G03X1020230Y221598I2326J-41D01*
G02Y220024I-1365J-787D01*
G03Y217698I2015J-1163D01*
G02Y216124I-1365J-787D01*
G03Y213798I2015J-1163D01*
G01X1020231D01*
G02X1020250Y212258I-1366J-787D01*
G03X1019919Y211006I1995J-1197D01*
G01Y201803D01*
X1025500Y196222D01*
Y192539D01*
X1026600Y191439D01*
Y189119D01*
X1026494Y189013D01*
Y188926D01*
G01X1012105Y224709D02*
X1012551Y224264D01*
G02X1013158Y222797I-1467J-1466D01*
G03X1015400Y220435I2327J-37D01*
G01X1015529D01*
G02X1016850Y218072I-44J-1575D01*
G03X1016825Y215789I2015J-1164D01*
G01X1016850Y215747D01*
X1016869Y215713D01*
G02X1016850Y214173I-1384J-753D01*
G01X1016517Y213595D01*
X1016516Y213246D01*
Y207312D01*
X1017150Y206678D01*
Y201188D01*
X1022950Y195388D01*
Y191690D01*
X1023336Y191304D01*
Y188955D01*
X1023194Y188813D01*
Y188726D01*
G01X1008725Y211060D02*
X1009500Y209062D01*
Y204000D01*
X1010486Y203014D01*
Y199014D01*
X1015700Y193800D01*
Y192683D01*
G01X1017700Y192974D02*
Y193800D01*
X1011500Y200000D01*
Y203529D01*
X1010529Y204500D01*
Y209099D01*
G02X1010740Y209898I1576J11D01*
G01X1012105Y213009D01*
G01X1008725Y218860D02*
X1007428Y215864D01*
X1007341Y215713D01*
G03X1007360Y214172I1384J-754D01*
G02X1007385Y211889I-2015J-1164D01*
G01X1007360Y211847D01*
X1007341Y211813D01*
G03X1007360Y210272I1384J-754D01*
G01X1007863Y209400D01*
G02X1008398Y207400I-3469J-2000D01*
G01Y203500D01*
X1009500Y202398D01*
Y198000D01*
X1013700Y193800D01*
Y192561D01*
G01X1005345Y216909D02*
X1006644Y213910D01*
X1006710Y213797D01*
G02X1006729Y212256I-1365J-787D01*
G01X1006710Y212222D01*
X1006685Y212180D01*
G03X1006710Y209897I2040J-1119D01*
G02X1007171Y208177I-2977J-1720D01*
G01Y203294D01*
X1008500Y201965D01*
Y197100D01*
X1011700Y193900D01*
Y192853D01*
G01X1009700D02*
Y194000D01*
X1007500Y196200D01*
Y200501D01*
X1003700Y204301D01*
Y208853D01*
G02X1003980Y209897I2088J0D01*
G03X1004005Y212180I-2015J1164D01*
G01X1003980Y212222D01*
X1003961Y212256D01*
G02X1003980Y213797I1384J754D01*
G03X1004005Y216080I-2015J1164D01*
G01X1003980Y216122D01*
X1003961Y216156D01*
G02X1005286Y218484I1384J753D01*
G01X1005415D01*
G03X1007360Y219647I-70J2325D01*
G01X1007428Y219764D01*
X1008725Y222760D01*
G01X1005345Y224709D02*
G03X1003591Y222423I7812J-7810D01*
G01X1003330Y221972D01*
G03X1003305Y219689I2015J-1164D01*
G01X1003330Y219647D01*
X1003349Y219613D01*
G02X1003330Y218072I-1384J-754D01*
G03X1003305Y215789I2015J-1164D01*
G01X1003330Y215747D01*
X1003349Y215713D01*
G02X1003330Y214172I-1384J-754D01*
G03X1003305Y211889I2015J-1164D01*
G01X1003330Y211847D01*
X1003349Y211813D01*
G02X1003330Y210272I-1384J-754D01*
G03X1002900Y208665I2787J-1607D01*
G01Y203100D01*
X1005796Y200204D01*
Y198807D01*
G01X1001796Y199049D02*
Y200204D01*
X1000206Y201794D01*
Y208094D01*
X1000200Y208100D01*
Y208964D01*
G03X999950Y209896I-1864J0D01*
G02X999915Y212162I2015J1164D01*
G01X999950Y212222D01*
G03Y213796I-1364J787D01*
G02X999915Y216062I2015J1164D01*
G01X999950Y216122D01*
G03Y217696I-1364J787D01*
G02X999915Y219962I2015J1164D01*
G01X999950Y220022D01*
G03Y221596I-1364J787D01*
G02X999915Y223862I2015J1164D01*
G01X999950Y223922D01*
G03Y225496I-1364J787D01*
G01X999887Y225603D01*
X998586Y228610D01*
G01X1003796Y198734D02*
Y200104D01*
X1001100Y202800D01*
Y208410D01*
G03X1000601Y210273I-3728J0D01*
G02Y211847I1364J787D01*
G01X1000636Y211907D01*
G03X1000601Y214173I-2050J1102D01*
G02Y215747I1364J787D01*
G01X1000636Y215807D01*
G03X1000601Y218073I-2050J1102D01*
G02Y219647I1364J787D01*
G01X1000636Y219707D01*
G03X1000601Y221973I-2050J1102D01*
G02Y223547I1364J787D01*
G01X1000636Y223607D01*
G03X1000601Y225873I-2050J1102D01*
G02Y227447I1364J787D01*
G01X1001591Y229163D01*
G03X1001965Y230559I-2419J1396D01*
G01X1025625Y213009D02*
X1025638D01*
X1027206Y211441D01*
Y201864D01*
X1032122Y196948D01*
Y195289D01*
G01X1035327Y200166D02*
Y202173D01*
X1032050Y205450D01*
G02X1031093Y206696I4269J4270D01*
G01X1030370Y207946D01*
G03X1030047Y208340I-1364J-789D01*
G01X1029088Y209954D01*
X1028500Y211177D01*
X1026990Y213797D01*
G02X1026965Y216080I2015J1164D01*
G01X1026990Y216122D01*
X1027009Y216156D01*
G03X1026990Y217697I-1384J754D01*
G02X1026965Y219980I2015J1164D01*
G01X1026990Y220022D01*
X1027009Y220056D01*
G03X1026990Y221597I-1384J754D01*
G01X1026924Y221710D01*
X1025625Y224709D01*
G01X1032385Y213009D02*
X1032394Y213000D01*
X1035988D01*
G02X1037780Y209897I0J-2069D01*
G03X1037761Y208356I1365J-787D01*
G01X1037780Y208322D01*
X1038300Y207502D01*
Y205000D01*
X1041790Y201510D01*
Y198006D01*
X1040892Y197108D01*
Y194246D01*
X1041634Y193504D01*
Y192547D01*
G01X1033744Y195798D02*
Y197536D01*
X1029005Y202275D01*
Y207159D01*
G01X1032385Y224709D02*
X1030700Y220900D01*
Y212400D01*
X1031700Y211400D01*
X1033350Y210550D01*
X1034106Y209794D01*
Y206494D01*
X1038614Y201986D01*
Y191891D01*
G01X1029005Y222760D02*
X1028100Y221855D01*
Y221385D01*
G02X1027665Y219689I-3524J0D01*
G01X1027640Y219647D01*
X1027621Y219613D01*
G03X1027640Y218072I1384J-754D01*
G02X1027665Y215789I-2015J-1164D01*
G01X1027640Y215747D01*
X1027621Y215713D01*
G03X1027640Y214172I1384J-754D01*
G01X1029553Y210853D01*
X1030454Y209300D01*
X1030911Y208511D01*
X1031285Y207864D01*
G03X1033100Y205500I9909J5729D01*
G01X1037104Y201496D01*
Y199996D01*
G01X998586Y380709D02*
X997289Y383705D01*
X997202Y383856D01*
G02X997221Y385397I1384J754D01*
G03Y387723I-2015J1163D01*
G02Y389297I1365J787D01*
G03Y391623I-2015J1163D01*
G01X996996Y392013D01*
Y393310D01*
X1002500Y398814D01*
Y404000D01*
X1000398Y406102D01*
Y407015D01*
G01X1025625Y372909D02*
X1026922Y375905D01*
X1026990Y376022D01*
G02X1028935Y377185I2015J-1162D01*
G01X1029064D01*
G03X1030389Y379513I-59J1575D01*
G01X1030370Y379547D01*
X1030345Y379589D01*
G02X1030370Y381872I2040J1119D01*
G03X1030389Y383413I-1365J787D01*
G01X1030370Y383447D01*
X1030345Y383489D01*
G02X1030370Y385772I2040J1119D01*
G03X1030389Y387313I-1365J787D01*
G01X1030370Y387347D01*
X1030345Y387389D01*
G02X1030370Y389672I2040J1119D01*
G03X1030700Y391000I-2142J1237D01*
G01Y399404D01*
X1035400Y404104D01*
Y405592D01*
X1035800Y405992D01*
Y406737D01*
G01X995206Y367060D02*
X996504Y370057D01*
X996571Y370172D01*
G03X996780Y370953I-1354J781D01*
G01Y382592D01*
G03X996590Y383413I-1574J68D01*
G01X996571Y383447D01*
X996546Y383489D01*
G02X996571Y385772I2040J1119D01*
G03X996590Y387313I-1365J787D01*
G01X996571Y387347D01*
G02Y389673I2015J1163D01*
G03Y391247I-1365J787D01*
G01X996100Y392064D01*
Y393700D01*
X998398Y395998D01*
Y397365D01*
G01X1018865Y372909D02*
X1019605Y373649D01*
G03X1019933Y374592I-811J811D01*
G02X1020205Y375980I2311J268D01*
G01X1020230Y376022D01*
X1020249Y376056D01*
G03X1020230Y377597I-1384J754D01*
G02X1020205Y379880I2015J1164D01*
G01X1020230Y379922D01*
X1020249Y379956D01*
G03X1020230Y381497I-1384J754D01*
G02X1020205Y383780I2015J1164D01*
G01X1020230Y383822D01*
X1020249Y383856D01*
G03X1020230Y385397I-1384J754D01*
G02X1020205Y387680I2015J1164D01*
G01X1020230Y387722D01*
X1020249Y387756D01*
G03X1020230Y389297I-1384J754D01*
G02X1020205Y391577I2015J1162D01*
G01X1020207Y391580D01*
X1020335Y391808D01*
X1020450Y391999D01*
Y402350D01*
X1024982Y406882D01*
Y409228D01*
X1024852Y409358D01*
Y409402D01*
G01X1012105Y372909D02*
X1012927Y373730D01*
G03X1013184Y374513I-647J646D01*
G02X1015415Y377185I2300J347D01*
G01X1015544D01*
G03X1016869Y379513I-59J1575D01*
G01X1016850Y379547D01*
X1016825Y379589D01*
G02X1016850Y381872I2040J1119D01*
G03X1016869Y383413I-1365J787D01*
G01X1016850Y383447D01*
G02X1016425Y386037I3227J1859D01*
G01X1016450Y386160D01*
Y393482D01*
X1017850Y394882D01*
Y403411D01*
X1021950Y407511D01*
Y409249D01*
X1021820Y409379D01*
Y409466D01*
G01X1022245Y378760D02*
X1022659Y379175D01*
G03X1023298Y380716I-1541J1542D01*
G02X1023610Y381872I2327J-8D01*
G03X1023629Y383413I-1365J787D01*
G01X1023610Y383447D01*
X1023585Y383489D01*
G02X1023610Y385772I2040J1119D01*
G03X1023629Y387313I-1365J787D01*
G01X1023610Y387347D01*
X1023585Y387389D01*
G02X1023610Y389672I2040J1119D01*
G01X1023611Y389673D01*
G03X1023816Y390334I-1366J786D01*
G03X1023628Y391216I-1571J126D01*
G01X1023296Y391812D01*
Y401696D01*
X1028451Y406851D01*
Y409042D01*
X1028274Y409219D01*
Y409306D01*
G01X1012105Y380709D02*
X1013259Y380044D01*
X1013569Y380128D01*
G03X1013674Y380566I-1465J583D01*
G03X1013470Y381497I-1570J144D01*
G02X1013376Y383645I2015J1164D01*
G02X1013445Y383780I2105J-991D01*
G01X1013470Y383822D01*
G03X1013794Y384756I-2274J1312D01*
G01Y394455D01*
X1015350Y396011D01*
Y404410D01*
X1018650Y407710D01*
Y409296D01*
X1018518Y409428D01*
Y409472D01*
G01X1022245Y374860D02*
X1021091Y374194D01*
X1020781Y374278D01*
G02X1020680Y374679I1465J582D01*
G02X1020861Y375613I1566J181D01*
G01X1020880Y375647D01*
X1020905Y375689D01*
G03X1020880Y377972I-2040J1119D01*
G02X1020861Y379513I1365J787D01*
G01X1020880Y379547D01*
X1020905Y379589D01*
G03X1020880Y381872I-2040J1119D01*
G02X1020861Y383413I1365J787D01*
G01X1020880Y383447D01*
X1020905Y383489D01*
G03X1020880Y385772I-2040J1119D01*
G02X1020861Y387313I1365J787D01*
G01X1020880Y387347D01*
X1020905Y387389D01*
G03X1020880Y389672I-2040J1119D01*
G02X1020860Y391211I1365J787D01*
G01X1020984Y391430D01*
X1021200Y391791D01*
Y402039D01*
X1025732Y406571D01*
Y409222D01*
X1025912Y409402D01*
G01X1015485Y374860D02*
X1014331Y374194D01*
X1014021Y374278D01*
G02X1013927Y374625I1464J583D01*
G02X1015441Y376435I1558J235D01*
G01X1015570D01*
G03X1017525Y379880I-85J2325D01*
G01X1017500Y379922D01*
X1017481Y379956D01*
G02X1017500Y381497I1384J754D01*
G03X1017525Y383780I-2015J1164D01*
G01X1017500Y383822D01*
G02X1017161Y385889I2577J1484D01*
G01X1017200Y386084D01*
Y393171D01*
X1018600Y394571D01*
Y403100D01*
X1022700Y407200D01*
Y409166D01*
X1022880Y409346D01*
Y409466D01*
G01X1025625Y380709D02*
X1024471Y380044D01*
X1024161Y380128D01*
G02X1024050Y380714I1465J581D01*
G02X1024260Y381497I1576J-3D01*
G03X1024285Y383780I-2015J1164D01*
G01X1024260Y383822D01*
X1024241Y383856D01*
G02X1024260Y385397I1384J754D01*
G03X1024285Y387680I-2015J1164D01*
G01X1024260Y387722D01*
X1024241Y387756D01*
G02X1024260Y389297I1384J754D01*
G03X1024565Y390274I-2014J1165D01*
G03X1024285Y391579I-2320J185D01*
G01X1024046Y392007D01*
Y401385D01*
X1029201Y406540D01*
Y409053D01*
X1029334Y409186D01*
G01X1019578Y409511D02*
Y409395D01*
X1019400Y409217D01*
Y407399D01*
X1016100Y404099D01*
Y395700D01*
X1014544Y394144D01*
Y384705D01*
G02X1014118Y383442I-3349J426D01*
G01X1014101Y383413D01*
G03X1014057Y383327I1381J-761D01*
G03X1014120Y381872I1428J-667D01*
G02X1014422Y380498I-2015J-1163D01*
G03X1014805Y379440I1321J-120D01*
G01X1015485Y378760D01*
G01X1032385Y384609D02*
X1034100Y386324D01*
Y389900D01*
X1035700Y391500D01*
Y400600D01*
X1038600Y403500D01*
Y404566D01*
X1039800Y405766D01*
Y406540D01*
G01X1029005Y386560D02*
G02X1027952Y388500I1261J1940D01*
G03X1027935Y388792I-2327J11D01*
G03X1027883Y389071I-2309J-286D01*
G03X1027640Y389672I-2258J-563D01*
G02X1027621Y391213I1365J787D01*
G01X1027640Y391247D01*
G03X1028500Y392900I-27238J15221D01*
G03X1028800Y394211I-2715J1311D01*
G01Y399304D01*
X1033800Y404304D01*
Y406734D01*
G01X1032385Y372909D02*
X1033682Y375905D01*
X1033769Y376056D01*
G03X1033750Y377597I-1384J754D01*
G02X1033725Y379880I2015J1164D01*
G01X1033750Y379922D01*
X1033769Y379956D01*
G03X1033750Y381497I-1384J754D01*
G02X1035695Y384985I2015J1163D01*
G01X1035824D01*
G03X1037340Y386596I-59J1575D01*
G01Y389040D01*
X1038350Y390050D01*
Y397150D01*
X1043100Y401900D01*
Y405000D01*
X1043800Y405700D01*
Y406684D01*
G01X1029005Y374860D02*
G03X1030812Y376905I-254J2045D01*
G02X1031020Y377597I1573J-96D01*
G03X1031045Y379880I-2015J1164D01*
G01X1031020Y379922D01*
X1031001Y379956D01*
G02X1031020Y381497I1384J754D01*
G03X1031045Y383780I-2015J1164D01*
G01X1031020Y383822D01*
X1031001Y383856D01*
G02X1031020Y385397I1384J754D01*
G03X1031045Y387680I-2015J1164D01*
G01X1031020Y387722D01*
X1031001Y387756D01*
G02X1031020Y389297I1384J754D01*
G02X1031700Y390400I19055J-10986D01*
G01Y398400D01*
X1037120Y403820D01*
Y405216D01*
X1037800Y405896D01*
Y406629D01*
G01X1008725Y386560D02*
Y387880D01*
X1009326Y388481D01*
Y395626D01*
X1011626Y397926D01*
Y404625D01*
X1014398Y407397D01*
Y408465D01*
G01X1012105Y384609D02*
X1010526Y388040D01*
Y394726D01*
X1012826Y397026D01*
Y404227D01*
X1016398Y407799D01*
Y408694D01*
G01X1008725Y378760D02*
X1007426Y381759D01*
X1007360Y381872D01*
G02X1007341Y383413I1365J787D01*
G01X1007360Y383447D01*
X1007385Y383489D01*
G03X1007360Y385772I-2040J1119D01*
G02X1007666Y387727I1365J788D01*
G03X1008200Y388600I-1223J1348D01*
G01Y396300D01*
X1010426Y398526D01*
Y405327D01*
X1012398Y407299D01*
Y408331D01*
G01X1005345Y380709D02*
X1006642Y383705D01*
X1006729Y383856D01*
G03X1006710Y385397I-1384J754D01*
G02X1007039Y388163I2015J1163D01*
G03X1007200Y388700I-450J427D01*
G01Y397400D01*
X1009226Y399426D01*
Y406326D01*
X1010398Y407498D01*
Y408385D01*
G01X1008725Y374860D02*
X1007426Y377859D01*
X1007360Y377972D01*
G03X1005430Y379134I-2015J-1163D01*
G01X1005301D01*
G02X1003980Y381497I44J1575D01*
G03X1004005Y383780I-2015J1164D01*
G01X1003980Y383822D01*
X1003961Y383856D01*
G02X1003980Y385397I1384J754D01*
G03X1004005Y387680I-2015J1164D01*
G01X1003980Y387722D01*
X1003771Y388096D01*
Y394271D01*
X1006021Y396521D01*
Y405321D01*
X1008398Y407698D01*
Y408586D01*
G01X1005345Y372909D02*
X1006533Y375642D01*
G02X1006685Y375980I2191J-782D01*
G01X1006710Y376022D01*
X1006729Y376056D01*
G03X1005404Y378384I-1384J753D01*
G01X1005275D01*
G02X1003330Y381872I70J2325D01*
G03X1003349Y383413I-1365J787D01*
G01X1003330Y383447D01*
X1003305Y383489D01*
G02X1003330Y385772I2040J1119D01*
G03X1003349Y387313I-1365J787D01*
G01X1002576Y388695D01*
Y394576D01*
X1005271Y397271D01*
Y406071D01*
X1006398Y407198D01*
Y407982D01*
G01X998586Y369010D02*
G02X999726Y371593I3496J0D01*
G02X999950Y372122I2238J-636D01*
G03Y373696I-1364J787D01*
G02X999915Y375962I2015J1164D01*
G01X999950Y376022D01*
G03Y377596I-1364J787D01*
G02X999915Y379862I2015J1164D01*
G01X999950Y379922D01*
G03Y381496I-1364J787D01*
G02X999915Y383762I2015J1164D01*
G01X999950Y383822D01*
G03Y385396I-1364J787D01*
G02X999915Y387662I2015J1164D01*
G01X999950Y387722D01*
G03X1000372Y388570I-6161J3595D01*
G01Y395372D01*
X1003500Y398500D01*
Y405250D01*
X1002398Y406352D01*
Y407700D01*
G01X1001965Y367060D02*
X1000666Y370060D01*
X1000601Y370172D01*
G02Y371746I1364J787D01*
G01X1000626Y371788D01*
G03X1000601Y374073I-2040J1120D01*
G02Y375647I1364J787D01*
G01X1000636Y375707D01*
G03X1000601Y377973I-2050J1102D01*
G02Y379547I1364J787D01*
G01X1000636Y379607D01*
G03X1000601Y381873I-2050J1102D01*
G02Y383447I1364J787D01*
G01X1000636Y383507D01*
G03X1000601Y385773I-2050J1102D01*
G02Y387347I1364J787D01*
G02X1001000Y388000I13170J-7599D01*
G03X1001500Y389200I-3068J1983D01*
G01Y395000D01*
X1004398Y397898D01*
Y407727D01*
G01X1025625Y384609D02*
X1026922Y387605D01*
X1027009Y387756D01*
G03X1026990Y389297I-1384J754D01*
G02Y391623I2015J1163D01*
G03X1027600Y393900I-3945J2277D01*
G01Y399864D01*
X1031800Y404064D01*
Y407043D01*
G01X1035765Y222760D02*
X1037062Y219764D01*
X1037130Y219647D01*
G03X1039075Y218484I2015J1162D01*
G01X1039145D01*
G02X1040496Y217719I0J-1575D01*
G01X1040509Y217696D01*
G03X1042426Y216535I2015J1164D01*
G01X1042568D01*
G02X1043889Y214172I-44J-1575D01*
G03X1043864Y211889I2015J-1164D01*
G01X1043889Y211847D01*
X1043908Y211813D01*
G02X1043889Y210272I-1384J-754D01*
G03X1043500Y208819I2521J-1453D01*
G01Y207900D01*
G03X1043854Y207044I1210J-1D01*
G01X1046300Y204599D01*
Y201324D01*
X1047522Y200102D01*
Y195410D01*
G01X1049284Y218860D02*
X1052358Y215786D01*
Y198358D01*
X1053961Y196755D01*
Y195531D01*
G01X1035765Y218860D02*
X1037062Y215864D01*
X1037130Y215747D01*
G03X1039075Y214584I2015J1162D01*
G01X1039145D01*
G02X1040509Y212222I0J-1575D01*
G01X1040474Y212162D01*
G03X1040509Y209896I2050J-1102D01*
G01X1040541Y209840D01*
G02X1040719Y209191I-1396J-732D01*
G01Y207481D01*
X1044216Y203984D01*
Y200020D01*
X1043537Y199341D01*
Y196308D01*
X1044216Y195629D01*
Y194462D01*
X1043556Y193802D01*
Y192984D01*
G01X1042524Y222760D02*
X1044473Y220138D01*
X1044539Y220022D01*
G03X1045860Y219234I1365J787D01*
G01X1045904D01*
G02X1046621Y218820I0J-828D01*
G01X1047269Y217697D01*
G02X1047288Y216156I-1365J-787D01*
G01X1047269Y216122D01*
X1047244Y216080D01*
G03X1049199Y212635I2040J-1120D01*
G01X1049954D01*
X1050858Y211731D01*
Y195652D01*
G01X1045904Y228610D02*
X1047853Y225987D01*
X1047919Y225872D01*
G02X1047944Y223589I-2015J-1164D01*
G01X1047919Y223547D01*
X1047900Y223513D01*
G03X1049225Y221185I1384J-753D01*
G01X1049415D01*
X1053108Y217492D01*
Y202893D01*
X1055600Y200401D01*
Y194366D01*
G01X1035765Y211060D02*
X1037064Y208060D01*
X1037346Y207573D01*
Y204455D01*
X1039800Y202001D01*
Y193501D01*
X1040124Y193177D01*
Y192316D01*
G01X1039145Y224709D02*
X1041099Y222081D01*
X1041160Y221973D01*
G02X1041195Y219707I-2015J-1164D01*
G01X1041160Y219647D01*
G03X1042524Y217285I1364J-787D01*
G01X1042594D01*
G02X1044539Y213797I-70J-2325D01*
G03X1044520Y212256I1365J-787D01*
G01X1044539Y212222D01*
X1044564Y212180D01*
G02X1044539Y209897I-2040J-1119D01*
G03X1044250Y208818I1871J-1079D01*
G01Y208500D01*
G03X1044497Y207902I845J-1D01*
G01X1047200Y205200D01*
Y201486D01*
X1049145Y199541D01*
Y195507D01*
G01X1057225Y194172D02*
Y195275D01*
X1056500Y196000D01*
Y201500D01*
X1054500Y203500D01*
Y216499D01*
X1054910Y216909D01*
X1057314D01*
G01X1058763Y194050D02*
Y195737D01*
X1057500Y197000D01*
Y202000D01*
X1055500Y204000D01*
Y209500D01*
X1059000Y216500D01*
Y217526D01*
X1058026Y218500D01*
X1049284Y222760D01*
G01X1039145Y216909D02*
X1040040Y215813D01*
X1040845Y214730D01*
X1041160Y214173D01*
G02X1041195Y211907I-2015J-1164D01*
G01X1041160Y211847D01*
G03Y210273I1364J-787D01*
G01X1041700Y209284D01*
Y208000D01*
X1043549Y206151D01*
X1043550D01*
X1045300Y204401D01*
Y199818D01*
X1044302Y198820D01*
Y196683D01*
X1045357Y195628D01*
Y192972D01*
G01X1045904Y224709D02*
X1047203Y221710D01*
X1047269Y221597D01*
G02X1047288Y220056I-1365J-787D01*
G01X1047269Y220022D01*
G03Y219198I714J-412D01*
G01X1047919Y218072D01*
G02X1047944Y215789I-2015J-1164D01*
G01X1047919Y215747D01*
X1047900Y215713D01*
G03X1049225Y213385I1384J-753D01*
G01X1050315D01*
X1051608Y212092D01*
Y197483D01*
X1052414Y196677D01*
Y195555D01*
G01X1065242Y220096D02*
Y218765D01*
X1064984Y218507D01*
G03X1063284Y217450I258J-2311D01*
G01X1063232Y217360D01*
G03X1063207Y215075I2010J-1165D01*
G01X1063232Y215033D01*
X1063290Y214934D01*
G03X1065242Y213871I1952J1261D01*
G01X1065702D01*
G02X1066678Y213090I-460J-1575D01*
G02X1066697Y211537I-1436J-794D01*
G01X1066654Y211460D01*
G03X1066678Y209190I2118J-1113D01*
G01X1066817Y208940D01*
Y200499D01*
X1069805Y197511D01*
Y192370D01*
X1070924Y191251D01*
Y182253D01*
X1072666Y180511D01*
Y179166D01*
X1071998Y178498D01*
G01X1074498Y178501D02*
X1073414Y179585D01*
Y180821D01*
X1071672Y182563D01*
Y191561D01*
X1070556Y192677D01*
Y192679D01*
X1070554Y192681D01*
Y197824D01*
X1067565Y200813D01*
Y209141D01*
X1067336Y209554D01*
G02Y211140I1436J793D01*
G01X1067360Y211183D01*
G03X1066616Y214254I-2118J1113D01*
G03X1066364Y214409I-1353J-1917D01*
G03X1065806Y214621I-1122J-2112D01*
G01X1065242D01*
G02X1063939Y215311I0J1575D01*
G01X1063863Y215444D01*
G02X1063882Y216983I1379J753D01*
G01X1063936Y217076D01*
G02X1065015Y217754I1306J-881D01*
G01X1065242Y217527D01*
Y216196D01*
G01X1075582Y222047D02*
Y223378D01*
X1075810Y223606D01*
G02X1076947Y222834I-228J-1559D01*
G03X1078892Y221671I2015J1162D01*
G01X1078962D01*
G02X1080326Y219309I0J-1575D01*
G01X1080291Y219249D01*
G03X1080326Y216983I2050J-1102D01*
G02Y215409I-1364J-787D01*
G01X1080284Y215336D01*
G03X1080326Y213082I2057J-1089D01*
G01X1080537Y212717D01*
Y206291D01*
X1081936Y204892D01*
Y195601D01*
X1083048Y194489D01*
Y190413D01*
X1091184Y182277D01*
Y180697D01*
X1090318Y179831D01*
G01X1075582Y225947D02*
Y224616D01*
X1075839Y224359D01*
G02X1077597Y223209I-257J-2312D01*
G03X1078918Y222421I1365J787D01*
G01X1079060D01*
G02X1081012Y218994I-98J-2325D01*
G01X1080977Y218934D01*
G03Y217360I1364J-787D01*
G02X1081012Y215094I-2015J-1164D01*
G01X1080977Y215034D01*
X1080958Y215000D01*
G03X1080977Y213459I1383J-754D01*
G01X1081285Y212925D01*
Y206604D01*
X1082686Y205203D01*
Y195909D01*
X1083796Y194799D01*
Y190723D01*
X1091932Y182587D01*
Y180717D01*
X1092818Y179831D01*
G01X1065242Y227896D02*
X1060806Y223460D01*
Y205441D01*
X1063799Y202448D01*
Y199202D01*
X1066786Y196215D01*
Y190825D01*
X1067906Y189705D01*
Y179406D01*
X1067274Y178774D01*
G01X1065242Y231797D02*
G03X1066757Y228684I22931J9235D01*
G02Y227110I-1365J-787D01*
G01X1065308Y225661D01*
X1064074D01*
X1061556Y223143D01*
Y205753D01*
X1061554Y205751D01*
X1064547Y202758D01*
Y199558D01*
X1064552Y199552D01*
X1067533Y196572D01*
X1067535D01*
Y191134D01*
X1068654Y190015D01*
Y179345D01*
X1069498Y178501D01*
G01X1072202Y220096D02*
Y221427D01*
X1072430Y221655D01*
G02X1073567Y220884I-228J-1560D01*
G03X1075497Y219722I2015J1163D01*
G01X1075626D01*
G02X1076947Y217359I-44J-1575D01*
G03Y215033I2015J-1163D01*
G02Y213457I-1365J-788D01*
G03Y211131I2015J-1163D01*
G01X1077527Y210125D01*
Y205270D01*
X1078916Y203881D01*
Y195393D01*
X1080030Y194279D01*
Y189163D01*
X1086026Y183167D01*
Y180551D01*
X1085306Y179831D01*
G01X1072202Y227896D02*
Y227897D01*
X1074152Y225273D01*
X1074217Y225160D01*
G02Y222834I-2015J-1163D01*
G03X1075523Y220472I1364J-788D01*
G01X1075652D01*
G02X1077597Y216984I-70J-2325D01*
G03Y215408I1365J-788D01*
G02Y213082I-2015J-1163D01*
G03Y211506I1365J-788D01*
G01X1078277Y210327D01*
Y205581D01*
X1079666Y204192D01*
Y195701D01*
X1080778Y194589D01*
Y189473D01*
X1086774Y183477D01*
Y180875D01*
X1087818Y179831D01*
G01X1068822Y218147D02*
Y219478D01*
X1068594Y219706D01*
G03X1068763Y216572I227J-1559D01*
G01X1068906D01*
G02X1070837Y215411I-83J-2325D01*
G01X1071147Y214874D01*
Y209121D01*
X1070664Y208638D01*
Y204351D01*
X1073626Y201389D01*
Y193262D01*
X1074740Y192148D01*
Y186925D01*
X1078234Y183431D01*
Y179283D01*
X1078389Y179128D01*
Y179041D01*
G01X1068822Y225947D02*
Y227278D01*
X1069050Y227506D01*
G02X1069520Y227359I-229J-1559D01*
G02X1070187Y225160I-698J-1412D01*
G03Y222834I2015J-1163D01*
G02Y221260I-1365J-787D01*
G03X1072117Y217772I2015J-1163D01*
G01X1072246D01*
G02X1073777Y216139I-44J-1575D01*
G01Y208792D01*
X1073084Y208099D01*
Y205141D01*
X1075896Y202329D01*
Y194385D01*
X1077010Y193271D01*
Y187912D01*
X1081822Y183100D01*
Y179737D01*
X1081667Y179582D01*
Y179495D01*
G01X1068822Y222047D02*
G02X1067160Y219786I-7767J3968D01*
G03X1068737Y215822I1577J-1668D01*
G01X1068891D01*
G02X1070187Y215035I-69J-1575D01*
G01X1070397Y214672D01*
Y209432D01*
X1069914Y208949D01*
Y204040D01*
X1072876Y201078D01*
Y192951D01*
X1073990Y191837D01*
Y186614D01*
X1077484Y183120D01*
Y179283D01*
X1077329Y179128D01*
Y179041D01*
G01X1068822Y229847D02*
X1069853Y228033D01*
G02X1070837Y224784I-1031J-2086D01*
G03Y223210I1365J-787D01*
G02Y220884I-2015J-1163D01*
G03X1072158Y218522I1365J-787D01*
G01X1072287D01*
G02X1074527Y216126I-85J-2325D01*
G01Y208481D01*
X1073834Y207788D01*
Y205452D01*
X1076646Y202640D01*
Y194696D01*
X1077760Y193582D01*
Y188223D01*
X1082572Y183411D01*
Y179737D01*
X1082727Y179582D01*
Y179495D01*
G01X1104300Y184800D02*
X1105270Y185770D01*
Y189600D01*
X1099600Y195270D01*
Y199300D01*
X1093301Y205599D01*
Y210532D01*
X1093865Y211543D01*
G03X1093884Y213084I-1365J787D01*
G01X1093865Y213118D01*
X1093840Y213160D01*
G02X1093865Y215443I2040J1119D01*
G03X1093846Y216984I-1384J754D01*
G02X1093821Y219267I2015J1164D01*
G01X1093846Y219309D01*
X1093865Y219343D01*
G03X1093846Y220884I-1384J754D01*
G02X1093821Y223167I2015J1164D01*
G01X1093846Y223209D01*
X1093865Y223243D01*
G03X1093846Y224784I-1384J754D01*
G02X1093821Y227067I2015J1164D01*
G01X1093846Y227109D01*
X1093865Y227143D01*
G03X1093846Y228684I-1384J754D01*
G02Y231010I2015J1163D01*
G01X1093911Y231124D01*
X1095861Y233746D01*
G01X1106800Y184900D02*
X1106020Y185680D01*
Y189912D01*
X1100350Y195582D01*
Y199611D01*
X1094051Y205910D01*
Y210336D01*
X1094521Y211176D01*
G03X1094546Y213459I-2015J1164D01*
G01X1094521Y213501D01*
X1094502Y213535D01*
G02X1094521Y215076I1384J754D01*
G03X1094496Y217359I-2040J1119D01*
G02X1094477Y218900I1365J787D01*
G01X1094496Y218934D01*
X1094521Y218976D01*
G03X1094496Y221259I-2040J1119D01*
G02X1094477Y222800I1365J787D01*
G01X1094496Y222834D01*
X1094521Y222876D01*
G03X1094496Y225159I-2040J1119D01*
G02X1094477Y226700I1365J787D01*
G01X1094496Y226734D01*
X1094521Y226776D01*
G03X1094707Y228573I-2040J1119D01*
G03X1094562Y228946I-2551J-777D01*
G01X1094496Y229059D01*
G02X1095349Y231337I1365J788D01*
G02X1096705Y232415I5692J-5768D01*
G03X1096941Y232598I-843J1331D01*
G03X1097226Y232959I-1081J1147D01*
G03Y234533I-1365J787D01*
G01X1097160Y234647D01*
G03X1095912Y236072I-4241J-2455D01*
G01X1095802D01*
G02X1094477Y238400I59J1575D01*
G01X1094564Y238551D01*
X1095861Y241547D01*
G01X1099300Y183700D02*
X1100230Y184630D01*
Y190300D01*
X1096450Y194080D01*
Y198090D01*
X1089800Y204740D01*
Y208410D01*
X1090484Y209590D01*
G03X1090466Y211134I-1383J756D01*
G02X1090441Y213417I2015J1164D01*
G01X1090466Y213459D01*
X1090485Y213493D01*
G03X1090466Y215034I-1384J754D01*
G01X1090441Y215076D01*
G02X1090466Y217359I2040J1119D01*
G03X1090485Y218900I-1365J787D01*
G01X1090466Y218934D01*
X1090441Y218976D01*
G02X1090466Y221259I2040J1119D01*
G03X1090485Y222800I-1365J787D01*
G01X1090466Y222834D01*
X1090441Y222876D01*
G02X1090466Y225159I2040J1119D01*
G03X1090485Y226700I-1365J787D01*
G01X1090466Y226734D01*
X1090441Y226776D01*
G02X1090466Y229059I2040J1119D01*
G03X1090485Y230600I-1365J787D01*
G01X1090466Y230634D01*
G02X1090441Y232917I2015J1164D01*
G01X1090466Y232959D01*
X1090532Y233075D01*
X1092481Y235696D01*
G01X1101800Y184000D02*
X1101104Y184696D01*
Y190488D01*
X1097200Y194392D01*
Y198401D01*
X1090600Y205001D01*
Y208263D01*
X1090605Y208268D01*
X1091141Y209226D01*
G03X1091116Y211509I-2040J1119D01*
G02X1091097Y213050I1365J787D01*
G01X1091116Y213084D01*
X1091141Y213126D01*
G03X1091116Y215409I-2040J1119D01*
G01X1091097Y215443D01*
G02X1091116Y216984I1384J754D01*
G03X1091141Y219267I-2015J1164D01*
G01X1091116Y219309D01*
X1091097Y219343D01*
G02X1091116Y220884I1384J754D01*
G03X1091141Y223167I-2015J1164D01*
G01X1091116Y223209D01*
X1091097Y223243D01*
G02X1091116Y224784I1384J754D01*
G03X1091141Y227067I-2015J1164D01*
G01X1091116Y227109D01*
X1091097Y227143D01*
G02X1091116Y228684I1384J754D01*
G03Y231010I-2015J1163D01*
G02Y232584I1365J787D01*
G01X1091162Y232664D01*
X1091725Y233420D01*
G02X1092792Y233956I1067J-794D01*
G03X1093492Y234246I0J990D01*
G01X1093560Y234314D01*
G03X1093846Y236484I-1272J1271D01*
G01X1093780Y236597D01*
X1092481Y239596D01*
G01X1035765Y374860D02*
X1037064Y377859D01*
X1037130Y377972D01*
G02X1039060Y379134I2015J-1163D01*
G01X1039145D01*
G03X1040496Y379899I0J1575D01*
G01X1040509Y379922D01*
G02X1042454Y381085I2015J-1162D01*
G01X1042583D01*
G03X1043908Y383413I-59J1575D01*
G01X1043889Y383447D01*
X1043864Y383489D01*
G02X1043889Y385772I2040J1119D01*
G03X1043908Y387313I-1365J787D01*
G01X1043889Y387347D01*
X1043864Y387389D01*
G02X1043889Y389672I2040J1119D01*
G03X1044100Y390459I-1363J787D01*
G01Y392500D01*
X1046500Y394900D01*
Y403500D01*
X1049800Y406800D01*
Y407615D01*
G01X1049284Y378760D02*
X1050500Y379976D01*
Y381100D01*
X1055600Y386200D01*
Y399100D01*
X1058300Y401800D01*
Y403716D01*
X1057800Y404216D01*
Y405358D01*
G01X1045904Y369010D02*
X1050010D01*
X1052000Y371000D01*
X1054300D01*
X1057500Y374200D01*
Y381788D01*
X1059100Y383388D01*
Y396200D01*
X1063200Y400300D01*
Y405292D01*
X1063800Y405892D01*
Y406826D01*
G01X1035765Y386560D02*
Y389265D01*
X1037250Y390750D01*
Y399950D01*
X1039700Y402400D01*
Y403700D01*
X1041800Y405800D01*
Y406612D01*
G01X1039145Y372909D02*
X1041096Y375534D01*
X1041173Y375670D01*
G02X1042524Y376435I1351J-810D01*
G01X1042609D01*
G03X1044564Y379880I-85J2325D01*
G01X1044539Y379922D01*
X1044520Y379956D01*
G02X1044539Y381497I1384J754D01*
G03X1044564Y383780I-2015J1164D01*
G01X1044539Y383822D01*
X1044520Y383856D01*
G02X1044539Y385397I1384J754D01*
G03X1044564Y387680I-2015J1164D01*
G01X1044539Y387722D01*
X1044520Y387756D01*
G02X1044539Y389297I1384J754D01*
G02X1045469Y390435I3936J-2268D01*
G01X1045500Y390466D01*
Y391900D01*
X1047700Y394100D01*
Y400200D01*
X1049800Y402300D01*
Y404700D01*
X1051800Y406700D01*
Y407687D01*
G01X1052664Y380709D02*
X1057000Y385045D01*
Y398400D01*
X1060300Y401700D01*
Y404365D01*
X1059800Y404865D01*
Y405805D01*
G01X1049284Y374860D02*
X1052980D01*
X1055100Y376980D01*
Y381460D01*
X1058100Y384460D01*
Y397400D01*
X1061800Y401100D01*
Y406100D01*
G01X1073322Y389747D02*
X1071410D01*
X1070997Y390160D01*
Y403334D01*
X1074719Y407056D01*
Y417608D01*
X1073816Y418511D01*
G01X1073322Y393647D02*
X1072070D01*
X1071747Y393970D01*
Y403026D01*
X1075467Y406746D01*
Y417672D01*
X1076316Y418521D01*
G01X1083462Y383896D02*
X1083287D01*
G02X1082316Y385194I0J1012D01*
G03X1082122Y386967I-2222J654D01*
G02X1081998Y387215I1375J842D01*
G02X1082869Y389256I1463J582D01*
G01X1083682Y390069D01*
G02X1083863Y390173I283J-283D01*
G03X1084813Y390886I-401J1524D01*
G01X1084826Y390909D01*
G02X1086771Y392072I2015J-1162D01*
G01X1086900D01*
G03X1088233Y394385I-59J1575D01*
G01X1087896Y394968D01*
Y396541D01*
X1087898Y396543D01*
Y403757D01*
X1092161Y408020D01*
Y408851D01*
X1091426Y409586D01*
Y410424D01*
G01X1084646Y389694D02*
G03X1085477Y390534I-1184J2002D01*
G01X1085490Y390557D01*
G02X1086841Y391322I1351J-810D01*
G01X1086926D01*
G03X1088881Y394767I-85J2325D01*
G01X1088646Y395169D01*
Y403447D01*
X1092909Y407710D01*
Y408664D01*
X1093926Y409681D01*
G01X1083462Y387796D02*
G02X1084493Y389604I2100J0D01*
G01D02*
X1084646Y389694D01*
G01X1073322Y378047D02*
X1071546D01*
X1070999Y378594D01*
Y385518D01*
X1068147Y388370D01*
Y404512D01*
X1069749Y406114D01*
Y416909D01*
X1068816Y417842D01*
G01X1073322Y381947D02*
X1071994D01*
X1071747Y382194D01*
Y385828D01*
X1068898Y388677D01*
Y389969D01*
X1068897Y389970D01*
Y404204D01*
X1070499Y405806D01*
Y417264D01*
X1071316Y418081D01*
G01X1080082Y381947D02*
X1078783Y384946D01*
X1078717Y385059D01*
G02X1078698Y386600I1365J787D01*
G01X1078717Y386634D01*
X1078742Y386676D01*
G03X1078717Y388959I-2040J1119D01*
G02X1079046Y390934I1365J788D01*
G01X1079874Y391762D01*
G02X1080502Y392128I1008J-1007D01*
G03X1081447Y392859I-420J1519D01*
G02X1083377Y394021I2015J-1163D01*
G01X1083462D01*
G03X1084813Y394786I0J1575D01*
G01X1084880Y394911D01*
Y405008D01*
X1087043Y407171D01*
Y410395D01*
X1086416Y411022D01*
G01X1080082Y389747D02*
Y390907D01*
X1080366Y391191D01*
X1080707Y391406D01*
G03X1082097Y392484I-622J2237D01*
G02X1083403Y393271I1365J-788D01*
G01X1083532D01*
G03X1085477Y394434I-70J2325D01*
G01X1085628Y394718D01*
Y404698D01*
X1087791Y406861D01*
Y410410D01*
X1088916Y411535D01*
G01X1076702Y383896D02*
Y382568D01*
X1076474Y382340D01*
G02X1075337Y384686I228J1559D01*
G03Y387012I-2015J1163D01*
G02Y388586I1365J787D01*
G03Y390912I-2015J1163D01*
G02Y392486I1365J787D01*
G03X1075648Y393646I-2015J1162D01*
G01Y401353D01*
X1080186Y405891D01*
Y418945D01*
X1080341Y419100D01*
Y419187D01*
G01X1076702Y391696D02*
G02X1078067Y394812I14703J-4584D01*
G01X1078297Y395210D01*
X1081860Y398773D01*
Y405485D01*
X1082886Y406511D01*
Y419295D01*
X1082731Y419450D01*
Y419537D01*
G01X1076702Y379996D02*
Y381330D01*
X1076446Y381586D01*
G02X1074687Y385062I256J2313D01*
G03Y386636I-1365J787D01*
G02Y388962I2015J1163D01*
G03Y390536I-1365J787D01*
G02Y392862I2015J1163D01*
G01Y392861D01*
G03X1074898Y393646I-1365J788D01*
G01Y401664D01*
X1079436Y406202D01*
Y418945D01*
X1079281Y419100D01*
Y419187D01*
G01X1076702Y387796D02*
G02X1078067Y390910I14795J-4629D01*
G03X1078376Y391501I-7007J4040D01*
G03X1078459Y392151I-961J453D01*
G03X1078416Y393091I-12434J-98D01*
G02X1078717Y394437I2301J192D01*
G01X1078897Y394749D01*
X1082610Y398462D01*
Y405174D01*
X1083636Y406200D01*
Y419295D01*
X1083791Y419450D01*
Y419537D01*
G01X1045800Y406935D02*
Y406214D01*
X1044200Y404614D01*
Y396000D01*
X1040000Y391800D01*
Y389924D01*
X1040161Y389763D01*
G02X1040509Y389296I-1832J-1728D01*
G02Y387722I-1364J-787D01*
G01X1040474Y387662D01*
G03X1040509Y385396I2050J-1102D01*
G02X1039145Y383034I-1364J-787D01*
G01X1039060D01*
G03X1037130Y381872I85J-2325D01*
G01X1035765Y378760D01*
G01X1042524Y374860D02*
X1045758Y375234D01*
X1045948D01*
G03X1047269Y377597I-44J1575D01*
G02X1047244Y379880I2015J1164D01*
G01X1047269Y379922D01*
X1047288Y379956D01*
G03X1047269Y381497I-1384J754D01*
G02X1047244Y383780I2015J1164D01*
G01X1047269Y383822D01*
G03X1047480Y384589I-1289J767D01*
G01Y391680D01*
X1049100Y393300D01*
Y399900D01*
X1051000Y401800D01*
Y403600D01*
X1053800Y406400D01*
Y407669D01*
G01X1039145Y380709D02*
X1041096Y383334D01*
X1041160Y383447D01*
X1041195Y383507D01*
G03X1041160Y385773I-2050J1102D01*
G02Y387347I1364J787D01*
G01X1041195Y387407D01*
G03X1041160Y389673I-2050J1102D01*
G02X1040900Y390643I1679J970D01*
G01Y391400D01*
X1045300Y395800D01*
Y403800D01*
X1047800Y406300D01*
Y407132D01*
G01X1045904Y372909D02*
X1047853Y375531D01*
X1047919Y375647D01*
X1047944Y375689D01*
G03X1047919Y377972I-2040J1119D01*
G02X1047900Y379513I1365J787D01*
G01X1047919Y379547D01*
X1047944Y379589D01*
G03X1047919Y381872I-2040J1119D01*
G02X1049240Y384235I1365J788D01*
G01X1049935D01*
X1050400Y384700D01*
X1051400D01*
X1054700Y388000D01*
Y401200D01*
X1054300Y401600D01*
Y403300D01*
X1055800Y404800D01*
Y405734D01*
G01X1127968Y364218D02*
X1129995Y362191D01*
X1131678D01*
X1133848Y364361D01*
X1135279D01*
X1136888Y365970D01*
X1137440D01*
X1139200Y367730D01*
Y371121D01*
G01X1149410Y370080D02*
Y369758D01*
X1147573Y367921D01*
X1147035D01*
X1146106Y366992D01*
Y363983D01*
X1144945Y362822D01*
X1143932D01*
X1141231Y360121D01*
X1140268D01*
X1138317Y358170D01*
X1136888D01*
X1135691Y356973D01*
X1134077D01*
X1132131Y355027D01*
X1129905D01*
X1128271Y356661D01*
X1126436D01*
X1124932Y358165D01*
X1122824D01*
X1121637Y356978D01*
X1119363D01*
X1118176Y358165D01*
X1116047D01*
X1114860Y356978D01*
X1112904D01*
X1111717Y358165D01*
X1109397D01*
X1108210Y356978D01*
X1105999D01*
X1104812Y358165D01*
X1102477D01*
X1101290Y356978D01*
X1099255D01*
X1097842Y358391D01*
X1096479D01*
X1095548Y359322D01*
G01X1094437Y360433D02*
X1092386D01*
G01X1087494Y360122D02*
X1085982D01*
G01X1080735D02*
X1078852D01*
G01X1077940Y359210D02*
X1077657Y358927D01*
X1075663D01*
X1075380Y359210D01*
G01X1133180Y360570D02*
X1131508Y358898D01*
X1130080D01*
G01X1105340Y362000D02*
X1105270Y362070D01*
X1103087D01*
X1103017Y362000D01*
G01X1088025Y364091D02*
X1085871D01*
G01X1080963Y364251D02*
X1079097D01*
G01X1110463Y186124D02*
Y186211D01*
X1110308Y186366D01*
Y190014D01*
X1103200Y197122D01*
Y201730D01*
X1099990Y204940D01*
Y208097D01*
X1098188Y209899D01*
Y210356D01*
G03X1097876Y211509I-2327J-11D01*
G01X1097857Y211543D01*
G02X1097876Y213084I1384J754D01*
G03X1097901Y215367I-2015J1164D01*
G01X1097876Y215409D01*
X1097857Y215443D01*
G02X1097876Y216984I1384J754D01*
G03X1097901Y219267I-2015J1164D01*
G01X1097876Y219309D01*
X1097857Y219343D01*
G02X1097876Y220884I1384J754D01*
G03X1097901Y223167I-2015J1164D01*
G01X1097876Y223209D01*
X1097857Y223243D01*
G02X1097876Y224784I1384J754D01*
G03X1097901Y227067I-2015J1164D01*
G01X1097876Y227109D01*
X1097857Y227143D01*
G02X1097876Y228684I1384J754D01*
G03X1098055Y229070I-2013J1168D01*
G03X1098182Y230014I-2194J776D01*
G01X1098171Y230273D01*
G02X1098170Y230320I1109J47D01*
G01Y230398D01*
G02X1098402Y230958I792J0D01*
G01X1099241Y231797D01*
G01X1114372Y186124D02*
Y186211D01*
X1114217Y186366D01*
Y192113D01*
X1106550Y199780D01*
Y202580D01*
X1102848Y206282D01*
Y209252D01*
X1101566Y210534D01*
Y212232D01*
X1101567Y212233D01*
G03X1101256Y213459I-2326J62D01*
G02X1101237Y215000I1365J787D01*
G01X1101256Y215034D01*
X1101281Y215076D01*
G03X1101256Y217359I-2040J1119D01*
G02X1101237Y218900I1365J787D01*
G01X1101256Y218934D01*
X1101281Y218976D01*
G03X1101256Y221259I-2040J1119D01*
G02X1101237Y222800I1365J787D01*
G01X1101256Y222834D01*
X1101281Y222876D01*
G03X1101256Y225159I-2040J1119D01*
G02X1101237Y226700I1365J787D01*
G01X1101256Y226734D01*
X1101281Y226776D01*
G03X1101256Y229059I-2040J1119D01*
G02X1101237Y230600I1365J787D01*
G01X1101256Y230634D01*
G03X1101281Y232917I-2015J1164D01*
G01X1101256Y232959D01*
G02Y234533I1365J787D01*
G03Y236859I-2015J1163D01*
G02X1101237Y238400I1365J787D01*
G01X1101256Y238434D01*
X1101281Y238476D01*
G03X1101256Y240759I-2040J1119D01*
G01X1100995Y241210D01*
G03X1099241Y243496I-9566J-5524D01*
G01Y235696D02*
G02X1098888Y234363I-2695J0D01*
G01X1098261Y233261D01*
X1097810Y232468D01*
G03X1097433Y229960I5394J-2093D01*
G02X1097347Y229321I-1572J-114D01*
G02X1097226Y229059I-1485J527D01*
G03X1097201Y226776I2015J-1164D01*
G01X1097226Y226734D01*
X1097245Y226700D01*
G02X1097226Y225159I-1384J-754D01*
G03X1097201Y222876I2015J-1164D01*
G01X1097226Y222834D01*
X1097245Y222800D01*
G02X1097226Y221259I-1384J-754D01*
G03X1097201Y218976I2015J-1164D01*
G01X1097226Y218934D01*
X1097245Y218900D01*
G02X1097226Y217359I-1384J-754D01*
G03X1097201Y215076I2015J-1164D01*
G01X1097226Y215034D01*
X1097245Y215000D01*
G02X1097226Y213459I-1384J-754D01*
G03Y211133I2015J-1163D01*
G02X1097437Y210353I-1365J-788D01*
G01X1097438Y210352D01*
Y209588D01*
X1099240Y207786D01*
Y204629D01*
X1102450Y201419D01*
Y196811D01*
X1109558Y189703D01*
Y186366D01*
X1109403Y186211D01*
Y186124D01*
G01X1113312D02*
Y186211D01*
X1113467Y186366D01*
Y191802D01*
X1105800Y199469D01*
Y202269D01*
X1102098Y205971D01*
Y208941D01*
X1100816Y210223D01*
Y212253D01*
G03X1100606Y213084I-1575J44D01*
G02X1100581Y215367I2015J1164D01*
G01X1100606Y215409D01*
X1100625Y215443D01*
G03X1100606Y216984I-1384J754D01*
G02X1100581Y219267I2015J1164D01*
G01X1100606Y219309D01*
X1100625Y219343D01*
G03X1100606Y220884I-1384J754D01*
G02X1100581Y223167I2015J1164D01*
G01X1100606Y223209D01*
X1100625Y223243D01*
G03X1100606Y224784I-1384J754D01*
G02X1100581Y227067I2015J1164D01*
G01X1100606Y227109D01*
X1100625Y227143D01*
G03X1100606Y228684I-1384J754D01*
G02Y231010I2015J1163D01*
G03Y232584I-1365J787D01*
G01X1100581Y232626D01*
G02X1100606Y234909I2040J1119D01*
G01X1100625Y234943D01*
G03X1100606Y236484I-1384J754D01*
G02X1100581Y238767I2015J1164D01*
G01X1100606Y238809D01*
X1100625Y238843D01*
G03X1100605Y240384I-1384J753D01*
G03X1099469Y241155I-1365J-788D01*
G01X1099241Y240927D01*
Y239596D01*
G01X1121992Y185598D02*
X1122940Y186546D01*
Y191060D01*
X1116300Y197700D01*
Y200460D01*
X1107200Y209560D01*
Y210889D01*
G02X1107366Y211509I1240J0D01*
G01X1107385Y211543D01*
G03X1107366Y213084I-1384J754D01*
G02X1107341Y215367I2015J1164D01*
G01X1107366Y215409D01*
X1107385Y215443D01*
G03X1107366Y216984I-1384J754D01*
G02X1107341Y219267I2015J1164D01*
G01X1107366Y219309D01*
X1107385Y219343D01*
G03X1107366Y220884I-1384J754D01*
G02X1107341Y223167I2015J1164D01*
G01X1107366Y223209D01*
X1107385Y223243D01*
G03X1107366Y224784I-1384J754D01*
G02X1107341Y227067I2015J1164D01*
G01X1107366Y227109D01*
X1107385Y227143D01*
G03X1107366Y228684I-1384J754D01*
G02Y231010I2015J1163D01*
G03Y232584I-1365J787D01*
G01X1107299Y232699D01*
X1106001Y235696D01*
G01X1124492Y186158D02*
X1123780Y186870D01*
Y191282D01*
X1117050Y198012D01*
Y200880D01*
X1107969Y209961D01*
Y210958D01*
G02X1108016Y211133I351J0D01*
G03Y213459I-2015J1163D01*
G02X1107997Y215000I1365J787D01*
G01X1108016Y215034D01*
X1108041Y215076D01*
G03X1108016Y217359I-2040J1119D01*
G02X1107997Y218900I1365J787D01*
G01X1108016Y218934D01*
X1108041Y218976D01*
G03X1108016Y221259I-2040J1119D01*
G02X1107997Y222800I1365J787D01*
G01X1108016Y222834D01*
X1108041Y222876D01*
G03X1108016Y225159I-2040J1119D01*
G02X1107997Y226700I1365J787D01*
G01X1108016Y226734D01*
X1108041Y226776D01*
G03X1108016Y229059I-2040J1119D01*
G02X1107997Y230600I1365J787D01*
G01X1108016Y230634D01*
G03X1108041Y232917I-2015J1164D01*
G01X1108016Y232959D01*
G02Y234533I1365J787D01*
G03Y236859I-2015J1163D01*
G01X1107950Y236975D01*
X1106001Y239596D01*
G01X1116992Y185192D02*
X1118020Y186220D01*
Y191608D01*
X1113310Y196318D01*
Y198929D01*
X1105069Y207170D01*
Y209156D01*
X1103961Y211176D01*
G02X1103986Y213459I2040J1119D01*
G03X1104005Y215000I-1365J787D01*
G01X1103986Y215034D01*
X1103961Y215076D01*
G02X1103986Y217359I2040J1119D01*
G03X1104005Y218900I-1365J787D01*
G01X1103986Y218934D01*
X1103961Y218976D01*
G02X1103986Y221259I2040J1119D01*
G03X1104005Y222800I-1365J787D01*
G01X1103986Y222834D01*
X1103961Y222876D01*
G02X1103986Y225159I2040J1119D01*
G03X1104005Y226700I-1365J787D01*
G01X1103986Y226734D01*
X1103961Y226776D01*
G02X1103986Y229059I2040J1119D01*
G03X1104005Y230600I-1365J787D01*
G01X1103921Y230746D01*
X1102621Y233746D01*
G01X1119492Y185408D02*
X1118770Y186130D01*
Y191920D01*
X1114130Y196560D01*
Y199360D01*
X1105900Y207590D01*
Y209301D01*
X1104617Y211543D01*
G02X1104636Y213084I1384J754D01*
G03X1104661Y215367I-2015J1164D01*
G01X1104636Y215409D01*
X1104617Y215443D01*
G02X1104636Y216984I1384J754D01*
G03X1104661Y219267I-2015J1164D01*
G01X1104636Y219309D01*
X1104617Y219343D01*
G02X1104636Y220884I1384J754D01*
G03X1104661Y223167I-2015J1164D01*
G01X1104636Y223209D01*
X1104617Y223243D01*
G02X1104636Y224784I1384J754D01*
G03X1104661Y227067I-2015J1164D01*
G01X1104636Y227109D01*
X1104617Y227143D01*
G02X1104636Y228684I1384J754D01*
G03Y231010I-2015J1163D01*
G02Y232584I1365J787D01*
G01X1104661Y232626D01*
G03X1104636Y234909I-2040J1119D01*
G01X1104617Y234943D01*
G02X1104636Y236484I1384J754D01*
G03X1104661Y238767I-2015J1164D01*
G01X1104636Y238809D01*
X1104570Y238925D01*
X1102621Y241547D01*
G01X1116141Y233746D02*
X1114191Y231124D01*
X1114126Y231010D01*
G03X1116056Y227522I2015J-1163D01*
G01X1116185D01*
G02X1117506Y226734I-44J-1575D01*
G03X1119451Y225571I2015J1162D01*
G01X1119521D01*
G02X1120885Y223209I0J-1575D01*
G01X1120850Y223149D01*
G03X1120885Y220883I2050J-1102D01*
G02Y219309I-1364J-787D01*
G01X1120850Y219249D01*
G03X1120885Y216983I2050J-1102D01*
G02Y215409I-1364J-787D01*
G01X1120860Y215367D01*
G03X1120885Y213084I2040J-1119D01*
G02X1120904Y211543I-1365J-787D01*
G01X1120885Y211509D01*
X1120860Y211467D01*
G03X1120885Y209184I2040J-1119D01*
G02X1120904Y207643I-1365J-787D01*
G01X1120885Y207609D01*
X1120860Y207567D01*
G03X1122815Y204122I2040J-1120D01*
G01X1122944D01*
G02X1124265Y203334I-44J-1575D01*
G01X1125659Y201940D01*
X1127408D01*
X1131900Y197448D01*
Y195894D01*
G01X1116141Y241547D02*
X1114844Y238551D01*
X1114757Y238400D01*
G03X1115610Y236163I1384J-753D01*
G02X1117331Y234912I-1275J-3563D01*
G03X1117506Y234533I2191J782D01*
G02Y232959I-1365J-787D01*
G01X1117481Y232917D01*
G02X1115677Y231352I-3269J1946D01*
G03X1116082Y228272I463J-1506D01*
G01X1116211D01*
G02X1118156Y227109I-70J-2325D01*
G03X1119477Y226321I1365J787D01*
G01X1119619D01*
G02X1121571Y222894I-98J-2325D01*
G01X1121536Y222834D01*
G03Y221260I1364J-787D01*
G02X1121571Y218994I-2015J-1164D01*
G01X1121536Y218934D01*
G03Y217360I1364J-787D01*
G02X1121571Y215094I-2015J-1164D01*
G01X1121504Y214978D01*
G03X1121535Y213459I1396J-731D01*
G02X1121560Y211176I-2015J-1164D01*
G01X1121535Y211134D01*
X1121516Y211100D01*
G03X1121535Y209559I1384J-754D01*
G02X1121560Y207276I-2015J-1164D01*
G01X1121535Y207234D01*
X1121516Y207200D01*
G03X1122841Y204872I1384J-753D01*
G01X1122970D01*
G02X1124551Y204189I-70J-2334D01*
G01X1126050Y202690D01*
X1127720D01*
X1133345Y197065D01*
X1133395D01*
G01X1148018Y204865D02*
X1146674Y206209D01*
X1145970D01*
X1140258Y211921D01*
X1136369D01*
G02X1134380Y215367I51J2326D01*
G01X1134405Y215409D01*
X1134424Y215443D01*
G03X1134405Y216984I-1384J754D01*
G02X1134380Y219267I2015J1164D01*
G01X1134405Y219309D01*
X1134424Y219343D01*
G03X1134405Y220884I-1384J754D01*
G02X1134380Y223167I2015J1164D01*
G01X1134405Y223209D01*
X1134424Y223243D01*
G03X1134405Y224784I-1384J754D01*
G02X1134380Y227067I2015J1164D01*
G01X1134405Y227109D01*
X1134424Y227143D01*
G03X1134405Y228684I-1384J754D01*
G02Y231010I2015J1163D01*
G03X1133111Y233371I-1365J787D01*
G01X1132955D01*
G02X1131025Y234533I85J2325D01*
G03X1129704Y235321I-1365J-787D01*
G01X1129609D01*
G02X1127645Y236484I51J2326D01*
G03X1126508Y237255I-1365J-789D01*
G01X1126280Y237027D01*
Y235696D01*
G01Y239596D02*
Y238265D01*
X1126536Y238009D01*
G02X1128295Y236859I-256J-2312D01*
G03X1129601Y236072I1365J788D01*
G01X1129711D01*
G02X1131675Y234909I-51J-2326D01*
G03X1132969Y234122I1365J787D01*
G01X1133110D01*
G02X1135055Y230634I-70J-2325D01*
G01X1135036Y230600D01*
G03X1135055Y229059I1384J-754D01*
G02X1135080Y226776I-2015J-1164D01*
G01X1135055Y226734D01*
X1135036Y226700D01*
G03X1135055Y225159I1384J-754D01*
G02X1135080Y222876I-2015J-1164D01*
G01X1135055Y222834D01*
X1135036Y222800D01*
G03X1135055Y221259I1384J-754D01*
G02X1135080Y218976I-2015J-1164D01*
G01X1135055Y218934D01*
X1135036Y218900D01*
G03X1135055Y217359I1384J-754D01*
G02X1135080Y215076I-2015J-1164D01*
G01X1135055Y215034D01*
X1135036Y215000D01*
G03X1136361Y212672I1384J-753D01*
G01X1140568D01*
X1145790Y207450D01*
X1148099D01*
G01X1112761Y235696D02*
X1110812Y233075D01*
X1110746Y232959D01*
X1110721Y232917D01*
G03X1110746Y230634I2040J-1119D01*
G02Y229059I-1363J-787D01*
G03X1112691Y225571I2015J-1163D01*
G01X1112820D01*
G02X1114126Y224784I-59J-1575D01*
G03X1116056Y223622I2015J1163D01*
G01X1116185D01*
G02X1117506Y221259I-44J-1575D01*
G03X1117481Y218976I2015J-1164D01*
G01X1117506Y218934D01*
X1117525Y218900D01*
G02X1117506Y217359I-1384J-754D01*
G03X1117481Y215076I2015J-1164D01*
G01X1117506Y215034D01*
G02X1117531Y213505I-1365J-787D01*
G01X1117505Y213460D01*
G03X1117470Y211194I2015J-1164D01*
G01X1117505Y211134D01*
G02Y209560I-1364J-787D01*
G03X1117480Y207275I2015J-1165D01*
G01X1117505Y207233D01*
G02Y205659I-1364J-787D01*
G03X1119435Y202171I2015J-1163D01*
G01X1119930D01*
X1122210Y199891D01*
Y199060D01*
X1126445Y194825D01*
X1127637D01*
X1129160Y193302D01*
G01X1112761Y239596D02*
X1114060Y236597D01*
X1114126Y236484D01*
G02X1114392Y235490I-1725J-994D01*
G01Y235152D01*
G02X1112690Y233371I-1783J0D01*
G03X1111396Y231010I71J-1574D01*
G02X1111462Y228798I-2025J-1167D01*
G01X1111396Y228684D01*
G03X1112717Y226321I1365J-788D01*
G01X1112846D01*
G02X1114776Y225159I-85J-2325D01*
G03X1116082Y224372I1365J788D01*
G01X1116211D01*
G02X1118156Y220884I-70J-2325D01*
G03X1118137Y219343I1365J-787D01*
G01X1118156Y219309D01*
X1118181Y219267D01*
G02X1118156Y216984I-2040J-1119D01*
G03X1118137Y215443I1365J-787D01*
G01X1118156Y215409D01*
X1118191Y215349D01*
G02X1118156Y213083I-2050J-1102D01*
G03Y211509I1364J-787D01*
G01X1118191Y211449D01*
G02X1118156Y209183I-2050J-1102D01*
G03Y207609I1364J-787D01*
G02Y205283I-2015J-1163D01*
G03X1119520Y202921I1364J-787D01*
G01X1120241D01*
X1122960Y200202D01*
Y199371D01*
X1125951Y196380D01*
X1128748D01*
X1130493Y194635D01*
G01X1122900Y233746D02*
X1125029Y233363D01*
X1126195Y233371D01*
X1126351D01*
G02X1127645Y232584I-71J-1574D01*
G03X1129590Y231421I2015J1162D01*
G01X1129731D01*
G02X1131025Y229059I-71J-1574D01*
G03X1131000Y226776I2015J-1164D01*
G01X1131025Y226734D01*
X1131044Y226700D01*
G02X1131025Y225159I-1384J-754D01*
G03X1131000Y222876I2015J-1164D01*
G01X1131025Y222834D01*
X1131044Y222800D01*
G02X1131025Y221259I-1384J-754D01*
G03X1131000Y218976I2015J-1164D01*
G01X1131025Y218934D01*
X1131044Y218900D01*
G02X1131025Y217359I-1384J-754D01*
G03X1131000Y215076I2015J-1164D01*
G01X1131025Y215034D01*
X1131044Y215000D01*
G02X1131025Y213459I-1384J-754D01*
G03X1132955Y209971I2015J-1163D01*
G01X1133084D01*
G02X1134405Y209183I-44J-1575D01*
G03X1136335Y208021I2015J1163D01*
G01X1139529D01*
X1145135Y202415D01*
G01X1122900Y241547D02*
X1124500Y238435D01*
X1124577Y235479D01*
X1124915Y234909D01*
G03X1126209Y234122I1365J787D01*
G01X1126350D01*
G02X1128295Y232959I-70J-2325D01*
G03X1129589Y232172I1365J787D01*
G01X1129745D01*
G02X1131675Y228684I-85J-2325D01*
G03X1131656Y227143I1365J-787D01*
G01X1131675Y227109D01*
X1131700Y227067D01*
G02X1131675Y224784I-2040J-1119D01*
G03X1131656Y223243I1365J-787D01*
G01X1131675Y223209D01*
X1131700Y223167D01*
G02X1131675Y220884I-2040J-1119D01*
G03X1131656Y219343I1365J-787D01*
G01X1131675Y219309D01*
X1131700Y219267D01*
G02X1131675Y216984I-2040J-1119D01*
G03X1131656Y215443I1365J-787D01*
G01X1131675Y215409D01*
X1131700Y215367D01*
G02X1131675Y213084I-2040J-1119D01*
G03X1132996Y210721I1365J-788D01*
G01X1133125D01*
G02X1135055Y209559I-85J-2325D01*
G03X1136376Y208771I1365J787D01*
G01X1139840D01*
X1143511Y205100D01*
X1145116D01*
G01X1119521Y231797D02*
G03Y230222I0J-787D01*
G01X1119591D01*
G02X1121536Y229060I-70J-2326D01*
G01X1121549Y229037D01*
G03X1122900Y228272I1351J810D01*
G01X1122970D01*
G02X1124915Y224784I-70J-2325D01*
G03X1124896Y223243I1365J-787D01*
G01X1124915Y223209D01*
X1124940Y223167D01*
G02X1124915Y220884I-2040J-1119D01*
G03X1124896Y219343I1365J-787D01*
G01X1124915Y219309D01*
X1124940Y219267D01*
G02X1124915Y216984I-2040J-1119D01*
G03X1124896Y215443I1365J-787D01*
G01X1124915Y215409D01*
X1124940Y215367D01*
G02X1124915Y213084I-2040J-1119D01*
G03X1124896Y211543I1365J-787D01*
G01X1124915Y211509D01*
X1124940Y211467D01*
G02X1124915Y209184I-2040J-1119D01*
G03X1126236Y206821I1365J-788D01*
G01X1126365D01*
G02X1128295Y205659I-85J-2325D01*
G01X1128710Y204941D01*
X1128990Y204660D01*
X1131061D01*
X1135890Y199831D01*
X1136108Y199832D01*
X1136169Y199771D01*
G01X1119521Y243496D02*
G02X1121278Y241207I-7822J-7823D01*
G01X1121536Y240760D01*
G02X1121571Y238494I-2015J-1164D01*
G01X1121536Y238434D01*
G03Y236860I1364J-787D01*
G02X1121561Y234575I-2015J-1165D01*
G01X1121536Y234533D01*
G03X1122852Y232172I1364J-787D01*
G01X1122985D01*
G02X1124915Y231010I-85J-2325D01*
G03X1126236Y230222I1365J787D01*
G01X1126331D01*
G02X1128320Y226776I-51J-2326D01*
G01X1128295Y226734D01*
X1128276Y226700D01*
G03X1128295Y225159I1384J-754D01*
G02X1128320Y222876I-2015J-1164D01*
G01X1128295Y222834D01*
X1128276Y222800D01*
G03X1128295Y221259I1384J-754D01*
G02X1128320Y218976I-2015J-1164D01*
G01X1128295Y218934D01*
X1128276Y218900D01*
G03X1128295Y217359I1384J-754D01*
G02X1128320Y215076I-2015J-1164D01*
G01X1128295Y215034D01*
X1128276Y215000D01*
G03X1128295Y213459I1384J-754D01*
G02Y211133I-2015J-1163D01*
G03X1129589Y208772I1365J-787D01*
G01X1129611Y208771D01*
X1129747D01*
G02X1131619Y207702I-86J-2324D01*
G01X1133240Y206080D01*
X1136801D01*
X1138981Y203900D01*
X1139199Y203901D01*
X1139260Y203840D01*
G01X1119521Y235696D02*
X1118995Y234124D01*
X1118181Y232626D01*
X1118156Y232584D01*
X1118090Y232468D01*
G03X1117814Y231850I3030J-1724D01*
G03X1119521Y229471I1713J-573D01*
G02X1120872Y228706I0J-1575D01*
G01X1120885Y228683D01*
G03X1122802Y227522I2015J1164D01*
G01X1122944D01*
G02X1124265Y225159I-44J-1575D01*
G03X1124240Y222876I2015J-1164D01*
G01X1124265Y222834D01*
X1124284Y222800D01*
G02X1124265Y221259I-1384J-754D01*
G03X1124240Y218976I2015J-1164D01*
G01X1124265Y218934D01*
X1124284Y218900D01*
G02X1124265Y217359I-1384J-754D01*
G03X1124240Y215076I2015J-1164D01*
G01X1124265Y215034D01*
X1124284Y215000D01*
G02X1124265Y213459I-1384J-754D01*
G03X1124240Y211176I2015J-1164D01*
G01X1124265Y211134D01*
X1124284Y211100D01*
G02X1124265Y209559I-1384J-754D01*
G03X1126210Y206071I2015J-1163D01*
G01X1126339D01*
G02X1127645Y205284I-59J-1575D01*
G01X1128109Y204480D01*
X1128679Y203910D01*
X1130750D01*
X1135358Y199302D01*
Y199082D01*
X1135420Y199020D01*
G01X1119521Y239596D02*
Y240927D01*
X1119748Y241154D01*
G02X1120884Y240383I-228J-1558D01*
G02X1120885Y238809I-1363J-788D01*
G01X1120850Y238749D01*
G03X1120885Y236483I2050J-1102D01*
G02Y234909I-1364J-787D01*
G03X1122830Y231421I2015J-1163D01*
G01X1122971D01*
G02X1124265Y230634I-71J-1574D01*
G03X1126229Y229471I2015J1163D01*
G01X1126339D01*
G02X1127664Y227143I-59J-1575D01*
G01X1127645Y227109D01*
X1127620Y227067D01*
G03X1127645Y224784I2040J-1119D01*
G02X1127664Y223243I-1365J-787D01*
G01X1127645Y223209D01*
X1127620Y223167D01*
G03X1127645Y220884I2040J-1119D01*
G02X1127664Y219343I-1365J-787D01*
G01X1127645Y219309D01*
X1127620Y219267D01*
G03X1127645Y216984I2040J-1119D01*
G02X1127664Y215443I-1365J-787D01*
G01X1127645Y215409D01*
X1127620Y215367D01*
G03X1127645Y213084I2040J-1119D01*
G02X1127664Y211543I-1365J-787D01*
G01X1127645Y211509D01*
G03X1129575Y208021I2015J-1163D01*
G01X1129731D01*
G02X1131025Y207234I-71J-1574D01*
G01X1132929Y205330D01*
X1136490D01*
X1138449Y203371D01*
Y203151D01*
X1138511Y203089D01*
G01X1158000Y206500D02*
Y206587D01*
X1158200Y206787D01*
Y208488D01*
X1158187Y208914D01*
X1158586Y210470D01*
X1159186Y211508D01*
X1159204Y211543D01*
G03X1157879Y213871I-1384J753D01*
G01X1157750D01*
G02X1155805Y215034I70J2325D01*
G03X1154484Y215822I-1365J-787D01*
G01X1154355D01*
G02X1152425Y216984I85J2325D01*
G03X1151119Y217771I-1365J-788D01*
G01X1150990D01*
G02X1149045Y218934I70J2325D01*
G03X1147724Y219722I-1365J-787D01*
G01X1147595D01*
G02X1145665Y220884I85J2325D01*
G03X1144305Y221670I-1360J-784D01*
G01X1142946D01*
X1141409Y223207D01*
Y226971D01*
X1141109Y227271D01*
Y228471D01*
X1141409Y228771D01*
Y229971D01*
X1141109Y230271D01*
Y231471D01*
X1141409Y231771D01*
Y232971D01*
X1141109Y233271D01*
Y234471D01*
X1141409Y234771D01*
Y235971D01*
X1141109Y236271D01*
Y237471D01*
X1141409Y237771D01*
Y238971D01*
X1141109Y239271D01*
Y240471D01*
X1141409Y240771D01*
Y241971D01*
X1141109Y242271D01*
Y243471D01*
X1141409Y243771D01*
Y244971D01*
X1141109Y245271D01*
Y246471D01*
X1141409Y246771D01*
Y248021D01*
X1140488Y248942D01*
X1139993D01*
X1139250Y249685D01*
Y250180D01*
X1138508Y250922D01*
X1136348D01*
G02X1134405Y252084I72J2325D01*
G03X1133099Y252871I-1365J-788D01*
G01X1132970D01*
G02X1131025Y254034I70J2325D01*
G03X1129704Y254822I-1365J-787D01*
G01X1129575D01*
G02X1127620Y258267I85J2325D01*
G01X1127645Y258309D01*
X1127664Y258343D01*
G03X1126339Y260671I-1384J753D01*
G01X1126210D01*
G02X1124265Y261834I70J2325D01*
G03X1122948Y262622I-1365J-786D01*
G03X1122853I-48J-1574D01*
G03X1121513Y261793I47J-1574D01*
G03X1121331Y260919I1387J-745D01*
G03X1121437Y260466I1570J128D01*
G01X1121747Y260382D01*
X1122900Y261047D01*
G01X1159150Y206500D02*
Y206587D01*
X1158950Y206787D01*
Y208500D01*
X1158940Y208831D01*
X1159287Y210184D01*
X1159854Y211165D01*
G03X1157905Y214621I-2034J1131D01*
G01X1157776D01*
G02X1156455Y215409I44J1575D01*
G03X1154510Y216572I-2015J-1162D01*
G01X1154381D01*
G02X1153075Y217359I59J1575D01*
G03X1151145Y218521I-2015J-1163D01*
G01X1151016D01*
G02X1149695Y219309I44J1575D01*
G03X1147750Y220472I-2015J-1162D01*
G01X1147611D01*
G02X1146315Y221259I69J1575D01*
G03X1144306Y222420I-2010J-1159D01*
G01X1143257D01*
X1142159Y223518D01*
Y248332D01*
X1138819Y251672D01*
X1136361D01*
G02X1135055Y252459I59J1575D01*
G03X1133125Y253621I-2015J-1163D01*
G01X1132996D01*
G02X1131675Y254409I44J1575D01*
G03X1129730Y255572I-2015J-1162D01*
G01X1129601D01*
G02X1128276Y257900I59J1575D01*
G01X1128295Y257934D01*
X1128320Y257976D01*
G03X1126365Y261421I-2040J1120D01*
G01X1126236D01*
G02X1124915Y262209I44J1575D01*
G03X1122970Y263372I-2015J-1162D01*
G01X1122830D01*
G03X1120885Y262209I70J-2325D01*
G01X1120850Y262149D01*
G03X1120580Y260857I2049J-1102D01*
G01X1119521Y259096D01*
G01X1122007Y374933D02*
X1122524Y374037D01*
G01X1122007Y374933D02*
G02Y377259I2015J1163D01*
G03Y378833I-1365J787D01*
G02Y381159I2015J1163D01*
G03Y382733I-1365J787D01*
G02Y385059I2015J1163D01*
G03Y386633I-1365J787D01*
G02Y388959I2015J1163D01*
G03Y390533I-1365J787D01*
G03X1121981Y390576I-1045J-603D01*
G02X1122006Y392859I2040J1119D01*
G03X1122025Y394400I-1365J787D01*
G01X1122006Y394434D01*
X1121981Y394476D01*
G02X1122006Y396759I2040J1119D01*
G03X1122025Y398300I-1365J787D01*
G01X1122006Y398334D01*
X1121981Y398376D01*
G02X1122006Y400659I2040J1119D01*
G03X1122025Y402200I-1365J787D01*
G01X1122006Y402234D01*
X1121981Y402276D01*
G02X1123936Y405721I2040J1120D01*
G01X1124021D01*
G03X1125385Y408083I0J1575D01*
G02X1125350Y410349I2015J1164D01*
G01X1125385Y410409D01*
G03Y411983I-1364J787D01*
G02X1127330Y415472I2015J1163D01*
G01X1127459D01*
G03X1128765Y416259I-59J1575D01*
G02X1130695Y417421I2015J-1163D01*
G01X1130824D01*
G03X1132145Y418209I-44J1575D01*
G01X1132368Y418595D01*
X1134456Y420683D01*
Y422289D01*
X1133640Y423105D01*
G01X1124021Y368296D02*
X1122842Y371003D01*
G03X1122657Y371409I-2200J-757D01*
G02X1122585Y372842I1365J787D01*
G03X1122524Y374037I-1197J538D01*
G01X1124021Y376096D02*
X1122832Y378832D01*
G03X1122657Y379209I-2189J-787D01*
G02Y380783I1365J787D01*
G03Y383109I-2015J1163D01*
G02Y384683I1365J787D01*
G03Y387009I-2015J1163D01*
G02Y388583I1365J787D01*
G03Y390909I-2015J1163D01*
G01X1122637Y390943D01*
G02X1122656Y392484I1384J754D01*
G03X1122681Y394767I-2015J1164D01*
G01X1122656Y394809D01*
X1122637Y394843D01*
G02X1122656Y396384I1384J754D01*
G03X1122681Y398667I-2015J1164D01*
G01X1122656Y398709D01*
X1122637Y398743D01*
G02X1122656Y400284I1384J754D01*
G03X1122681Y402567I-2015J1164D01*
G01X1122656Y402609D01*
X1122637Y402643D01*
G02X1123962Y404971I1384J753D01*
G01X1124091D01*
G03X1126036Y408460I-69J2325D01*
G02Y410034I1364J787D01*
G01X1126071Y410094D01*
G03X1126036Y412360I-2050J1102D01*
G02X1127400Y414722I1364J787D01*
G01X1127485D01*
G03X1129415Y415884I-85J2325D01*
G02X1130721Y416671I1365J-788D01*
G01X1130850D01*
G03X1132798Y417836I-70J2328D01*
G01X1132972Y418138D01*
X1135206Y420372D01*
Y421970D01*
X1136100Y422864D01*
G01X1130780Y364396D02*
X1132077Y367392D01*
X1132164Y367543D01*
G03X1132145Y369084I-1384J754D01*
G02Y371410I2015J1163D01*
G03X1132211Y372868I-1123J781D01*
G01X1132145Y372984D01*
X1132120Y373026D01*
G02X1134109Y376472I2040J1120D01*
G01X1134219D01*
G03X1135544Y378800I-59J1575D01*
G01X1135525Y378834D01*
X1135500Y378876D01*
G02X1135525Y381159I2040J1119D01*
G03X1135544Y382700I-1365J787D01*
G01X1135525Y382734D01*
X1135500Y382776D01*
G02X1135525Y385059I2040J1119D01*
G03X1135544Y386600I-1365J787D01*
G01X1135525Y386634D01*
X1135500Y386676D01*
G02X1135525Y388959I2040J1119D01*
G03X1135544Y390500I-1365J787D01*
G01X1135525Y390534D01*
X1135500Y390576D01*
G02X1135525Y392859I2040J1119D01*
G03X1135544Y394400I-1365J787D01*
G01X1135525Y394434D01*
G02X1137455Y397922I2015J1163D01*
G01X1137611D01*
G03X1138905Y400284I-71J1574D01*
G02X1138880Y402567I2015J1164D01*
G01X1138905Y402609D01*
X1138924Y402643D01*
G03X1138905Y404184I-1384J754D01*
G02X1140850Y407672I2015J1163D01*
G01X1140979D01*
G03X1142285Y408459I-59J1575D01*
G02X1144215Y409621I2015J-1163D01*
G01X1144344D01*
G03X1145665Y410409I-44J1575D01*
G02X1147595Y411571I2015J-1163D01*
G01X1149725D01*
X1151589Y413435D01*
Y414534D01*
G01X1153382Y412791D02*
X1152006D01*
X1150036Y410821D01*
X1147636D01*
G03X1146315Y410033I44J-1575D01*
G02X1144385Y408871I-2015J1163D01*
G01X1144241D01*
G03X1142935Y408084I59J-1575D01*
G02X1141005Y406922I-2015J1163D01*
G01X1140876D01*
G03X1139555Y404559I44J-1575D01*
G02X1139580Y402276I-2015J-1164D01*
G01X1139555Y402234D01*
X1139536Y402200D01*
G03X1139555Y400659I1384J-754D01*
G02X1137625Y397171I-2015J-1163D01*
G01X1137469D01*
G03X1136175Y394810I71J-1574D01*
G02Y392484I-2015J-1163D01*
G03X1136156Y390943I1365J-787D01*
G01X1136175Y390909D01*
X1136200Y390867D01*
G02X1136175Y388584I-2040J-1119D01*
G03X1136156Y387043I1365J-787D01*
G01X1136175Y387009D01*
X1136200Y386967D01*
G02X1136175Y384684I-2040J-1119D01*
G03X1136156Y383143I1365J-787D01*
G01X1136175Y383109D01*
X1136200Y383067D01*
G02X1136175Y380784I-2040J-1119D01*
G03X1136156Y379243I1365J-787D01*
G01X1136175Y379209D01*
X1136200Y379167D01*
G02X1136175Y376884I-2040J-1119D01*
G01X1136109Y376769D01*
X1134160Y374146D01*
G01X1120641Y370247D02*
X1118502Y373234D01*
G02X1118627Y375309I2140J912D01*
G03Y376883I-1365J787D01*
G02Y379209I2015J1163D01*
G03Y380783I-1365J787D01*
G02Y383109I2015J1163D01*
G03Y384683I-1365J787D01*
G02Y387009I2015J1163D01*
G03Y388583I-1365J787D01*
G02Y390909I2015J1163D01*
G03X1118645Y390943I-456J263D01*
G03X1118626Y392484I-1384J754D01*
G02X1118601Y394767I2015J1164D01*
G01X1118626Y394809D01*
X1118645Y394843D01*
G03X1118626Y396384I-1384J754D01*
G02X1118601Y398667I2015J1164D01*
G01X1118626Y398709D01*
X1118645Y398743D01*
G03X1118626Y400284I-1384J754D01*
G02X1118601Y402567I2015J1164D01*
G01X1118626Y402609D01*
X1118645Y402643D01*
G03X1118626Y404184I-1384J754D01*
G02X1120571Y407672I2015J1163D01*
G01X1120700D01*
G03X1122025Y410000I-59J1575D01*
G01X1122006Y410034D01*
X1121981Y410076D01*
G02X1122006Y412359I2040J1119D01*
G03X1122025Y413900I-1365J787D01*
G01X1122006Y413934D01*
X1121981Y413976D01*
G02X1123936Y417421I2040J1120D01*
G01X1124021D01*
G03X1125372Y418186I0J1575D01*
G01X1125385Y418209D01*
G02X1127303Y419372I2016J-1161D01*
G01X1127401Y419371D01*
X1127449D01*
G03X1128765Y420158I-48J1574D01*
G01X1129356Y421185D01*
Y421994D01*
X1128640Y422710D01*
G01X1120641Y374146D02*
X1119512Y376689D01*
G03X1119277Y377259I-2250J-594D01*
G02Y378833I1365J787D01*
G03Y381159I-2015J1163D01*
G02Y382733I1365J787D01*
G03Y385059I-2015J1163D01*
G02Y386633I1365J787D01*
G03Y388959I-2015J1163D01*
G02Y390533I1365J787D01*
G03X1119301Y390576I-1531J883D01*
G03X1119276Y392859I-2040J1119D01*
G02X1119257Y394400I1365J787D01*
G01X1119276Y394434D01*
X1119301Y394476D01*
G03X1119276Y396759I-2040J1119D01*
G02X1119257Y398300I1365J787D01*
G01X1119276Y398334D01*
X1119301Y398376D01*
G03X1119276Y400659I-2040J1119D01*
G02X1119257Y402200I1365J787D01*
G01X1119276Y402234D01*
X1119301Y402276D01*
G03X1119276Y404559I-2040J1119D01*
G02X1120597Y406922I1365J788D01*
G01X1120726D01*
G03X1122681Y410367I-85J2325D01*
G01X1122656Y410409D01*
X1122637Y410443D01*
G02X1122656Y411984I1384J754D01*
G03X1122681Y414267I-2015J1164D01*
G01X1122656Y414309D01*
X1122637Y414343D01*
G02X1123962Y416671I1384J753D01*
G01X1124091D01*
G03X1126036Y417834I-70J2325D01*
G02X1127352Y418621I1364J-787D01*
G01X1127400D01*
X1127498Y418620D01*
G03X1129416Y419783I-98J2324D01*
G01X1130106Y420983D01*
Y422106D01*
X1131140Y423140D01*
G01X1130780Y368296D02*
X1129394Y371447D01*
G02X1129415Y372983I1386J749D01*
G03Y375309I-2015J1163D01*
G02X1129700Y377243I1365J787D01*
G02X1131514Y378602I5140J-4970D01*
G03X1132145Y379209I-731J1392D01*
G03Y380783I-1364J787D01*
G02Y383109I2015J1163D01*
G03Y384683I-1365J787D01*
G02Y387009I2015J1163D01*
G03Y388583I-1365J787D01*
G02Y390909I2017J1163D01*
G01X1132164Y390943D01*
G03X1132145Y392484I-1384J754D01*
G02X1132120Y394767I2015J1164D01*
G01X1132145Y394809D01*
X1132164Y394843D01*
G03X1132145Y396384I-1384J754D01*
G02X1134090Y399872I2015J1163D01*
G01X1134219D01*
G03X1135544Y402200I-59J1575D01*
G01X1135525Y402234D01*
X1135500Y402276D01*
G02X1135525Y404559I2040J1119D01*
G03X1135544Y406100I-1365J787D01*
G01X1135525Y406134D01*
X1135500Y406176D01*
G02X1137455Y409621I2040J1120D01*
G01X1137584D01*
G03X1138905Y410409I-44J1575D01*
G02X1140850Y411572I2015J-1162D01*
G01X1140979D01*
G03X1142285Y412359I-59J1575D01*
G02X1144215Y413521I2015J-1163D01*
G01X1144344D01*
G03X1145665Y414309I-44J1575D01*
G01X1146163Y415171D01*
X1146276Y415366D01*
X1147671Y416761D01*
Y417688D01*
G01X1130780Y376096D02*
X1132501Y377986D01*
G02X1132651Y378498I5621J-1369D01*
G02X1132795Y378833I1510J-450D01*
G03Y381159I-2017J1163D01*
G02Y382733I1365J787D01*
G03Y385059I-2015J1163D01*
G02Y386633I1365J787D01*
G03Y388959I-2015J1163D01*
G02X1132820Y390576I1365J788D01*
G03X1132795Y392859I-2040J1119D01*
G02X1132776Y394400I1365J787D01*
G01X1132795Y394434D01*
X1132820Y394476D01*
G03X1132795Y396759I-2040J1119D01*
G02X1134116Y399122I1365J788D01*
G01X1134245D01*
G03X1136200Y402567I-85J2325D01*
G01X1136175Y402609D01*
X1136156Y402643D01*
G02X1136175Y404184I1384J754D01*
G03X1136200Y406467I-2015J1164D01*
G01X1136175Y406509D01*
X1136156Y406543D01*
G02X1137481Y408871I1384J753D01*
G01X1137610D01*
G03X1139555Y410034I-70J2325D01*
G02X1140876Y410822I1365J-787D01*
G01X1141005D01*
G03X1142935Y411984I-85J2325D01*
G02X1144241Y412771I1365J-788D01*
G01X1144385D01*
G03X1146315Y413933I-85J2325D01*
G01X1146313Y413935D01*
X1146851Y414862D01*
X1147988Y416002D01*
X1149521D01*
G01X1127400Y370247D02*
Y368916D01*
X1127173Y368689D01*
G02X1126019Y371005I227J1558D01*
G02X1126036Y371034I1367J-782D01*
G01X1126035Y371033D01*
G03Y373359I-2015J1163D01*
G02Y374933I1365J787D01*
G03Y377259I-2015J1163D01*
G02Y378833I1365J787D01*
G03Y381159I-2015J1163D01*
G02Y382733I1365J787D01*
G03Y385059I-2015J1163D01*
G02Y386633I1365J787D01*
G03Y388959I-2015J1163D01*
G02X1125914Y389226I1448J817D01*
G02X1126036Y390534I1486J521D01*
G01X1126071Y390594D01*
G03X1126036Y392860I-2050J1102D01*
G02Y394434I1364J787D01*
G01X1126071Y394494D01*
G03X1126036Y396760I-2050J1102D01*
G02Y398334I1364J787D01*
G01X1126071Y398394D01*
G03X1126036Y400660I-2050J1102D01*
G02X1127400Y403022I1364J787D01*
G01X1127485D01*
G03X1129440Y406467I-85J2325D01*
G01X1129415Y406509D01*
X1129396Y406543D01*
G02X1129415Y408084I1384J754D01*
G03X1129440Y410367I-2015J1164D01*
G01X1129415Y410409D01*
X1129396Y410443D01*
G02X1130721Y412771I1384J753D01*
G01X1130850D01*
G03X1132795Y413934I-70J2325D01*
G02X1134116Y414722I1365J-787D01*
G01X1134245D01*
G03X1136175Y415884I-85J2325D01*
G02X1137521Y416672I1365J-788D01*
G01X1137591D01*
G03X1139555Y417835I-51J2326D01*
G01X1140126Y418825D01*
Y420476D01*
X1141284Y421634D01*
X1141504D01*
X1141566Y421696D01*
G01X1127400Y378047D02*
G02X1128765Y381161I14795J-4629D01*
G03Y382735I-1365J787D01*
G01X1128764Y382736D01*
G02Y385060I2016J1162D01*
G01X1128765Y385061D01*
G03Y386635I-1365J787D01*
G02Y388961I2015J1163D01*
G03X1128880Y389205I-1408J813D01*
G03X1128784Y390500I-1480J541D01*
G01X1128765Y390534D01*
X1128740Y390576D01*
G02X1128765Y392859I2040J1119D01*
G03X1128784Y394400I-1365J787D01*
G01X1128765Y394434D01*
X1128740Y394476D01*
G02X1128765Y396759I2040J1119D01*
G03X1128784Y398300I-1365J787D01*
G01X1128765Y398334D01*
X1128740Y398376D01*
G02X1130695Y401821I2040J1120D01*
G01X1130824D01*
G03X1132145Y404184I-44J1575D01*
G02X1132120Y406467I2015J1164D01*
G01X1132145Y406509D01*
X1132164Y406543D01*
G03X1132145Y408084I-1384J754D01*
G02X1134090Y411572I2015J1163D01*
G01X1134219D01*
G03X1135525Y412359I-59J1575D01*
G02X1137455Y413521I2015J-1163D01*
G01X1137584D01*
G03X1138905Y414309I-44J1575D01*
G02X1140850Y415472I2015J-1162D01*
G01X1140989D01*
G03X1142129Y416036I-70J1575D01*
G01Y417177D01*
X1147202Y422250D01*
X1149545D01*
X1149700Y422405D01*
X1149787D01*
G01X1127400Y366347D02*
Y367678D01*
X1127144Y367934D01*
G02X1125360Y371368I256J2313D01*
G01X1125385Y371409D01*
G03Y372983I-1365J787D01*
G02Y375309I2015J1163D01*
G03Y376883I-1365J787D01*
G02Y379209I2015J1163D01*
G03Y380783I-1365J787D01*
G02Y383109I2015J1163D01*
G03Y384683I-1365J787D01*
G02Y387009I2015J1163D01*
G03Y388583I-1365J787D01*
G02X1125204Y388977I2015J1164D01*
G02X1125350Y390849I2196J770D01*
G01X1125385Y390909D01*
G03Y392483I-1364J787D01*
G02X1125350Y394749I2015J1164D01*
G01X1125385Y394809D01*
G03Y396383I-1364J787D01*
G02X1125350Y398649I2015J1164D01*
G01X1125360Y398666D01*
X1125385Y398709D01*
G03Y400283I-1364J787D01*
G02X1127330Y403772I2015J1163D01*
G01X1127459D01*
G03X1128784Y406100I-59J1575D01*
G01X1128765Y406134D01*
X1128740Y406176D01*
G02X1128765Y408459I2040J1119D01*
G03X1128784Y410000I-1365J787D01*
G01X1128765Y410034D01*
X1128740Y410076D01*
G02X1130695Y413521I2040J1120D01*
G01X1130824D01*
G03X1132145Y414309I-44J1575D01*
G02X1134090Y415472I2015J-1162D01*
G01X1134219D01*
G03X1135525Y416259I-59J1575D01*
G02X1137489Y417422I2015J-1163D01*
G01X1137559D01*
G03X1138905Y418210I-19J1576D01*
G01X1139376Y419026D01*
Y420787D01*
X1140755Y422166D01*
X1140754Y422384D01*
X1140815Y422445D01*
G01X1127400Y374146D02*
G02X1128765Y377261I14855J-4653D01*
G03X1128962Y378252I-1365J786D01*
G02X1129415Y380785I4215J553D01*
G03Y383111I-2015J1163D01*
G02Y384685I1365J787D01*
G03Y387011I-2015J1163D01*
G01Y387010D01*
G02Y388586I1365J788D01*
G03X1129601Y388994I-1989J1153D01*
G03X1129440Y390867I-2201J754D01*
G01X1129415Y390909D01*
X1129396Y390943D01*
G02X1129415Y392484I1384J754D01*
G03X1129440Y394767I-2015J1164D01*
G01X1129415Y394809D01*
X1129396Y394843D01*
G02X1129415Y396384I1384J754D01*
G03X1129440Y398667I-2015J1164D01*
G01X1129415Y398709D01*
X1129396Y398743D01*
G02X1130721Y401071I1384J753D01*
G01X1130850D01*
G03X1132795Y404559I-70J2325D01*
G02X1132776Y406100I1365J787D01*
G01X1132795Y406134D01*
X1132820Y406176D01*
G03X1132795Y408459I-2040J1119D01*
G02X1134116Y410822I1365J788D01*
G01X1134245D01*
G03X1136175Y411984I-85J2325D01*
G02X1137481Y412771I1365J-788D01*
G01X1137610D01*
G03X1139555Y413934I-70J2325D01*
G02X1140876Y414722I1365J-787D01*
G01X1141005D01*
G03X1142879Y415792I-85J2325D01*
G01Y416866D01*
X1147513Y421500D01*
X1149545D01*
X1149700Y421345D01*
X1149787D01*
G01X1102243Y374039D02*
X1101726Y374935D01*
G02Y377261I2015J1163D01*
G03Y378835I-1365J787D01*
G02Y381161I2015J1163D01*
G03Y382735I-1365J787D01*
G02Y385061I2015J1163D01*
G03Y386635I-1365J787D01*
G02Y388961I2015J1163D01*
G03Y390535I-1365J787D01*
G02Y392861I2015J1163D01*
G03X1101802Y393009I-1245J733D01*
G03X1101745Y394400I-1441J638D01*
G01X1101726Y394434D01*
X1101701Y394476D01*
G02X1101726Y396759I2040J1119D01*
G03X1101745Y398300I-1365J787D01*
G01X1101726Y398334D01*
X1101701Y398376D01*
G02X1101726Y400659I2040J1119D01*
G03X1101745Y402200I-1365J787D01*
G01X1101726Y402234D01*
X1101701Y402276D01*
G02X1101726Y404559I2040J1119D01*
G03X1101745Y406100I-1365J787D01*
G01X1101726Y406134D01*
X1101701Y406176D01*
G02X1101726Y408459I2040J1119D01*
G03X1101745Y410000I-1365J787D01*
G01X1101726Y410034D01*
X1101701Y410076D01*
G02X1101726Y412359I2040J1119D01*
G03X1101745Y413900I-1365J787D01*
G01X1101726Y413934D01*
X1101701Y413976D01*
G02X1103656Y417421I2040J1120D01*
G01X1103785D01*
G03X1104808Y419990I-42J1505D01*
G01Y421056D01*
X1103850Y422014D01*
G01X1102243Y374039D02*
G02X1102304Y372844I-1136J-657D01*
G03X1102376Y371411I1437J-646D01*
G02X1102603Y370869I-2015J-1163D01*
G01X1103741Y368296D01*
G01Y376096D02*
X1102623Y378590D01*
G03X1102376Y379211I-2263J-540D01*
G02Y380785I1365J787D01*
G03Y383111I-2015J1163D01*
G02Y384685I1365J787D01*
G03Y387011I-2015J1163D01*
G02Y388585I1365J787D01*
G03Y390911I-2015J1163D01*
G02Y392485I1365J787D01*
G03X1102492Y392713I-2117J1221D01*
G03X1102401Y394767I-2131J935D01*
G01X1102376Y394809D01*
X1102357Y394843D01*
G02X1102376Y396384I1384J754D01*
G03X1102401Y398667I-2015J1164D01*
G01X1102376Y398709D01*
X1102357Y398743D01*
G02X1102376Y400284I1384J754D01*
G03X1102401Y402567I-2015J1164D01*
G01X1102376Y402609D01*
X1102357Y402643D01*
G02X1102376Y404184I1384J754D01*
G03X1102401Y406467I-2015J1164D01*
G01X1102376Y406509D01*
X1102357Y406543D01*
G02X1102376Y408084I1384J754D01*
G03X1102401Y410367I-2015J1164D01*
G01X1102376Y410409D01*
X1102357Y410443D01*
G02X1102376Y411984I1384J754D01*
G03X1102401Y414267I-2015J1164D01*
G01X1102376Y414309D01*
X1102357Y414343D01*
G02X1103682Y416671I1384J753D01*
G01X1103811D01*
G03X1105781Y417876I-69J2325D01*
G03X1105756Y420159I-2040J1119D01*
G01Y421640D01*
X1106240Y422124D01*
G01X1113881Y370247D02*
X1112441Y373509D01*
G02X1113311Y375617I1440J639D01*
G03X1115246Y377261I-1400J3609D01*
G03Y378835I-1365J787D01*
G02Y381161I2015J1163D01*
G03Y382735I-1365J787D01*
G02Y385061I2015J1163D01*
G03Y386635I-1365J787D01*
G02Y388961I2015J1163D01*
G03Y390535I-1365J787D01*
G02Y392861I2015J1163D01*
G02X1115265Y392892I597J-344D01*
G03X1115246Y394433I-1384J754D01*
G02X1115221Y396716I2015J1164D01*
G01X1115246Y396758D01*
X1115273Y396806D01*
G03X1115246Y398332I-1392J739D01*
G02X1115211Y400598I2015J1164D01*
G01X1115246Y400658D01*
X1115265Y400692D01*
G03X1115246Y402233I-1384J754D01*
G02Y404559I2015J1163D01*
G03X1115265Y406100I-1365J787D01*
G01X1115246Y406134D01*
X1115221Y406176D01*
G02X1115246Y408459I2040J1119D01*
G02X1117176Y409621I2015J-1163D01*
G01X1117305D01*
G03X1118626Y410409I-44J1575D01*
G01X1118645Y410443D01*
G03X1118626Y411984I-1384J754D01*
G02X1118601Y414267I2015J1164D01*
G01X1118626Y414309D01*
X1118645Y414343D01*
G03X1118626Y415884I-1384J754D01*
G02X1118601Y418167I1858J1162D01*
G01X1118626Y418209D01*
G02X1120571Y419372I2015J-1162D01*
G01X1120700D01*
G03X1122006Y420159I-59J1575D01*
G01X1122216Y420524D01*
Y421248D01*
X1121340Y422124D01*
G01X1113881Y374146D02*
G03X1115896Y376885I-11302J10425D01*
G03Y379211I-2015J1163D01*
G02Y380785I1365J787D01*
G03Y383111I-2015J1163D01*
G02Y384685I1365J787D01*
G03Y387011I-2015J1163D01*
G02Y388585I1365J787D01*
G03Y390911I-2015J1163D01*
G02Y392485I1365J787D01*
G02X1115921Y392525I574J-331D01*
G03X1115896Y394808I-2040J1119D01*
G02X1115869Y396334I1365J787D01*
G01X1115931Y396442D01*
G03X1115896Y398708I-2050J1102D01*
G02X1115877Y400249I1365J787D01*
G01X1115896Y400283D01*
X1115921Y400325D01*
G03X1115896Y402608I-2040J1119D01*
G02Y404184I1365J788D01*
G03X1115921Y406467I-2015J1164D01*
G01X1115896Y406509D01*
X1115877Y406543D01*
G02X1115896Y408084I1384J754D01*
G02X1117202Y408871I1365J-788D01*
G01X1117331D01*
G03X1119276Y410034I-70J2325D01*
G01X1119301Y410076D01*
G03X1119276Y412359I-2040J1119D01*
G02X1119257Y413900I1365J787D01*
G01X1119276Y413934D01*
X1119301Y413976D01*
G03X1119276Y416259I-2040J1119D01*
G02X1119257Y417800I1330J787D01*
G01X1119276Y417834D01*
G02X1120597Y418622I1365J-787D01*
G01X1120726D01*
G03X1122656Y419784I-85J2325D01*
G01X1122966Y420320D01*
Y421250D01*
X1123840Y422124D01*
G01X1100361Y370247D02*
X1098788Y372433D01*
G02X1098346Y375311I1573J1715D01*
G03Y376885I-1365J787D01*
G02Y379211I2015J1163D01*
G03Y380785I-1365J787D01*
G02Y383111I2015J1163D01*
G03Y384685I-1365J787D01*
G02Y387011I2015J1163D01*
G03Y388585I-1365J787D01*
G02Y390911I2015J1163D01*
G01X1098365Y390943D01*
G03X1098346Y392484I-1384J754D01*
G02X1098321Y394767I2015J1164D01*
G01X1098346Y394809D01*
X1098365Y394843D01*
G03X1098346Y396384I-1384J754D01*
G02X1098321Y398667I2015J1164D01*
G01X1098346Y398709D01*
X1098365Y398743D01*
G03X1098346Y400284I-1384J754D01*
G02X1098321Y402567I2015J1164D01*
G01X1098346Y402609D01*
X1098365Y402643D01*
G03X1098346Y404184I-1384J754D01*
G02X1098321Y406467I2015J1164D01*
G01X1098346Y406509D01*
X1098365Y406543D01*
G03X1098346Y408084I-1384J754D01*
G02X1098321Y410367I2015J1164D01*
G01X1098346Y410409D01*
X1098365Y410443D01*
G03X1098346Y411984I-1384J754D01*
G02X1098321Y414267I2015J1164D01*
G01X1098346Y414309D01*
X1098365Y414343D01*
G03X1098346Y415884I-1384J754D01*
G02X1098035Y417047I2015J1162D01*
G01Y417620D01*
X1099556Y419141D01*
Y421308D01*
X1098740Y422124D01*
G01X1100361Y374146D02*
X1099244Y376639D01*
G03X1098996Y377261I-2263J-542D01*
G02Y378835I1365J787D01*
G03Y381161I-2015J1163D01*
G02Y382735I1365J787D01*
G03Y385061I-2015J1163D01*
G02Y386635I1365J787D01*
G03Y388961I-2015J1163D01*
G02Y390535I1365J787D01*
G02X1099021Y390576I847J-488D01*
G03X1098996Y392859I-2040J1119D01*
G02X1098977Y394400I1365J787D01*
G01X1098996Y394434D01*
X1099021Y394476D01*
G03X1098996Y396759I-2040J1119D01*
G02X1098977Y398300I1365J787D01*
G01X1098996Y398334D01*
X1099021Y398376D01*
G03X1098996Y400659I-2040J1119D01*
G02X1098977Y402200I1365J787D01*
G01X1098996Y402234D01*
X1099021Y402276D01*
G03X1098996Y404559I-2040J1119D01*
G02X1098977Y406100I1365J787D01*
G01X1098996Y406134D01*
X1099021Y406176D01*
G03X1098996Y408459I-2040J1119D01*
G02X1098977Y410000I1365J787D01*
G01X1098996Y410034D01*
X1099021Y410076D01*
G03X1098996Y412359I-2040J1119D01*
G02X1098977Y413900I1365J787D01*
G01X1098996Y413934D01*
X1099021Y413976D01*
G03X1098996Y416259I-2040J1119D01*
G02X1098785Y417046I1365J788D01*
G01Y417309D01*
X1100306Y418830D01*
Y421190D01*
X1101240Y422124D01*
G01X1110501Y368296D02*
X1109202Y371296D01*
X1109136Y371410D01*
G02Y372984I1365J787D01*
G01X1109161Y373026D01*
G03X1109136Y375309I-2040J1119D01*
G01X1109117Y375343D01*
G02X1109136Y376884I1384J754D01*
G02X1109526Y377530I16228J-9356D01*
G02X1109976Y378130I993J-276D01*
G02X1110426Y378280I540J-871D01*
G03X1111626Y378880I-161J1821D01*
G03X1111866Y379211I-1465J1315D01*
G03Y380785I-1364J787D01*
G02Y383111I2015J1163D01*
G03Y384685I-1365J787D01*
G02Y387011I2015J1163D01*
G03Y388585I-1365J787D01*
G02Y390909I2015J1162D01*
G01X1111885Y390943D01*
G03X1111866Y392484I-1384J754D01*
G02X1111753Y394587I2015J1163D01*
G02X1111866Y394808I2249J-1011D01*
G03Y396382I-1365J787D01*
G01X1111841Y396424D01*
G02X1111866Y398707I2040J1119D01*
G03X1111885Y400248I-1365J787D01*
G01X1111866Y400282D01*
G02Y402608I2015J1163D01*
G01X1111885Y402642D01*
G03X1111866Y404183I-1384J754D01*
G02X1111831Y406449I2015J1164D01*
G01X1111893Y406557D01*
G03X1111866Y408083I-1392J739D01*
G02X1113811Y411572I2015J1163D01*
G01X1113940D01*
G03X1115265Y413900I-59J1575D01*
G01X1115246Y413934D01*
X1115221Y413976D01*
G02X1115246Y416259I2040J1119D01*
G03X1115457Y417047I-1365J788D01*
G01Y419142D01*
X1117106Y420791D01*
Y421358D01*
X1116340Y422124D01*
G01X1110501Y376096D02*
X1112023Y378144D01*
X1112450Y378718D01*
X1112516Y378834D01*
X1112541Y378876D01*
G03X1112516Y381159I-2040J1119D01*
G02X1112497Y382700I1365J787D01*
G01X1112516Y382734D01*
X1112541Y382776D01*
G03X1112516Y385059I-2040J1119D01*
G02X1112497Y386600I1365J787D01*
G01X1112516Y386634D01*
X1112541Y386676D01*
G03X1112516Y388959I-2040J1119D01*
G02X1112497Y390500I1365J787D01*
G01X1112516Y390534D01*
X1112541Y390576D01*
G03X1112516Y392859I-2040J1119D01*
G02X1112497Y394400I1365J787D01*
G02X1112516Y394432I442J-241D01*
G03X1112541Y396715I-2015J1164D01*
G01X1112516Y396757D01*
X1112497Y396791D01*
G02X1112516Y398332I1384J754D01*
G03Y400658I-2015J1163D01*
G02Y402232I1365J787D01*
G01X1112541Y402274D01*
G03X1112516Y404559I-2040J1120D01*
G02X1112489Y406085I1365J787D01*
G01X1112551Y406193D01*
G03X1112516Y408459I-2050J1102D01*
G02X1113862Y410822I1365J787D01*
G01X1113966D01*
G03X1115921Y414267I-85J2325D01*
G01X1115896Y414309D01*
X1115877Y414343D01*
G02X1115896Y415884I1384J754D01*
G03X1116208Y417047I-2015J1164D01*
G01X1107121Y370247D02*
Y368916D01*
X1106893Y368688D01*
G02X1105737Y371000I228J1559D01*
G01X1105756Y371034D01*
G03X1105781Y373317I-2015J1164D01*
G01X1105756Y373359D01*
G02Y374933I1365J787D01*
G03Y377259I-2015J1163D01*
G02X1105737Y378800I1365J787D01*
G01X1105756Y378834D01*
X1105781Y378876D01*
G03X1105756Y381159I-2040J1119D01*
G02X1105737Y382700I1365J787D01*
G01X1105756Y382734D01*
X1105781Y382776D01*
G03X1105756Y385059I-2040J1119D01*
G02X1105737Y386600I1365J787D01*
G01X1105756Y386634D01*
X1105781Y386676D01*
G03X1105756Y388959I-2040J1119D01*
G02X1105737Y390500I1365J787D01*
G01X1105756Y390534D01*
X1105781Y390576D01*
G03X1105756Y392859I-2040J1119D01*
G02X1105737Y394400I1365J787D01*
G01X1105756Y394434D01*
X1105781Y394476D01*
G03X1105756Y396759I-2040J1119D01*
G02X1105737Y398300I1365J787D01*
G01X1105756Y398334D01*
X1105781Y398376D01*
G03X1105756Y400659I-2040J1119D01*
G02X1105737Y402200I1365J787D01*
G01X1105756Y402234D01*
X1105781Y402276D01*
G03X1105756Y404559I-2040J1119D01*
G02X1105737Y406100I1365J787D01*
G01X1105756Y406134D01*
X1105781Y406176D01*
G03X1105756Y408459I-2040J1119D01*
G02X1105737Y410000I1365J787D01*
G01X1105756Y410034D01*
X1105781Y410076D01*
G03X1105756Y412359I-2040J1119D01*
G02X1107077Y414722I1365J788D01*
G01X1107219D01*
G03X1109448Y417046I-98J2325D01*
G01Y419202D01*
X1109806Y419560D01*
Y422145D01*
X1109961Y422300D01*
Y422387D01*
G01X1107121Y378047D02*
G02X1108486Y381161I14795J-4629D01*
G03Y382735I-1365J787D01*
G02Y385061I2015J1163D01*
G03Y386635I-1365J787D01*
G02Y388961I2015J1163D01*
G03Y390535I-1365J787D01*
G02X1108350Y392585I2012J1163D01*
G02X1108486Y392859I2047J-845D01*
G03X1108513Y394385I-1365J787D01*
G01X1108451Y394493D01*
G02X1108486Y396759I2050J1102D01*
G03X1108513Y398285I-1365J787D01*
G01X1108451Y398393D01*
G02X1108486Y400659I2050J1102D01*
G03X1108513Y402185I-1365J787D01*
G01X1108451Y402293D01*
G02X1108486Y404559I2050J1102D01*
G03X1108513Y406085I-1365J787D01*
G03X1108451Y406193I-1663J-883D01*
G02X1108486Y408459I2050J1102D01*
G03X1108513Y409985I-1365J787D01*
G01X1108451Y410093D01*
G02X1110403Y413520I2050J1102D01*
G01X1110520D01*
G03X1111866Y415884I-19J1576D01*
G02X1111832Y418148I2015J1163D01*
G01X1112023Y418482D01*
X1112025Y418486D01*
X1112756Y419217D01*
Y422895D01*
X1112601Y423050D01*
Y423137D01*
G01X1107121Y366347D02*
Y367678D01*
X1106865Y367934D01*
G02X1105106Y371410I256J2313D01*
G03Y372984I-1365J787D01*
G01X1105081Y373026D01*
G02X1105106Y375309I2040J1119D01*
G01X1105125Y375343D01*
G03X1105106Y376884I-1384J754D01*
G02X1105081Y379167I2015J1164D01*
G01X1105106Y379209D01*
X1105125Y379243D01*
G03X1105106Y380784I-1384J754D01*
G02X1105081Y383067I2015J1164D01*
G01X1105106Y383109D01*
X1105125Y383143D01*
G03X1105106Y384684I-1384J754D01*
G02X1105081Y386967I2015J1164D01*
G01X1105106Y387009D01*
X1105125Y387043D01*
G03X1105106Y388584I-1384J754D01*
G02X1105081Y390867I2015J1164D01*
G01X1105106Y390909D01*
X1105125Y390943D01*
G03X1105106Y392484I-1384J754D01*
G02X1105081Y394767I2015J1164D01*
G01X1105106Y394809D01*
X1105125Y394843D01*
G03X1105106Y396384I-1384J754D01*
G02X1105081Y398667I2015J1164D01*
G01X1105106Y398709D01*
X1105125Y398743D01*
G03X1105106Y400284I-1384J754D01*
G02X1105081Y402567I2015J1164D01*
G01X1105106Y402609D01*
X1105125Y402643D01*
G03X1105106Y404184I-1384J754D01*
G02X1105081Y406467I2015J1164D01*
G01X1105106Y406509D01*
X1105125Y406543D01*
G03X1105106Y408084I-1384J754D01*
G02X1105081Y410367I2015J1164D01*
G01X1105106Y410409D01*
X1105125Y410443D01*
G03X1105106Y411984I-1384J754D01*
G02X1107051Y415472I2015J1163D01*
G01X1107201D01*
G03X1108698Y417046I-80J1575D01*
G01Y419513D01*
X1109056Y419871D01*
Y422145D01*
X1108901Y422300D01*
Y422387D01*
G01X1107121Y374146D02*
G02X1108486Y377261I14855J-4653D01*
G03X1108683Y378252I-1365J786D01*
G02X1109136Y380785I4215J553D01*
G03Y383111I-2015J1163D01*
G02Y384685I1365J787D01*
G03Y387011I-2015J1163D01*
G02Y388585I1365J787D01*
G03Y390911I-2015J1163D01*
G02X1109015Y392220I1371J787D01*
G02X1109136Y392484I1473J-515D01*
G03X1109161Y394767I-2015J1164D01*
G01X1109136Y394809D01*
X1109109Y394857D01*
G02X1109136Y396383I1392J739D01*
G03X1109171Y398649I-2015J1164D01*
G01X1109161Y398666D01*
X1109109Y398757D01*
G02X1109136Y400283I1392J739D01*
G03X1109171Y402549I-2015J1164D01*
G01X1109109Y402657D01*
G02X1109136Y404183I1392J739D01*
G03X1109171Y406449I-2015J1164D01*
G03X1109109Y406557I-1966J-1057D01*
G02X1109136Y408083I1392J739D01*
G03X1109171Y410349I-2015J1164D01*
G01X1109109Y410457D01*
G02X1110442Y412770I1392J738D01*
G01X1110571D01*
G03X1112516Y416259I-69J2325D01*
G02X1112489Y417785I1365J787D01*
G01X1112627Y418027D01*
X1113506Y418906D01*
Y422895D01*
X1113661Y423050D01*
Y423137D01*
G01X1210059Y380067D02*
X1209972D01*
X1209772Y379867D01*
X1208687D01*
X1205026Y381383D01*
X1203485Y382413D01*
X1200929Y382665D01*
X1199197Y382321D01*
X1198335D01*
G02X1197014Y383109I44J1575D01*
G03X1192984I-2015J-1162D01*
G02X1190254I-1365J787D01*
G03X1188309Y384272I-2015J-1162D01*
G01X1188180D01*
G02X1186874Y385059I59J1575D01*
G03X1184944Y386221I-2015J-1163D01*
G01X1184815D01*
G02X1183494Y387009I44J1575D01*
G03X1181549Y388172I-2015J-1162D01*
G01X1181420D01*
G02X1180095Y390500I59J1575D01*
G01X1180114Y390534D01*
X1180139Y390576D01*
G03X1178150Y394022I-2040J1120D01*
G01X1178055D01*
G02X1176734Y394810I44J1575D01*
G03X1174804Y395972I-2015J-1163D01*
G01X1174648D01*
G02X1173354Y396759I71J1574D01*
G03X1171424Y397921I-2015J-1163D01*
G01X1171339D01*
G02X1169988Y398686I0J1575D01*
G01X1169975Y398709D01*
G03X1168011Y399872I-2015J-1163D01*
G01X1167901D01*
G02X1166595Y400659I59J1575D01*
G03X1162552Y400637I-2015J-1163D01*
G02X1161201Y399872I-1351J810D01*
G01X1161150Y399873D01*
G03X1159185Y398709I51J-2326D01*
G02X1157891Y397922I-1365J787D01*
G01Y397921D01*
G02X1157733I-79J1576D01*
G03X1156930Y397746I86J-2325D01*
G02X1155923Y397546I-1007J2436D01*
G01X1154440D01*
G01Y393647D02*
Y392316D01*
X1154668Y392088D01*
G03X1155805Y392859I-228J1560D01*
G02X1157769Y394022I2015J-1163D01*
G01X1157864D01*
G03X1159185Y394810I-44J1575D01*
G02X1161115Y395972I2015J-1163D01*
G01X1161271D01*
G03X1162565Y396759I-71J1574D01*
G02X1164510Y397922I2015J-1162D01*
G01X1164650D01*
G02X1166595Y396759I-70J-2325D01*
G03X1167889Y395972I1365J787D01*
G01X1168045D01*
G02X1169975Y394810I-85J-2325D01*
G01X1169988Y394787D01*
G03X1171339Y394022I1351J810D01*
G01X1171390D01*
G02X1173354Y392859I-51J-2326D01*
G03X1174660Y392072I1365J788D01*
G01X1174789D01*
G02X1176734Y388584I-70J-2325D01*
G03X1178055Y386221I1365J-788D01*
G01X1178184D01*
G02X1180114Y385059I-85J-2325D01*
G03X1181420Y384272I1365J788D01*
G01X1181549D01*
G02X1183494Y383109I-70J-2325D01*
G03X1184815Y382321I1365J787D01*
G01X1184944D01*
G02X1186874Y381159I-85J-2325D01*
G03X1188180Y380372I1365J788D01*
G01X1188309D01*
G02X1190254Y379209I-70J-2325D01*
G03X1192984I1365J787D01*
G02X1197014I2015J-1162D01*
G03X1199744I1365J787D01*
G02X1200032Y379611I2167J-1249D01*
G02X1200108Y379693I1872J-1659D01*
G01X1200065Y379650D01*
Y379645D01*
X1200970Y380550D01*
X1201955D01*
X1203928Y379733D01*
X1206711Y376950D01*
X1207900D01*
X1208100Y377150D01*
X1208187D01*
G01X1151060Y387796D02*
X1152214Y387131D01*
X1152566Y387226D01*
G02X1154370Y388172I1873J-1379D01*
G01X1154499D01*
G03X1155805Y388959I-59J1575D01*
G02X1157735Y390121I2015J-1163D01*
G01X1157905D01*
G02X1159835Y388959I-85J-2325D01*
G03X1161141Y388172I1365J788D01*
G01X1161259D01*
G03X1162565Y388959I-59J1575D01*
G02X1164495Y390121I2015J-1163D01*
G01X1164665D01*
G02X1166595Y388959I-85J-2325D01*
G03X1167901Y388172I1365J788D01*
G01X1168030D01*
G02X1169975Y384683I-69J-2325D01*
G03X1171339Y382321I1364J-787D01*
G01X1171424D01*
G02X1173354Y381159I-85J-2325D01*
G03X1174660Y380372I1365J788D01*
G01X1174789D01*
G02X1176734Y379209I-70J-2325D01*
G03X1178055Y378421I1365J787D01*
G01X1178184D01*
G02X1180114Y377259I-85J-2325D01*
G03X1181420Y376472I1365J788D01*
G01X1181530D01*
G02X1183494Y375309I-51J-2326D01*
G03X1184788Y374522I1365J787D01*
G01X1184929D01*
G02X1186874Y373359I-70J-2325D01*
G03X1188168Y372572I1365J787D01*
G01X1188324D01*
G02X1190254Y371410I-85J-2325D01*
G03X1192984I1365J787D01*
G02X1194914Y372572I2015J-1163D01*
G01X1195084D01*
G02X1197014Y371410I-85J-2325D01*
G03X1197851Y370676I1499J865D01*
G01X1199466Y370007D01*
X1203625D01*
X1208618Y367948D01*
X1208878Y368058D01*
X1208959Y368024D01*
G01X1210059Y378917D02*
X1209972D01*
X1209772Y379117D01*
X1208537D01*
X1206686Y379883D01*
X1206176Y379672D01*
X1205528Y379940D01*
X1205317Y380451D01*
Y380450D01*
X1204671Y380718D01*
X1203224Y381685D01*
X1200966Y381907D01*
X1199271Y381571D01*
X1198325D01*
G02X1196364Y382734I54J2325D01*
G03X1193634I-1365J-787D01*
G02X1189604I-2015J1162D01*
G03X1188283Y383522I-1365J-787D01*
G01X1188154D01*
G02X1186224Y384684I85J2325D01*
G03X1184918Y385471I-1365J-788D01*
G01X1184789D01*
G02X1182844Y386634I70J2325D01*
G03X1181523Y387422I-1365J-787D01*
G01X1181394D01*
G02X1179439Y390867I85J2325D01*
G01X1179464Y390909D01*
X1179483Y390943D01*
G03X1178158Y393271I-1384J753D01*
G01X1178048D01*
G02X1176084Y394434I51J2326D01*
G03X1174790Y395221I-1365J-787D01*
G01X1174634D01*
G02X1172704Y396383I85J2325D01*
G03X1171383Y397171I-1365J-787D01*
G01X1171254D01*
G02X1169324Y398333I85J2325D01*
G01X1169311Y398356D01*
G03X1167960Y399121I-1351J-810D01*
G01X1167909D01*
G02X1165945Y400284I51J2326D01*
G03X1163229Y400306I-1364J-788D01*
G01X1163216Y400283D01*
G02X1161270Y399120I-2016J1163D01*
G01X1161200Y399121D01*
X1161156D01*
G03X1159835Y398333I44J-1575D01*
G02X1157905Y397171I-2015J1163D01*
G01X1157749D01*
G03X1157217Y397053I70J-1574D01*
G03X1156583Y396572I605J-1455D01*
G01X1156666Y396262D01*
X1157820Y395597D01*
G01X1154440Y389747D02*
Y391078D01*
X1154696Y391334D01*
G03X1156455Y392484I-256J2312D01*
G02X1157761Y393271I1365J-788D01*
G01X1157871D01*
G03X1159835Y394434I-51J2326D01*
G02X1161129Y395221I1365J-787D01*
G01X1161270D01*
G03X1163215Y396384I-70J2325D01*
G02X1164509Y397171I1365J-787D01*
G01X1164651D01*
G02X1165945Y396384I-71J-1574D01*
G03X1167890Y395221I2015J1162D01*
G01X1168008D01*
G02X1169324Y394434I-48J-1574D01*
G03X1171288Y393271I2015J1163D01*
G01X1171398D01*
G02X1172704Y392484I-59J-1575D01*
G03X1174634Y391322I2015J1163D01*
G01X1174763D01*
G02X1176084Y388959I-44J-1575D01*
G03X1178029Y385471I2015J-1163D01*
G01X1178158D01*
G02X1179464Y384684I-59J-1575D01*
G03X1181394Y383522I2015J1163D01*
G01X1181523D01*
G02X1182844Y382734I-44J-1575D01*
G03X1184789Y381571I2015J1162D01*
G01X1184918D01*
G02X1186224Y380784I-59J-1575D01*
G03X1188154Y379622I2015J1163D01*
G01X1188283D01*
G02X1189604Y378834I-44J-1575D01*
G03X1193634I2015J1161D01*
G02X1196364I1365J-786D01*
G03X1200394I2015J1160D01*
G02X1200589Y379107I1516J-876D01*
G01X1201282Y379800D01*
X1201805D01*
X1203503Y379097D01*
X1206400Y376200D01*
X1207900D01*
X1208100Y376000D01*
X1208187D01*
G01X1154440Y385847D02*
X1153286Y386512D01*
X1153203Y386822D01*
G02X1154396Y387422I1238J-975D01*
G01X1154525D01*
G03X1156455Y388584I-85J2325D01*
G02X1157761Y389371I1365J-788D01*
G01X1157879D01*
G02X1159185Y388584I-59J-1575D01*
G03X1161115Y387422I2015J1163D01*
G01X1161285D01*
G03X1163215Y388584I-85J2325D01*
G02X1164521Y389371I1365J-788D01*
G01X1164639D01*
G02X1165945Y388584I-59J-1575D01*
G03X1167875Y387422I2015J1163D01*
G01X1167960D01*
G02X1169324Y385060I0J-1575D01*
G03X1171269Y381571I2015J-1163D01*
G01X1171398D01*
G02X1172704Y380784I-59J-1575D01*
G03X1174634Y379622I2015J1163D01*
G01X1174763D01*
G02X1176084Y378834I-44J-1575D01*
G03X1178029Y377671I2015J1162D01*
G01X1178158D01*
G02X1179464Y376884I-59J-1575D01*
G03X1181428Y375721I2015J1163D01*
G01X1181523D01*
G02X1182844Y374933I-44J-1575D01*
G03X1184774Y373771I2015J1163D01*
G01X1184930D01*
G02X1186224Y372984I-71J-1574D01*
G03X1188169Y371821I2015J1162D01*
G01X1188310D01*
G02X1189604Y371034I-71J-1574D01*
G03X1193634I2015J1163D01*
G02X1194928Y371821I1365J-787D01*
G01X1194950Y371822D01*
X1195068D01*
G02X1196364Y371035I-69J-1575D01*
G03X1197564Y369983I2148J1240D01*
G01X1199316Y369257D01*
X1200471D01*
X1200869Y368859D01*
X1201569D01*
X1201967Y369257D01*
X1203476D01*
X1204123Y368991D01*
X1204339Y368470D01*
X1204987Y368203D01*
X1205507Y368419D01*
X1206154Y368153D01*
X1206370Y367632D01*
X1207018Y367365D01*
X1207538Y367581D01*
X1208332Y367254D01*
X1208439Y366994D01*
X1208520Y366961D01*
G01X1116208Y417047D02*
Y418819D01*
X1117856Y420467D01*
Y421140D01*
X1118840Y422124D01*
G01X1206867Y292821D02*
X1206780D01*
X1206580Y292621D01*
X1204639D01*
G03X1203267Y291448I800J-2325D01*
G02X1202416Y290672I-1508J799D01*
G01X1201700D01*
G02X1200394Y291459I59J1575D01*
G03X1198464Y292621I-2015J-1163D01*
G01X1198335D01*
G02X1197014Y293409I44J1575D01*
G03X1195001Y294572I-2013J-1161D01*
G01X1194997D01*
G03X1192984Y293409I0J-2324D01*
G02X1190254I-1365J787D01*
G03X1188309Y294572I-2015J-1162D01*
G01X1188180D01*
G02X1186874Y295359I59J1575D01*
G03X1184944Y296521I-2015J-1163D01*
G01X1184815D01*
G02X1184202Y296664I44J1575D01*
G02X1183622Y297121I658J1431D01*
G01X1183705Y297431D01*
X1184859Y298096D01*
G01X1207738Y295571D02*
X1207651D01*
X1207451Y295771D01*
X1204269D01*
X1202318Y297722D01*
X1194955D01*
G03X1193634Y296934I44J-1575D01*
G02X1189604I-2015J1162D01*
G03X1188467Y297706I-1365J-787D01*
G01X1188239Y297478D01*
Y296147D01*
G01X1181479D02*
G02X1183888Y295982I987J-3265D01*
G03X1184789Y295771I970J2114D01*
G01X1184918D01*
G02X1186224Y294984I-59J-1575D01*
G03X1188154Y293822I2015J1163D01*
G01X1188283D01*
G02X1189604Y293034I-44J-1575D01*
G03X1193634I2015J1162D01*
G02X1194998Y293822I1364J-786D01*
G01X1195000D01*
G02X1196364Y293034I0J-1574D01*
G03X1198325Y291871I2015J1162D01*
G01X1198438D01*
G02X1199744Y291084I-59J-1575D01*
G03X1201674Y289922I2015J1163D01*
G01X1202559D01*
G03X1203931Y291095I-800J2325D01*
G02X1204782Y291871I1508J-799D01*
G01X1206580D01*
X1206780Y291671D01*
X1206867D01*
G01X1161200Y288347D02*
Y289678D01*
X1161428Y289906D01*
G02X1162565Y289134I-228J-1559D01*
G01X1162584Y289100D01*
G02X1162565Y287559I-1384J-754D01*
G03X1162540Y285276I2015J-1164D01*
G01X1162565Y285234D01*
X1162584Y285200D01*
G02X1162565Y283659I-1384J-754D01*
G03X1162540Y281376I2015J-1164D01*
G01X1162565Y281334D01*
X1162584Y281300D01*
G02X1162565Y279759I-1384J-754D01*
G03Y277433I2015J-1163D01*
G02Y275859I-1365J-787D01*
G03X1162540Y273576I2015J-1164D01*
G01X1162565Y273534D01*
X1162584Y273500D01*
G02X1162565Y271959I-1384J-754D01*
G03X1162540Y269676I2015J-1164D01*
G01X1162556Y269649D01*
X1162562Y269638D01*
X1162565Y269634D01*
G02X1162776Y268847I-1365J-788D01*
G01Y266832D01*
X1163898Y265710D01*
Y259533D01*
X1165946Y255984D01*
G02X1165971Y254457I-1366J-786D01*
G01X1165945Y254409D01*
X1165920Y254367D01*
G03X1165945Y252084I2040J-1119D01*
G02X1165964Y250543I-1365J-787D01*
G01X1165945Y250509D01*
X1165920Y250467D01*
G03X1165945Y248184I2040J-1119D01*
G02X1165964Y246643I-1365J-787D01*
G01X1165945Y246609D01*
X1165920Y246567D01*
G03X1165945Y244284I2040J-1119D01*
G02X1165964Y242743I-1365J-787D01*
G01X1165945Y242709D01*
X1165920Y242667D01*
G03X1165945Y240384I2040J-1119D01*
G02X1165964Y238843I-1365J-787D01*
G01X1165945Y238809D01*
X1165920Y238767D01*
G03X1165945Y236484I2040J-1119D01*
G02X1165964Y234943I-1365J-787D01*
G01X1165945Y234909D01*
G03X1165920Y232626I2015J-1164D01*
G01X1165945Y232584D01*
G02Y231010I-1365J-787D01*
G03Y228684I2015J-1163D01*
G02X1165964Y227143I-1365J-787D01*
G01X1165945Y227109D01*
X1165920Y227067D01*
G03X1165945Y224784I2040J-1119D01*
G02X1165964Y223243I-1365J-787D01*
G01X1165945Y223209D01*
X1165920Y223167D01*
G03X1165945Y220884I2040J-1119D01*
G02X1165964Y219343I-1365J-787D01*
G01X1165945Y219309D01*
X1165920Y219267D01*
G03X1165945Y216984I2040J-1119D01*
G02X1165964Y215443I-1365J-787D01*
G01X1165945Y215409D01*
X1165920Y215367D01*
G03X1165945Y213084I2040J-1119D01*
G03X1167909Y211921I2015J1163D01*
G01X1167960D01*
G02X1169311Y211156I0J-1575D01*
G01X1169324Y211133D01*
G03X1171254Y209971I2015J1163D01*
G01X1171410D01*
G02X1172704Y209184I-71J-1574D01*
G03X1174649Y208021I2015J1162D01*
G01X1174790D01*
G02X1176084Y207234I-71J-1574D01*
G03X1178048Y206071I2015J1163D01*
G01X1178158D01*
G02X1179464Y205284I-59J-1575D01*
G03X1181394Y204122I2015J1163D01*
G01X1181523D01*
G02X1182844Y203334I-44J-1575D01*
G03X1183214Y202851I2016J1161D01*
G01X1184491Y200775D01*
X1186283Y199760D01*
X1189394D01*
X1190136Y199018D01*
Y198523D01*
X1190879Y197780D01*
X1191374D01*
X1192126Y197028D01*
X1192125Y196748D01*
X1192186Y196687D01*
G01X1161200Y292247D02*
Y290916D01*
X1161457Y290659D01*
G02X1163215Y289509I-257J-2312D01*
G01X1163240Y289467D01*
G02X1163215Y287184I-2040J-1119D01*
G03X1163196Y285643I1365J-787D01*
G01X1163215Y285609D01*
X1163240Y285567D01*
G02X1163215Y283284I-2040J-1119D01*
G03X1163196Y281743I1365J-787D01*
G01X1163215Y281709D01*
X1163240Y281667D01*
G02X1163215Y279384I-2040J-1119D01*
G03X1163196Y277843I1365J-787D01*
G01X1163215Y277809D01*
G02Y275483I-2015J-1163D01*
G03Y273909I1365J-787D01*
G01X1163240Y273867D01*
G02X1163215Y271584I-2040J-1119D01*
G03X1163196Y270043I1365J-787D01*
G01X1163215Y270009D01*
G02X1163526Y268847I-2015J-1162D01*
G01Y267143D01*
X1164648Y266021D01*
Y259734D01*
X1166596Y256359D01*
G02X1166623Y254084I-2016J-1162D01*
G01X1166620Y254079D01*
X1166611Y254062D01*
X1166576Y254000D01*
G03X1166595Y252459I1384J-754D01*
G02X1166620Y250176I-2015J-1164D01*
G01X1166595Y250134D01*
X1166576Y250100D01*
G03X1166595Y248559I1384J-754D01*
G02X1166620Y246276I-2015J-1164D01*
G01X1166595Y246234D01*
X1166576Y246200D01*
G03X1166595Y244659I1384J-754D01*
G02X1166620Y242376I-2015J-1164D01*
G01X1166595Y242334D01*
X1166576Y242300D01*
G03X1166595Y240759I1384J-754D01*
G02X1166620Y238476I-2015J-1164D01*
G01X1166595Y238434D01*
X1166576Y238400D01*
G03X1166595Y236859I1384J-754D01*
G02Y234533I-2015J-1163D01*
G03Y232959I1365J-787D01*
G01X1166620Y232917D01*
G02X1166595Y230634I-2040J-1119D01*
G01X1166576Y230600D01*
G03X1166595Y229059I1384J-754D01*
G02X1166620Y226776I-2015J-1164D01*
G01X1166595Y226734D01*
X1166576Y226700D01*
G03X1166595Y225159I1384J-754D01*
G02X1166620Y222876I-2015J-1164D01*
G01X1166595Y222834D01*
X1166576Y222800D01*
G03X1166595Y221259I1384J-754D01*
G02X1166620Y218976I-2015J-1164D01*
G01X1166595Y218934D01*
X1166576Y218900D01*
G03X1166595Y217359I1384J-754D01*
G02X1166620Y215076I-2015J-1164D01*
G01X1166595Y215034D01*
X1166576Y215000D01*
G03X1166595Y213459I1384J-754D01*
G03X1167901Y212672I1365J788D01*
G01X1168011D01*
G02X1169975Y211509I-51J-2326D01*
G03X1171291Y210722I1364J787D01*
G01X1171409D01*
G02X1173354Y209559I-70J-2325D01*
G03X1174648Y208772I1365J787D01*
G01X1174804D01*
G02X1176734Y207610I-85J-2325D01*
G03X1178055Y206822I1365J787D01*
G01X1178150D01*
G02X1180114Y205659I-51J-2326D01*
G03X1181420Y204872I1365J788D01*
G01X1181549D01*
G02X1183494Y203709I-70J-2325D01*
G03X1183642Y203496I1363J789D01*
G03X1183745Y203381I1224J992D01*
G01X1183807Y203319D01*
X1185029Y201333D01*
X1186481Y200510D01*
X1189705D01*
X1192654Y197561D01*
X1192939D01*
X1193000Y197500D01*
G01X1207738Y296721D02*
X1207651D01*
X1207451Y296521D01*
X1204580D01*
X1202629Y298472D01*
X1194945D01*
G03X1192984Y297309I54J-2325D01*
G02X1190254I-1365J787D01*
G03X1188496Y298459I-2015J-1162D01*
G01X1188239Y298716D01*
Y300047D01*
G01X1208963Y311832D02*
X1208876D01*
X1208676Y311632D01*
X1207646D01*
X1206933Y312121D01*
X1198322D01*
G02X1198308Y312122I105J1571D01*
G02X1197014Y312909I71J1574D01*
G03X1193125Y313126I-2015J-1162D01*
G01X1192773Y313031D01*
X1191619Y313696D01*
G01X1206987Y308422D02*
X1206900D01*
X1206700Y308222D01*
X1198310D01*
G02X1197014Y309009I69J1575D01*
G03X1195088Y310172I-2015J-1161D01*
G01X1195044Y310174D01*
G03X1194955I-44J-1103D01*
G01X1194910Y310172D01*
G03X1192984Y309010I89J-2324D01*
G02X1191847Y308238I-1365J787D01*
G01X1191619Y308466D01*
Y309797D01*
G01X1207171Y304200D02*
X1207084D01*
X1206884Y304000D01*
X1202896D01*
X1202497Y304399D01*
X1201797D01*
X1201398Y304000D01*
X1200698D01*
X1200299Y304399D01*
X1199599D01*
X1199200Y304000D01*
X1198500D01*
X1197112Y305388D01*
G03X1195084Y306272I-2138J-2138D01*
G01X1194941D01*
G03X1192984Y305109I58J-2325D01*
G02X1190254I-1365J787D01*
G03X1188309Y306272I-2015J-1162D01*
G01X1188180D01*
G02X1187002Y306871I60J1575D01*
G01X1187085Y307181D01*
X1188239Y307847D01*
G01X1208025Y299550D02*
X1207938D01*
X1207738Y299750D01*
X1197689D01*
X1195960Y301479D01*
X1195310Y301592D01*
X1195291Y301595D01*
G03X1195068Y301622I-300J-1547D01*
G01X1194955D01*
G03X1193634Y300834I44J-1575D01*
G02X1191689Y299671I-2015J1162D01*
G01X1191549D01*
G02X1189487Y302929I69J2325D01*
G01X1189393Y303281D01*
X1188239Y303947D01*
G01X1184859Y344896D02*
Y343565D01*
X1185087Y343337D01*
G03X1186224Y344109I-228J1559D01*
G02X1188169Y345272I2015J-1162D01*
G01X1188298D01*
G03X1189604Y346059I-59J1575D01*
G02X1191534Y347221I2015J-1163D01*
G01X1191676D01*
G03X1192984Y348009I-57J1575D01*
G01X1193033Y348095D01*
X1193042Y348104D01*
G02X1194939Y349172I1954J-1253D01*
G01X1194941D01*
G02X1195068I64J-2325D01*
G02X1197014Y348009I-69J-2325D01*
G03X1198335Y347221I1365J787D01*
G01X1198464D01*
G02X1200394Y346059I-85J-2325D01*
G03X1201700Y345272I1365J788D01*
G01X1205629D01*
X1210151Y340750D01*
X1211800D01*
X1212000Y340950D01*
X1212087D01*
G01X1191619Y344896D02*
X1190465Y344231D01*
X1190382Y343921D01*
G03X1191572Y343322I1237J976D01*
G03X1191667I47J1575D01*
G03X1192984Y344109I-47J1575D01*
G01X1193033Y344195D01*
X1193042Y344204D01*
G02X1194939Y345272I1954J-1253D01*
G01X1194941D01*
G02X1195068I64J-2325D01*
G02X1197014Y344109I-69J-2325D01*
G03X1198335Y343321I1365J787D01*
G01X1198464D01*
G02X1200394Y342159I-85J-2325D01*
G03X1201700Y341372I1365J788D01*
G01X1201829D01*
G02X1203774Y340209I-70J-2325D01*
G01X1203820Y340129D01*
X1203866Y340050D01*
X1206438Y337478D01*
X1210746D01*
X1211096Y337828D01*
X1212146D01*
X1212496Y337478D01*
X1216250D01*
X1216955Y336945D01*
X1217315Y336996D01*
X1217384Y336944D01*
G01X1191619Y340996D02*
X1193026D01*
G03X1194140Y341209I0J3020D01*
G01X1194205Y341235D01*
G02X1194858Y341370I709J-1780D01*
G01X1194930Y341372D01*
G02X1195070I70J-2324D01*
G02X1197014Y340209I-71J-2324D01*
G03X1198335Y339421I1365J787D01*
G01X1198464D01*
G02X1200394Y338259I-85J-2325D01*
G03X1201690Y337472I1365J788D01*
G01X1203069D01*
X1205014Y335527D01*
X1214117D01*
X1214972Y334906D01*
X1215313D01*
X1215321Y334900D01*
G01X1191619Y337096D02*
Y335765D01*
X1191847Y335537D01*
G03X1192984Y336309I-228J1559D01*
G01X1193033Y336395D01*
X1193042Y336404D01*
G02X1194939Y337472I1954J-1253D01*
G01X1194941D01*
G02X1195068I64J-2325D01*
G02X1197014Y336309I-69J-2325D01*
G03X1198335Y335521I1365J787D01*
G01X1198464D01*
G02X1200394Y334359I-85J-2325D01*
G03X1201700Y333572I1365J788D01*
G01X1201829D01*
G02X1203775Y332409I-69J-2325D01*
G01X1203940Y332121D01*
X1205601Y330462D01*
X1206945D01*
X1207145Y330662D01*
X1207232D01*
G01X1188239Y331247D02*
X1189393Y330581D01*
X1189745Y330676D01*
G02X1191534Y331621I1873J-1380D01*
G02X1191547I7J-2326D01*
G01X1191676D01*
G03X1192984Y332409I-57J1575D01*
G01X1192996Y332430D01*
X1192999Y332435D01*
G02X1194934Y333572I1995J-1180D01*
G01X1194941D01*
G02X1195068I64J-2325D01*
G02X1197014Y332409I-69J-2325D01*
G03X1198335Y331621I1365J787D01*
G01X1198464D01*
G02X1200394Y330459I-85J-2325D01*
G01X1200960Y329478D01*
X1201838Y328600D01*
X1203600D01*
X1204400Y327800D01*
X1209901D01*
X1210101Y328000D01*
X1210188D01*
G01X1210883Y324054D02*
X1210796D01*
X1210596Y324254D01*
X1209864D01*
X1209473Y323863D01*
X1208773D01*
X1208374Y324262D01*
X1207674D01*
X1207275Y323863D01*
X1206575D01*
X1206176Y324262D01*
X1205476D01*
X1205077Y323863D01*
X1204377D01*
X1203978Y324262D01*
X1203278D01*
X1202240Y325300D01*
X1200739D01*
X1199068Y326971D01*
X1198309D01*
G02X1196364Y328134I70J2325D01*
G03X1195047Y328921I-1364J-788D01*
G03X1194952I-47J-1575D01*
G03X1193528Y327910I47J-1575D01*
G03X1193535Y326765I1471J-564D01*
G01X1193845Y326681D01*
X1194999Y327347D01*
G01X1210096Y322070D02*
X1210009D01*
X1209809Y321870D01*
X1201759D01*
G02X1200411Y322630I0J1575D01*
G01X1200394Y322659D01*
G03X1198464Y323821I-2015J-1163D01*
G01X1198335D01*
G02X1197014Y324609I44J1575D01*
G03X1192984I-2015J-1163D01*
G02X1190254I-1365J787D01*
G03X1188496Y325759I-2015J-1162D01*
G01X1188239Y326016D01*
Y327347D01*
G01X1184859Y317596D02*
Y316265D01*
X1185087Y316037D01*
G03X1186224Y316809I-228J1559D01*
G02X1188169Y317972I2015J-1162D01*
G01X1188298D01*
G03X1189604Y318759I-59J1575D01*
G02X1191534Y319921I2015J-1163D01*
G01X1191663D01*
G03X1192984Y320709I-44J1575D01*
G02X1194929Y321872I2015J-1162D01*
G01X1195069D01*
G02X1197014Y320709I-70J-2325D01*
G03X1198308Y319922I1365J787D01*
G01X1199979D01*
X1202489Y317412D01*
X1209034D01*
X1209234Y317612D01*
X1209321D01*
G01X1191619Y317596D02*
X1190465Y316931D01*
X1190382Y316621D01*
G03X1191572Y316021I1237J974D01*
G01X1191590D01*
G03X1191649I29J978D01*
G01X1191667D01*
G03X1192984Y316809I-48J1574D01*
G02X1194929Y317972I2015J-1162D01*
G01X1196328D01*
X1197900Y316400D01*
X1199201D01*
X1200949Y314652D01*
X1201649D01*
X1202048Y315051D01*
X1202748D01*
X1203147Y314652D01*
X1203847D01*
X1204246Y315051D01*
X1204946D01*
X1205345Y314652D01*
X1208565D01*
X1208765Y314852D01*
X1208852D01*
G01X1188239Y346847D02*
X1187085Y347512D01*
X1187002Y347822D01*
G02X1188195Y348422I1238J-975D01*
G01X1188324D01*
G03X1190254Y349584I-85J2325D01*
G02X1191560Y350371I1365J-788D01*
G01X1191689D01*
G03X1193634Y351534I-70J2325D01*
G01X1193636Y351536D01*
G02X1193674Y351599I1364J-780D01*
G02X1194950Y352322I1323J-847D01*
G01X1194952D01*
G02X1195046I47J-1575D01*
G02X1196364Y351534I-47J-1575D01*
G03X1198309Y350371I2015J1162D01*
G01X1198438D01*
G02X1199744Y349584I-59J-1575D01*
G03X1201687Y348422I2015J1163D01*
G01X1204528D01*
X1205022Y347928D01*
Y347375D01*
X1205517Y346880D01*
X1206070D01*
X1206564Y346386D01*
Y345833D01*
X1207059Y345338D01*
X1207612D01*
X1210450Y342500D01*
X1213437D01*
X1213637Y342300D01*
X1213724D01*
G01X1208963Y310682D02*
X1208876D01*
X1208676Y310882D01*
X1207413D01*
X1206700Y311371D01*
X1203220D01*
X1202821Y310972D01*
X1202121D01*
X1201722Y311371D01*
X1201022D01*
X1200623Y310972D01*
X1199923D01*
X1199524Y311371D01*
X1198309D01*
G02X1196364Y312534I70J2325D01*
G03X1193762Y312722I-1365J-787D01*
G01X1193845Y312412D01*
X1194999Y311747D01*
G01X1206987Y307272D02*
X1206900D01*
X1206700Y307472D01*
X1198294D01*
G02X1196364Y308634I85J2325D01*
G03X1195057Y309422I-1365J-786D01*
G01X1195012Y309424D01*
G03X1194986I-13J-353D01*
G01X1194941Y309422D01*
G03X1193634Y308634I58J-1574D01*
G02X1191876Y307484I-2015J1162D01*
G01X1191619Y307227D01*
Y305896D01*
G01X1207171Y303050D02*
X1207084D01*
X1206884Y303250D01*
X1198189D01*
X1196581Y304858D01*
Y304857D01*
G03X1195069Y305522I-1609J-1606D01*
G01X1194952D01*
G03X1193634Y304734I47J-1575D01*
G02X1189604I-2015J1162D01*
G03X1188283Y305522I-1365J-787D01*
G01X1188154D01*
G02X1186365Y306467I84J2325D01*
G01X1186013Y306562D01*
X1184859Y305896D01*
G01X1208025Y300700D02*
X1207938D01*
X1207738Y300500D01*
X1206774D01*
X1206384Y300890D01*
X1205684D01*
X1205294Y300500D01*
X1204594D01*
X1204195Y300899D01*
X1203495D01*
X1203096Y300500D01*
X1202396D01*
X1201997Y300899D01*
X1201297D01*
X1200898Y300500D01*
X1200198D01*
X1199799Y300899D01*
X1199099D01*
X1198700Y300500D01*
X1198000D01*
X1196323Y302178D01*
X1196316Y302179D01*
X1195439Y302332D01*
X1195431Y302333D01*
G03X1195084Y302372I-433J-2286D01*
G01X1194929D01*
G03X1192984Y301209I70J-2325D01*
G02X1191667Y300422I-1364J788D01*
G02X1191572I-47J1575D01*
G02X1190155Y302578I47J1575D01*
G01X1190465Y302662D01*
X1191619Y301996D01*
G01X1184859Y340996D02*
Y342327D01*
X1185116Y342584D01*
G03X1186874Y343734I-257J2312D01*
G02X1188195Y344522I1365J-787D01*
G01X1188324D01*
G03X1190254Y345684I-85J2325D01*
G02X1191560Y346471I1365J-788D01*
G01X1191689D01*
G03X1193634Y347634I-70J2325D01*
G01X1193636Y347636D01*
G02X1193674Y347699I1364J-780D01*
G02X1194950Y348422I1323J-847D01*
G01X1194952D01*
G02X1195046I47J-1575D01*
G02X1196364Y347634I-47J-1575D01*
G03X1198309Y346471I2015J1162D01*
G01X1198438D01*
G02X1199744Y345684I-59J-1575D01*
G03X1201687Y344522I2015J1163D01*
G01X1205318D01*
X1209840Y340000D01*
X1211800D01*
X1212000Y339800D01*
X1212087D01*
G01X1188239Y342947D02*
X1189228Y343517D01*
X1189745D01*
G03X1191549Y342571I1873J1379D01*
G01X1191689D01*
G03X1193634Y343734I-70J2325D01*
G01X1193636Y343736D01*
G02X1193674Y343799I1364J-780D01*
G02X1194950Y344522I1323J-847D01*
G01X1194952D01*
G02X1195046I47J-1575D01*
G02X1196364Y343734I-47J-1575D01*
G03X1198309Y342571I2015J1162D01*
G01X1198438D01*
G02X1199744Y341784I-59J-1575D01*
G03X1201674Y340622I2015J1163D01*
G01X1201816D01*
G02X1203124Y339834I-57J-1575D01*
G01Y339833D01*
X1203266Y339589D01*
X1206127Y336728D01*
X1215998D01*
X1216594Y336277D01*
X1216620Y336079D01*
X1216689Y336027D01*
G01X1194999Y339047D02*
X1194630Y339260D01*
X1193845Y339712D01*
X1193762Y340022D01*
G02X1194417Y340511I1237J-974D01*
G01X1194421Y340513D01*
X1194484Y340538D01*
G02X1194880Y340620I431J-1083D01*
G01X1194952Y340622D01*
G02X1195047I47J-1574D01*
G02X1196364Y339834I-48J-1574D01*
G03X1198309Y338671I2015J1162D01*
G01X1198438D01*
G02X1199744Y337884I-59J-1575D01*
G03X1201674Y336722I2015J1163D01*
G01X1202758D01*
X1204703Y334777D01*
X1205886D01*
X1206284Y334379D01*
X1206984D01*
X1207382Y334777D01*
X1208168D01*
X1208566Y334379D01*
X1209266D01*
X1209664Y334777D01*
X1210470D01*
X1210689Y334558D01*
X1211389D01*
X1211608Y334777D01*
X1213873D01*
X1214531Y334298D01*
X1214574Y334021D01*
X1214644Y333970D01*
G01X1191619Y333196D02*
Y334527D01*
X1191876Y334784D01*
G03X1193634Y335934I-257J2312D01*
G01X1193636Y335936D01*
G02X1193674Y335999I1364J-780D01*
G02X1194950Y336722I1323J-847D01*
G01X1194952D01*
G02X1195046I47J-1575D01*
G02X1196364Y335934I-47J-1575D01*
G03X1198309Y334771I2015J1162D01*
G01X1198438D01*
G02X1199744Y333984I-59J-1575D01*
G03X1201674Y332822I2015J1163D01*
G01X1201816D01*
G02X1203124Y332034I-57J-1575D01*
G01X1203339Y331660D01*
X1205290Y329712D01*
X1206945D01*
X1207145Y329512D01*
X1207232D01*
G01X1191619Y329296D02*
X1190465Y329962D01*
X1190382Y330272D01*
G02X1191560Y330871I1238J-976D01*
G01X1191689D01*
G03X1193634Y332034I-70J2325D01*
G01X1193636Y332037D01*
G02X1194945Y332822I1359J-782D01*
G01X1194952D01*
G02X1195046I47J-1575D01*
G02X1196364Y332034I-47J-1575D01*
G03X1198309Y330871I2015J1162D01*
G01X1198448D01*
G02X1199744Y330084I-69J-1575D01*
G01X1200359Y329017D01*
X1200428Y328948D01*
X1200429D01*
X1201527Y327850D01*
X1203289D01*
X1204089Y327050D01*
X1204789D01*
X1205179Y326660D01*
X1205879D01*
X1206269Y327050D01*
X1206969D01*
X1207359Y326660D01*
X1208059D01*
X1208449Y327050D01*
X1209901D01*
X1210101Y326850D01*
X1210188D01*
G01X1191619Y325396D02*
G03X1192826Y328179I-31619J15367D01*
G02X1194929Y329672I2173J-833D01*
G01X1195069D01*
G02X1197014Y328509I-70J-2325D01*
G03X1198331Y327722I1364J788D01*
G03X1198437I53J1574D01*
G01Y327721D01*
X1199379D01*
X1201050Y326050D01*
X1202551D01*
X1203589Y325012D01*
X1210604D01*
X1210796Y325204D01*
X1210883D01*
G01X1210096Y320920D02*
X1210009D01*
X1209809Y321120D01*
X1201759D01*
G02X1199766Y322247I0J2326D01*
G01X1199746Y322281D01*
X1199744Y322283D01*
G03X1198423Y323071I-1365J-787D01*
G01X1198294D01*
G02X1196364Y324233I85J2325D01*
G03X1193634I-1365J-787D01*
G02X1189604I-2015J1162D01*
G03X1188467Y325005I-1365J-787D01*
G01X1188239Y324777D01*
Y323446D01*
G01X1184859Y313696D02*
Y315027D01*
X1185116Y315284D01*
G03X1186874Y316434I-257J2312D01*
G02X1188195Y317222I1365J-787D01*
G01X1188324D01*
G03X1190254Y318384I-85J2325D01*
G02X1191560Y319171I1365J-788D01*
G01X1191689D01*
G03X1193634Y320334I-70J2325D01*
G02X1194928Y321121I1365J-787D01*
G01X1195070D01*
G02X1196364Y320334I-71J-1574D01*
G03X1198309Y319171I2015J1162D01*
G01X1198310Y319172D01*
X1199668D01*
X1202178Y316662D01*
X1209034D01*
X1209234Y316462D01*
X1209321D01*
G01X1188239Y315647D02*
X1189393Y316312D01*
X1189745Y316217D01*
G03X1191549Y315271I1873J1379D01*
G01X1191580D01*
G03X1191659I40J1728D01*
G01X1191678D01*
G03X1193634Y316434I-58J2324D01*
G02X1194942Y317222I1365J-787D01*
G01X1196017D01*
X1197589Y315650D01*
X1198890D01*
X1200638Y313902D01*
X1208565D01*
X1208765Y313702D01*
X1208852D01*
G01X1184859Y348796D02*
X1185848Y348226D01*
X1186365D01*
G02X1188169Y349172I1873J-1379D01*
G01X1188298D01*
G03X1189604Y349959I-59J1575D01*
G02X1191534Y351121I2015J-1163D01*
G01X1191676D01*
G03X1192984Y351909I-57J1575D01*
G01X1193033Y351995D01*
X1193042Y352004D01*
G02X1194939Y353072I1954J-1253D01*
G01X1194941D01*
G02X1195068I64J-2325D01*
G02X1197014Y351909I-69J-2325D01*
G03X1198335Y351121I1365J787D01*
G01X1198464D01*
G02X1200394Y349959I-85J-2325D01*
G03X1201700Y349172I1365J788D01*
G01X1204839D01*
X1209506Y344506D01*
X1210761Y343250D01*
X1213437D01*
X1213637Y343450D01*
X1213724D01*
G01X1161200Y393647D02*
X1160046Y392981D01*
X1159963Y392671D01*
G03X1161141Y392072I1238J976D01*
G01X1161259D01*
G03X1162565Y392859I-59J1575D01*
G02X1164493Y394021I2015J-1163D01*
G02X1164667I87J-2325D01*
G02X1166595Y392859I-87J-2325D01*
G03X1167901Y392072I1365J788D01*
G01X1168030D01*
G02X1169975Y390909I-70J-2325D01*
G01X1169988Y390886D01*
G03X1171339Y390121I1351J810D01*
G01X1171424D01*
G02X1173379Y386676I-85J-2325D01*
G01X1173354Y386634D01*
X1173335Y386600D01*
G03X1174660Y384272I1384J-753D01*
G01X1174789D01*
G02X1176734Y383109I-70J-2325D01*
G03X1178055Y382321I1365J787D01*
G01X1178184D01*
G02X1180114Y381159I-85J-2325D01*
G03X1181420Y380372I1365J788D01*
G01X1181549D01*
G02X1183494Y379209I-70J-2325D01*
G03X1184815Y378421I1365J787D01*
G01X1184944D01*
G02X1186874Y377259I-85J-2325D01*
G03X1188180Y376472I1365J788D01*
G01X1188290D01*
G02X1190254Y375309I-51J-2326D01*
G03X1191548Y374522I1365J787D01*
G01X1191690D01*
G03X1192984Y375309I-71J1574D01*
G02X1197014I2015J-1163D01*
G03X1198308Y374522I1365J787D01*
G01X1198450D01*
G03X1199744Y375309I-71J1574D01*
G02X1201708Y376472I2015J-1163D01*
G01X1201703D01*
G03X1201759Y376471I56J1575D01*
G01X1202790D01*
X1203605Y375656D01*
X1204029D01*
X1204653Y375032D01*
Y374608D01*
X1205147Y374114D01*
X1205571D01*
X1206195Y373490D01*
Y373066D01*
X1206689Y372572D01*
X1210806D01*
X1211006Y372772D01*
X1211093D01*
G01X1216494Y345471D02*
X1216412Y345500D01*
X1216289Y345753D01*
X1216285Y345754D01*
Y345755D01*
X1215823Y345918D01*
X1213430Y346833D01*
X1209858D01*
X1203941Y352750D01*
X1200689D01*
X1199168Y354271D01*
X1198325D01*
G02X1196364Y355434I54J2325D01*
G03X1193634I-1365J-787D01*
G02X1191675Y354271I-2015J1162D01*
G01X1191563D01*
G02X1189604Y355434I56J2325D01*
G03X1188296Y356222I-1365J-787D01*
G01X1188154D01*
G02X1186224Y357384I85J2325D01*
G03X1184918Y358171I-1365J-788D01*
G01X1184789D01*
G02X1182844Y359334I70J2325D01*
G03X1180114I-1365J-787D01*
G02X1176084I-2015J1162D01*
G03X1174763Y360122I-1365J-787D01*
G01X1174634D01*
G02X1172704Y361284I85J2325D01*
G03X1171398Y362071I-1365J-788D01*
G01X1171269D01*
G02X1169324Y363234I70J2325D01*
G01X1169311Y363257D01*
G03X1167960Y364022I-1351J-810D01*
G01X1167875D01*
G02X1165945Y365184I85J2325D01*
G03X1164639Y365971I-1365J-788D01*
G01X1164510D01*
G02X1162565Y367134I70J2325D01*
G03X1161244Y367922I-1365J-787D01*
G01X1161115D01*
G02X1159185Y371410I85J2325D01*
G03Y372984I-1365J787D01*
G01X1159160Y373026D01*
G02X1159185Y375309I2040J1119D01*
G01X1159204Y375343D01*
G03X1159185Y376884I-1384J754D01*
G02X1159160Y379167I2015J1164D01*
G01X1159185Y379209D01*
X1159204Y379243D01*
G03X1159185Y380784I-1384J754D01*
G02X1160943Y384259I2015J1163D01*
G01X1161200Y384516D01*
Y385847D01*
G01X1207730Y354755D02*
X1207669Y354816D01*
X1207385D01*
X1205801Y356400D01*
X1204483D01*
X1204093Y356790D01*
X1203393D01*
X1203003Y356400D01*
X1202303D01*
X1201191Y356861D01*
X1200495Y357557D01*
X1200394Y357759D01*
G03X1198464Y358921I-2015J-1163D01*
G01X1198335D01*
G02X1197014Y359709I44J1575D01*
G03X1192984I-2015J-1162D01*
G02X1190254I-1365J787D01*
G03X1188309Y360872I-2015J-1162D01*
G01X1188180D01*
G02X1186874Y361659I59J1575D01*
G03X1184944Y362821I-2015J-1163D01*
G01X1184815D01*
G02X1183494Y363609I44J1575D01*
G03X1179464I-2015J-1162D01*
G02X1176734I-1365J787D01*
G03X1174789Y364772I-2015J-1162D01*
G01X1174660D01*
G02X1173354Y365559I59J1575D01*
G03X1171424Y366721I-2015J-1163D01*
G01X1171339D01*
G02X1169988Y367486I0J1575D01*
G01X1169975Y367509D01*
G03X1168030Y368672I-2015J-1162D01*
G01X1167901D01*
G02X1166595Y369459I59J1575D01*
G03X1164631Y370622I-2015J-1163D01*
G01X1164536D01*
G02X1163215Y372984I44J1575D01*
G01X1163240Y373026D01*
G03X1163215Y375309I-2040J1119D01*
G01X1163196Y375343D01*
G02X1163215Y376884I1384J754D01*
G03X1163240Y379167I-2015J1164D01*
G01X1163215Y379209D01*
X1163196Y379243D01*
G02X1164521Y381571I1384J753D01*
G01X1164650D01*
G03X1166712Y384829I-69J2325D01*
G01X1166806Y385181D01*
X1167960Y385847D01*
G01Y381947D02*
X1169113Y381282D01*
X1169196Y380972D01*
G02X1167960Y380372I-1237J975D01*
G01X1167890D01*
G03X1165945Y376884I70J-2325D01*
G02X1165964Y375343I-1365J-787D01*
G01X1165945Y375309D01*
G03X1167890Y371821I2015J-1163D01*
G01X1168008D01*
G02X1169324Y371034I-48J-1574D01*
G03X1171288Y369871I2015J1163D01*
G01X1171398D01*
G02X1172704Y369084I-59J-1575D01*
G03X1174634Y367922I2015J1163D01*
G01X1174763D01*
G02X1176084Y367134I-44J-1575D01*
G03X1180114I2015J1162D01*
G02X1182844I1365J-787D01*
G03X1184789Y365971I2015J1162D01*
G01X1184918D01*
G02X1186224Y365184I-59J-1575D01*
G03X1188154Y364022I2015J1163D01*
G01X1188283D01*
G02X1189604Y363234I-44J-1575D01*
G03X1193634I2015J1162D01*
G02X1196364I1365J-787D01*
G03X1198309Y362071I2015J1162D01*
G01X1205499D01*
X1206069Y361835D01*
X1207381Y360523D01*
X1212012Y358607D01*
X1213623D01*
X1214396Y358287D01*
X1215069Y357614D01*
Y357331D01*
X1215130Y357270D01*
G01X1210387Y363450D02*
X1210300D01*
X1210100Y363250D01*
X1209695D01*
X1207673Y364088D01*
X1207023Y364738D01*
X1201803Y366900D01*
X1198068D01*
G02X1197014Y367509I0J1217D01*
G03X1192984I-2015J-1162D01*
G02X1190254I-1365J787D01*
G03X1188309Y368672I-2015J-1162D01*
G01X1188180D01*
G02X1186874Y369459I59J1575D01*
G03X1184910Y370622I-2015J-1163D01*
G01X1184815D01*
G02X1183494Y371410I44J1575D01*
G03X1181564Y372572I-2015J-1163D01*
G01X1181394D01*
G03X1179464Y371410I85J-2325D01*
G02X1176734I-1365J787D01*
G03X1174804Y372572I-2015J-1163D01*
G01X1174648D01*
G02X1173354Y373359I71J1574D01*
G03X1171409Y374522I-2015J-1162D01*
G01X1171291D01*
G02X1169975Y375309I48J1574D01*
G03X1168217Y376459I-2015J-1162D01*
G01X1167960Y376716D01*
Y378047D01*
G01X1157820Y391696D02*
X1158974Y392362D01*
X1159326Y392267D01*
G03X1161115Y391322I1873J1380D01*
G01X1161285D01*
G03X1163215Y392484I-85J2325D01*
G02X1164521Y393271I1365J-788D01*
G01X1164639D01*
G02X1165945Y392484I-59J-1575D01*
G03X1167875Y391322I2015J1163D01*
G01X1167960D01*
G02X1169311Y390557I0J-1575D01*
G01X1169324Y390534D01*
G03X1171269Y389371I2015J1162D01*
G01X1171398D01*
G02X1172723Y387043I-59J-1575D01*
G01X1172704Y387009D01*
X1172679Y386967D01*
G03X1174634Y383522I2040J-1120D01*
G01X1174763D01*
G02X1176084Y382734I-44J-1575D01*
G03X1178029Y381571I2015J1162D01*
G01X1178158D01*
G02X1179464Y380784I-59J-1575D01*
G03X1181394Y379622I2015J1163D01*
G01X1181523D01*
G02X1182844Y378834I-44J-1575D01*
G03X1184789Y377671I2015J1162D01*
G01X1184918D01*
G02X1186224Y376884I-59J-1575D01*
G03X1188188Y375721I2015J1163D01*
G01X1188283D01*
G02X1189604Y374933I-44J-1575D01*
G03X1191534Y373771I2015J1163D01*
G01X1191704D01*
G03X1193634Y374933I-85J2325D01*
G02X1196364I1365J-787D01*
G03X1198294Y373771I2015J1163D01*
G01X1198464D01*
G03X1200394Y374933I-85J2325D01*
G02X1201715Y375721I1365J-787D01*
G01X1202479D01*
X1206378Y371822D01*
X1210806D01*
X1211006Y371622D01*
X1211093D01*
G01X1216876Y346556D02*
X1216793Y346586D01*
X1216537Y346462D01*
X1216083Y346622D01*
X1215829Y346720D01*
X1215821Y346724D01*
X1215812Y346727D01*
X1215808Y346729D01*
X1215793Y346734D01*
X1215568Y347238D01*
X1214819Y347523D01*
X1214316Y347298D01*
X1213569Y347583D01*
X1212549D01*
X1212249Y347883D01*
X1211269D01*
X1210969Y347583D01*
X1210169D01*
X1209301Y348451D01*
Y348875D01*
X1208607Y349569D01*
X1208183D01*
X1207618Y350134D01*
Y350558D01*
X1206924Y351252D01*
X1206500D01*
X1205935Y351817D01*
Y352241D01*
X1205241Y352935D01*
X1204817D01*
X1204252Y353500D01*
X1203180D01*
X1202880Y353800D01*
X1202000D01*
X1201700Y353500D01*
X1201000D01*
X1199479Y355021D01*
X1198335D01*
G02X1197014Y355809I44J1575D01*
G03X1192984I-2015J-1161D01*
G02X1191665Y355021I-1365J787D01*
G01X1191573D01*
G02X1190254Y355809I46J1575D01*
G03X1188309Y356972I-2015J-1162D01*
G01X1188180D01*
G02X1186874Y357759I59J1575D01*
G03X1184944Y358921I-2015J-1163D01*
G01X1184815D01*
G02X1183494Y359709I44J1575D01*
G03X1179464I-2015J-1162D01*
G02X1176734I-1365J787D01*
G03X1174789Y360872I-2015J-1162D01*
G01X1174660D01*
G02X1173354Y361659I59J1575D01*
G03X1171424Y362821I-2015J-1163D01*
G01X1171339D01*
G02X1169988Y363586I0J1575D01*
G01X1169975Y363609D01*
G03X1168030Y364772I-2015J-1162D01*
G01X1167901D01*
G02X1166595Y365559I59J1575D01*
G03X1164665Y366721I-2015J-1163D01*
G01X1164536D01*
G02X1163215Y367509I44J1575D01*
G03X1161270Y368672I-2015J-1162D01*
G01X1161141D01*
G02X1159816Y371000I59J1575D01*
G01X1159835Y371034D01*
G03X1159860Y373317I-2015J1164D01*
G01X1159835Y373359D01*
G02Y374933I1365J787D01*
G03Y377259I-2015J1163D01*
G02X1159816Y378800I1365J787D01*
G01X1159835Y378834D01*
X1159860Y378876D01*
G03X1159835Y381159I-2040J1119D01*
G02X1160972Y383506I1365J788D01*
G01X1161290Y383188D01*
Y382037D01*
X1161200Y381947D01*
G01X1206916Y353941D02*
X1206855Y354002D01*
Y354284D01*
X1205489Y355650D01*
X1202153D01*
X1200766Y356225D01*
X1199878Y357112D01*
X1199733Y357401D01*
G03X1198448Y358170I-1354J-805D01*
G01X1198447Y358171D01*
X1198325D01*
G02X1196364Y359334I54J2325D01*
G03X1193634I-1365J-787D01*
G02X1189604I-2015J1162D01*
G03X1188283Y360122I-1365J-787D01*
G01X1188154D01*
G02X1186224Y361284I85J2325D01*
G03X1184918Y362071I-1365J-788D01*
G01X1184789D01*
G02X1182844Y363234I70J2325D01*
G03X1180114I-1365J-787D01*
G02X1176084I-2015J1162D01*
G03X1174763Y364022I-1365J-787D01*
G01X1174634D01*
G02X1172704Y365184I85J2325D01*
G03X1171398Y365971I-1365J-788D01*
G01X1171269D01*
G02X1169324Y367134I70J2325D01*
G01X1169311Y367157D01*
G03X1167960Y367922I-1351J-810D01*
G01X1167875D01*
G02X1165945Y369084I85J2325D01*
G03X1164639Y369871I-1365J-788D01*
G01X1164529D01*
G02X1162540Y373317I51J2326D01*
G01X1162565Y373359D01*
G03Y374933I-1365J787D01*
G02Y377259I2015J1163D01*
G03X1162584Y378800I-1365J787D01*
G01X1162565Y378834D01*
X1162540Y378876D01*
G02X1164495Y382321I2040J1120D01*
G01X1164624D01*
G03X1166044Y384478I-45J1575D01*
G01X1165734Y384562D01*
X1164580Y383896D01*
G01X1171339Y379996D02*
X1170186Y380661D01*
X1169834Y380566D01*
G02X1168058Y379622I-1873J1381D01*
G01X1167916D01*
G03X1166595Y377259I44J-1575D01*
G02Y374933I-2015J-1163D01*
G03X1167889Y372572I1365J-787D01*
G01X1168045D01*
G02X1169975Y371410I-85J-2325D01*
G01X1169988Y371387D01*
G03X1171339Y370622I1351J810D01*
G01X1171390D01*
G02X1173354Y369459I-51J-2326D01*
G03X1174660Y368672I1365J788D01*
G01X1174789D01*
G02X1176734Y367509I-70J-2325D01*
G03X1179464I1365J787D01*
G02X1183494I2015J-1162D01*
G03X1184815Y366721I1365J787D01*
G01X1184944D01*
G02X1186874Y365559I-85J-2325D01*
G03X1188180Y364772I1365J788D01*
G01X1188309D01*
G02X1190254Y363609I-70J-2325D01*
G03X1192984I1365J787D01*
G02X1197014I2015J-1162D01*
G03X1198322Y362821I1365J787D01*
G01X1199055D01*
X1199454Y363220D01*
X1200154D01*
X1200553Y362821D01*
X1201253D01*
X1201652Y363220D01*
X1202352D01*
X1202751Y362821D01*
X1203451D01*
X1203850Y363220D01*
X1204550D01*
X1204949Y362821D01*
X1205649D01*
X1206494Y362471D01*
X1207806Y361159D01*
X1212162Y359357D01*
X1213773D01*
X1214821Y358923D01*
X1215599Y358145D01*
X1215883D01*
X1215944Y358084D01*
G01X1167960Y374146D02*
Y375477D01*
X1168187Y375704D01*
G02X1169311Y374956I-226J-1559D01*
G01X1169324Y374933D01*
G03X1171254Y373771I2015J1163D01*
G01X1171410D01*
G02X1172704Y372984I-71J-1574D01*
G03X1174649Y371821I2015J1162D01*
G01X1174790D01*
G02X1176084Y371034I-71J-1574D01*
G03X1180114I2015J1163D01*
G02X1181408Y371821I1365J-787D01*
G01X1181550D01*
G02X1182844Y371034I-71J-1574D01*
G03X1184808Y369871I2015J1163D01*
G01X1184918D01*
G02X1186224Y369084I-59J-1575D01*
G03X1188154Y367922I2015J1163D01*
G01X1188283D01*
G02X1189604Y367134I-44J-1575D01*
G03X1193634I2015J1162D01*
G02X1196364I1365J-787D01*
G03X1198067Y366150I1704J983D01*
G01X1201653D01*
X1206598Y364102D01*
X1207248Y363452D01*
X1209545Y362500D01*
X1210100D01*
X1210300Y362300D01*
X1210387D01*
G01X1198887Y410950D02*
X1198800D01*
X1198600Y410750D01*
X1195703D01*
X1192755Y407802D01*
X1192260D01*
X1191517Y407059D01*
Y406564D01*
X1190775Y405822D01*
X1189985D01*
X1189635Y406172D01*
X1188535D01*
X1188185Y405822D01*
X1187085D01*
X1186735Y406172D01*
X1185635D01*
X1185285Y405822D01*
X1184305D01*
X1182461Y407666D01*
X1179713D01*
X1177742Y405695D01*
G03X1176084Y404559I357J-2299D01*
G02X1174778Y403772I-1365J788D01*
G01X1174660D01*
G02X1173482Y404371I60J1575D01*
G01X1173565Y404681D01*
X1174719Y405347D01*
G01X1208583Y404210D02*
X1208496D01*
X1208296Y404010D01*
X1199615D01*
X1199040Y403772D01*
X1183411D01*
X1178700Y401821D01*
X1178027D01*
G03X1176225Y400876I71J-2326D01*
G01X1176164Y400937D01*
X1175603D01*
X1174719Y401447D01*
G01X1205825Y400428D02*
X1205738D01*
X1205538Y400228D01*
X1201940D01*
X1185801Y401821D01*
X1184809D01*
X1184808Y401822D01*
G03X1182844Y400659I51J-2326D01*
G02X1181538Y399872I-1365J788D01*
G01X1181428D01*
G03X1179347Y396613I51J-2326D01*
G01X1179253Y396261D01*
X1178099Y395596D01*
G01X1207140Y396735D02*
X1207053D01*
X1206853Y396535D01*
X1203649D01*
X1202476Y397021D01*
X1200659D01*
X1197830Y395850D01*
X1196073D01*
X1191071Y397922D01*
X1185209D01*
X1184859Y398272D01*
Y399496D01*
G01X1181479Y393647D02*
G03X1184375Y393972I0J13065D01*
G02X1184808Y394022I482J-2276D01*
G01X1184903D01*
G03X1186224Y394810I-44J1575D01*
G01Y394809D01*
G02X1188185Y395972I2015J-1162D01*
G01X1189049D01*
X1194798Y393590D01*
X1198250D01*
X1200362Y394464D01*
X1202009D01*
X1207125Y392345D01*
X1208449Y391830D01*
X1209031D01*
X1209231Y392030D01*
X1209318D01*
G01X1209571Y389475D02*
X1209485D01*
X1209285Y389275D01*
X1205770D01*
X1203079Y391966D01*
X1201722Y392528D01*
X1200567D01*
X1198540Y391689D01*
X1198083Y391879D01*
X1197113Y391478D01*
X1196923Y391020D01*
X1195953Y390619D01*
X1192370Y390700D01*
X1192039D01*
X1189511Y388172D01*
X1188180D01*
G02X1187002Y388771I60J1575D01*
G01X1187165Y389380D01*
X1187940Y389827D01*
X1188239Y389747D01*
G01X1210187Y384450D02*
X1210100D01*
X1209900Y384250D01*
X1208273D01*
X1203918Y386579D01*
X1195508Y388252D01*
X1194708D01*
X1192269Y387241D01*
X1191215Y386187D01*
G03X1189745Y385276I403J-2291D01*
G01X1189393Y385181D01*
X1188239Y385847D01*
G01X1167960Y401447D02*
Y402778D01*
X1168216Y403034D01*
G03X1169975Y404183I-256J2313D01*
G01X1169977Y404187D01*
X1169983Y404197D01*
X1169985Y404200D01*
X1170262Y404678D01*
X1173558Y407564D01*
X1180627Y410492D01*
X1184054D01*
X1184254Y410292D01*
X1184341D01*
G01X1198887Y409800D02*
X1198800D01*
X1198600Y410000D01*
X1196014D01*
X1191086Y405072D01*
X1183994D01*
X1182150Y406916D01*
X1180024D01*
X1178099Y404991D01*
X1177857Y404953D01*
G03X1176734Y404184I242J-1557D01*
G02X1174804Y403022I-2015J1163D01*
G01X1174634D01*
G02X1172845Y403967I84J2325D01*
G01X1172328D01*
X1171339Y403396D01*
G01X1208583Y403060D02*
X1208496D01*
X1208296Y403260D01*
X1205565D01*
X1205215Y402910D01*
X1204115D01*
X1203765Y403260D01*
X1202665D01*
X1202315Y402910D01*
X1201215D01*
X1200865Y403260D01*
X1199765D01*
X1199190Y403022D01*
X1183561D01*
X1178850Y401071D01*
X1178040D01*
G03X1176862Y400472I60J-1575D01*
G01X1176945Y400162D01*
X1178099Y399496D01*
G01X1205825Y399278D02*
X1205738D01*
X1205538Y399478D01*
X1201903D01*
X1199689Y399696D01*
X1199307Y399382D01*
X1198262Y399485D01*
X1197948Y399868D01*
X1196903Y399971D01*
X1196521Y399657D01*
X1195476Y399760D01*
X1195162Y400143D01*
X1194117Y400246D01*
X1193735Y399932D01*
X1192690Y400035D01*
X1192376Y400418D01*
X1191331Y400521D01*
X1190949Y400207D01*
X1189904Y400310D01*
X1189590Y400693D01*
X1188545Y400796D01*
X1188163Y400482D01*
X1187118Y400585D01*
X1186804Y400968D01*
X1185759Y401071D01*
X1184800D01*
G03X1183494Y400284I59J-1575D01*
G02X1181530Y399121I-2015J1163D01*
G01X1181435D01*
G03X1180015Y396965I44J-1575D01*
G01X1180325Y396881D01*
X1181479Y397546D01*
G01X1207140Y395585D02*
X1207053D01*
X1206853Y395785D01*
X1203499D01*
X1202326Y396271D01*
X1200809D01*
X1197980Y395100D01*
X1195923D01*
X1190921Y397172D01*
X1185209D01*
X1184859Y396822D01*
Y395596D01*
G01X1209318Y390880D02*
X1209231D01*
X1209031Y391080D01*
X1208308D01*
X1206845Y391648D01*
X1201859Y393714D01*
X1200512D01*
X1198400Y392840D01*
X1194648D01*
X1194630Y392847D01*
X1189800Y394849D01*
X1188899Y395222D01*
X1188195D01*
G03X1186874Y394434I44J-1575D01*
G02X1184910Y393271I-2015J1163D01*
G01X1184800D01*
G03X1183622Y392672I60J-1575D01*
G03X1183445Y392392I1254J-989D01*
G01X1183591Y392106D01*
X1184859Y391696D01*
G01X1209572Y388325D02*
X1209485D01*
X1209285Y388525D01*
X1205459D01*
X1202654Y391330D01*
X1201572Y391778D01*
X1200717D01*
X1196092Y389864D01*
X1192350Y389950D01*
X1189822Y387422D01*
X1188154D01*
G02X1186365Y388367I84J2325D01*
G01X1186013Y388462D01*
X1184859Y387796D01*
G01X1210187Y383300D02*
X1210100D01*
X1209900Y383500D01*
X1208085D01*
X1203662Y385864D01*
X1202976Y386000D01*
X1202517Y385694D01*
X1201830Y385830D01*
X1201523Y386290D01*
X1200837Y386426D01*
X1200378Y386120D01*
X1199691Y386256D01*
X1199384Y386716D01*
X1195434Y387502D01*
X1194858D01*
X1192694Y386605D01*
X1191560Y385471D01*
G03X1190382Y384872I60J-1575D01*
G01X1190465Y384562D01*
X1191619Y383896D01*
G01X1167960Y405347D02*
Y404016D01*
X1168187Y403789D01*
G03X1169311Y404537I-226J1559D01*
G03X1169325Y404559I-1322J857D01*
G01X1169328Y404564D01*
X1169334Y404575D01*
X1169661Y405138D01*
X1169747Y405224D01*
X1173157Y408210D01*
X1180477Y411242D01*
X1184054D01*
X1184254Y411442D01*
X1184341D01*
G01X1299549Y-18619D02*
X1301547Y-20617D01*
X1325194D01*
X1352520Y6709D01*
X1358250D01*
X1363400Y1559D01*
Y-10620D01*
X1371249Y-18469D01*
X1379088D01*
X1390100Y-7457D01*
Y-5500D01*
X1402300Y6700D01*
X1411100D01*
X1413059Y8659D01*
X1426657D01*
X1435916Y-600D01*
X1487446D01*
X1487621Y-775D01*
X1495325D01*
X1501407Y5307D01*
X1508507D01*
X1513600Y10400D01*
X1530200D01*
X1531100Y9500D01*
X1576100D01*
X1577073Y8527D01*
X1587367D01*
X1589294Y6600D01*
X1601144D01*
X1605337Y2407D01*
X1637752D01*
X1643849Y-3690D01*
X1654285D01*
X1661600Y3625D01*
X1672725D01*
X1676800Y7700D01*
X1694600D01*
X1696138Y9238D01*
X1734875D01*
G01X1464400Y454100D02*
X1463400Y453100D01*
Y452569D01*
X1462503Y451672D01*
X1458053D01*
X1457220Y450839D01*
Y447960D01*
X1457962Y447218D01*
X1458457D01*
X1459200Y446475D01*
Y445980D01*
X1460048Y445132D01*
X1460330D01*
X1460391Y445071D01*
G01X1449045Y454281D02*
X1449106Y454342D01*
Y454625D01*
X1450356Y455875D01*
X1461986D01*
X1463394Y457283D01*
Y457780D01*
X1464400Y458786D01*
Y459800D01*
G01X1443103Y458414D02*
X1443164Y458475D01*
X1443448D01*
X1448449Y463476D01*
X1454826D01*
X1456164Y462138D01*
Y460236D01*
X1456600Y459800D01*
G01X1461800Y454100D02*
X1462650Y453250D01*
Y452880D01*
X1462192Y452422D01*
X1457742D01*
X1456470Y451150D01*
Y447649D01*
X1459517Y444602D01*
Y444318D01*
X1459578Y444257D01*
G01X1448232Y455096D02*
X1448293Y455157D01*
X1448577D01*
X1450045Y456625D01*
X1450995D01*
X1451345Y456975D01*
X1452395D01*
X1452745Y456625D01*
X1453795D01*
X1454145Y456975D01*
X1455195D01*
X1455545Y456625D01*
X1456595D01*
X1456945Y456975D01*
X1457995D01*
X1458345Y456625D01*
X1461675D01*
X1462644Y457594D01*
Y457780D01*
X1461800Y458624D01*
Y459800D01*
G01X1443917Y457601D02*
X1443978Y457662D01*
Y457944D01*
X1444800Y458766D01*
X1445295D01*
X1446038Y459509D01*
Y460004D01*
X1446780Y460746D01*
X1447275D01*
X1448018Y461489D01*
Y461984D01*
X1448760Y462726D01*
X1449255D01*
X1449605Y462376D01*
X1450655D01*
X1451005Y462726D01*
X1452055D01*
X1452405Y462376D01*
X1453455D01*
X1453805Y462726D01*
X1454515D01*
X1455414Y461827D01*
Y461214D01*
X1454000Y459800D01*
G01X1479149Y348150D02*
X1482074Y345225D01*
X1486092D01*
X1489760Y341557D01*
Y339392D01*
X1487904Y337536D01*
Y337500D01*
G01X1534833Y309798D02*
X1531304D01*
X1530102Y308596D01*
X1523616D01*
X1520386Y305366D01*
X1512417D01*
X1506453Y311330D01*
X1501050D01*
X1496365Y316015D01*
X1477793D01*
X1474855Y313077D01*
X1472118D01*
X1470649Y314546D01*
G01X1561039Y451961D02*
X1580751D01*
X1583358Y449354D01*
G01X1820708Y63139D02*
X1824703D01*
X1834914Y52928D01*
G01X1590081Y143030D02*
X1591143Y144092D01*
G01X1546025Y401985D02*
X1548010Y403970D01*
Y404769D01*
X1549606Y406365D01*
X1566697D01*
X1566939Y406123D01*
X1572681D01*
X1574464Y407906D01*
G01X1530425Y397794D02*
X1531090Y398948D01*
X1531442Y399042D01*
G03X1533538Y399159I932J2132D01*
G02X1535112I787J-1365D01*
G03X1537438I1163J2015D01*
G02X1539012I787J-1365D01*
G03X1541338I1163J2015D01*
G03X1542500Y401089I-1163J2015D01*
G01Y401218D01*
G02X1543100Y402411I1575J-45D01*
G02X1543587Y402682I1090J-1385D01*
G03X1544450Y404370I-1219J1688D01*
G01Y405358D01*
X1546611Y407519D01*
X1549232D01*
X1550761Y409048D01*
G02X1551088Y409298I1112J-1115D01*
G01X1551133Y409324D01*
G02X1552662Y409299I742J-1390D01*
G03X1554988I1163J2015D01*
G02X1556562I787J-1365D01*
G03X1558888I1163J2015D01*
G02X1560462I787J-1365D01*
G03X1562788I1163J2015D01*
G02X1563803Y409571I1015J-1759D01*
G01X1566486D01*
X1566621Y409706D01*
X1572495D01*
X1575350Y412561D01*
Y442690D01*
X1578760Y446100D01*
X1582300D01*
G01X1532375Y401174D02*
X1531710Y400020D01*
X1531794Y399710D01*
G03X1533162Y399809I582J1464D01*
G02X1535488I1163J-2015D01*
G03X1537062I787J1365D01*
G02X1539388I1163J-2015D01*
G03X1540962I787J1365D01*
G03X1541750Y401130I-787J1365D01*
G01Y401259D01*
G02X1542695Y403048I2325J-84D01*
G02X1543080Y403281I1483J-2016D01*
G03X1543700Y404413I-723J1132D01*
G01Y405668D01*
X1546300Y408268D01*
X1548921D01*
X1550231Y409579D01*
G02X1550351Y409691I1645J-1642D01*
G02X1550713Y409948I1521J-1759D01*
G01X1550783Y409988D01*
G02X1553038Y409949I1092J-2054D01*
G03X1554612I787J1365D01*
G02X1556938I1163J-2015D01*
G03X1558512I787J1365D01*
G02X1560838I1163J-2015D01*
G03X1562412I787J1365D01*
G01X1562823Y410186D01*
G03X1563366Y411126I-542J940D01*
G01Y411753D01*
X1564524Y412911D01*
X1573766D01*
X1574601Y413746D01*
Y442684D01*
X1571945Y445340D01*
X1567509D01*
X1565923Y446926D01*
X1565525D01*
G01X1612183Y442623D02*
X1596272Y458534D01*
X1575062D01*
X1572025Y455497D01*
X1571236D01*
X1569425Y453686D01*
G01X1560679Y459166D02*
X1561086Y458759D01*
X1562252D01*
X1563771Y460278D01*
Y461351D01*
X1564677Y462257D01*
X1568125D01*
X1568617Y462749D01*
X1572319D01*
X1575300Y465730D01*
X1592769D01*
X1605418Y453081D01*
X1610619D01*
X1616200Y447500D01*
Y439599D01*
X1613701Y437100D01*
X1604600D01*
X1603000Y435500D01*
G01X1579009Y466809D02*
X1571407D01*
X1570099Y465501D01*
X1562932D01*
X1561890Y464459D01*
Y462863D01*
X1560838Y461811D01*
G02X1558512I-1163J2015D01*
G03X1556938I-787J-1365D01*
G02X1554612I-1163J2015D01*
G03X1553038I-787J-1365D01*
G02X1549925Y460446I-7749J13440D01*
G01X1603652Y438391D02*
X1613220D01*
X1615033Y440204D01*
Y446460D01*
X1609993Y451500D01*
X1604999D01*
G01X1572440Y461242D02*
X1569984Y458786D01*
X1566430D01*
X1565637Y457993D01*
Y456688D01*
X1564349Y455400D01*
X1559100D01*
G01X1685567Y158730D02*
X1685887Y158410D01*
X1691968D01*
X1693548Y159990D01*
X1695680D01*
G01X1821071Y66760D02*
X1825722D01*
X1834178Y58304D01*
G01X1835562Y54600D02*
X1825292Y64870D01*
X1820969D01*
G54D27*
G01X25827Y-16958D02*
X24957Y-16088D01*
X-7912D01*
X-18100Y-5900D01*
Y11800D01*
X602Y30502D01*
G01X1382Y68100D02*
X4700D01*
X6617Y66183D01*
Y56217D01*
X1434Y51034D01*
Y45290D01*
X5500Y41224D01*
Y20782D01*
X28403Y-2121D01*
X50497D01*
X52744Y-4368D01*
G01X602Y30502D02*
Y35078D01*
X-3060Y38740D01*
X-12400D01*
X-14460Y40800D01*
Y51801D01*
X-11620Y54641D01*
X-5170D01*
X-2700Y57111D01*
Y62680D01*
X-1470Y63910D01*
G01X10932Y523601D02*
X4482D01*
X-5660Y533743D01*
Y535118D01*
X-10947Y540405D01*
Y544117D01*
G01X91913Y121318D02*
X91555Y120960D01*
X77860D01*
X77790Y121030D01*
G01X60400Y355750D02*
X68633D01*
X75300Y349083D01*
Y343799D01*
X77085Y342014D01*
Y337886D01*
X70770Y331571D01*
Y330370D01*
X70749Y330349D01*
X70700D01*
G01X74887Y321780D02*
Y333299D01*
X78485Y336897D01*
Y343214D01*
X76701Y344998D01*
Y349662D01*
X68693Y357670D01*
Y358707D01*
X62994Y364406D01*
X59008D01*
X58271Y363669D01*
G01X53100Y315000D02*
X59400Y321300D01*
Y336848D01*
X59452Y336900D01*
Y338800D01*
G01X109500Y370000D02*
X103460Y376040D01*
X92570D01*
X82736Y366206D01*
X61494D01*
X56000Y371700D01*
X55500D01*
G01X623400Y476300D02*
X626163Y473537D01*
Y461663D01*
X609652Y445152D01*
X592216D01*
G01X697200Y79500D02*
X695078Y81622D01*
X688645D01*
X683637Y86630D01*
X673346D01*
X669516Y82800D01*
X649000D01*
X647600Y84200D01*
G01X647469Y277639D02*
X647530Y277700D01*
X651700D01*
X658500Y284500D01*
G01X642800Y264000D02*
X644900D01*
X646400Y265500D01*
Y276570D01*
X647469Y277639D01*
G01X658500Y284500D02*
X659812D01*
X661412Y282900D01*
X666804D01*
X669004Y280700D01*
X678512D01*
X679212Y280000D01*
X687510D01*
X690130Y277380D01*
G01X619260Y466610D02*
X618601Y467269D01*
X617075D01*
X616276Y468068D01*
Y485692D01*
X622091Y491507D01*
Y516236D01*
X619900Y518427D01*
Y529200D01*
X623267Y532567D01*
Y554467D01*
X632200Y563400D01*
X642127D01*
X647350Y568623D01*
G01X648500Y477400D02*
X641900D01*
X629300Y490000D01*
G01X1375412Y92182D02*
X1377327Y94097D01*
X1380137D01*
X1382804Y91430D01*
Y77231D01*
X1376979Y71406D01*
X1372906D01*
X1370600Y69100D01*
X1349900D01*
X1348754Y67954D01*
Y67953D01*
X1347701Y66900D01*
X1333900D01*
X1329800Y71000D01*
Y76000D01*
X1325400Y80400D01*
Y86400D01*
X1310600Y101200D01*
X1306700D01*
X1300000Y107900D01*
X1297400D01*
X1292700Y103200D01*
X1284812D01*
X1271811Y90199D01*
Y17876D01*
X1270758Y16823D01*
X1270757D01*
X1267800Y13866D01*
Y12200D01*
X1269250Y10750D01*
Y6549D01*
X1265581Y2880D01*
X1041668D01*
X1040764Y3784D01*
X1034049D01*
X1028210Y-2055D01*
X1023750D01*
X1022697Y-1002D01*
Y-1001D01*
X1018282Y3414D01*
X777792D01*
X777733Y3355D01*
X767045D01*
X759200Y11200D01*
X754700D01*
X751243Y14657D01*
Y19310D01*
X749800Y20753D01*
Y25348D01*
X750853Y26401D01*
X750854D01*
X752400Y27947D01*
Y37734D01*
X753900Y39234D01*
Y43066D01*
X751400Y45566D01*
Y68346D01*
X753957Y70903D01*
Y75011D01*
X751468Y77500D01*
X725753D01*
X722844Y80409D01*
Y81899D01*
X722845Y81900D01*
Y90009D01*
X719254Y93600D01*
X697100D01*
X694000Y90500D01*
X691000D01*
X690500Y91000D01*
Y92800D01*
X690100Y93200D01*
G01X1378464Y91979D02*
X1379536D01*
X1380956Y90559D01*
Y78456D01*
X1376300Y73800D01*
X1372700D01*
X1369800Y70900D01*
X1349154D01*
X1346954Y68700D01*
X1334700D01*
X1331600Y71800D01*
Y76746D01*
X1327300Y81046D01*
Y87300D01*
X1311600Y103000D01*
X1307446D01*
X1300746Y109700D01*
X1296654D01*
X1291954Y105000D01*
X1284066D01*
X1270011Y90945D01*
Y18623D01*
X1267054Y15666D01*
X1267053D01*
X1266000Y14613D01*
Y11454D01*
X1267057Y10397D01*
Y6902D01*
X1264835Y4680D01*
X1042414D01*
X1041510Y5584D01*
X1033303D01*
X1027464Y-255D01*
X1024497D01*
X1019028Y5214D01*
X777046D01*
X776987Y5155D01*
X767845D01*
X760000Y13000D01*
X755446D01*
X753043Y15403D01*
Y20056D01*
X751600Y21499D01*
Y24601D01*
X754200Y27201D01*
Y36988D01*
X755700Y38488D01*
Y43812D01*
X753200Y46312D01*
Y67600D01*
X755757Y70157D01*
Y75757D01*
X752214Y79300D01*
X726499D01*
X724645Y81154D01*
Y90755D01*
X719400Y96000D01*
X696500D01*
X693000Y92500D01*
G01X704500Y252500D02*
X706290D01*
X714870Y243920D01*
X727866D01*
X731662Y247716D01*
G01D02*
Y248528D01*
X723390Y256800D01*
Y261180D01*
X716551Y268019D01*
Y281178D01*
X736000Y300627D01*
Y303400D01*
G01X713970Y308360D02*
X722130Y300200D01*
X727800D01*
X731300Y303700D01*
X735700D01*
G01X797780Y423484D02*
X797610D01*
X790035Y431059D01*
X759080D01*
X734482Y406461D01*
Y304918D01*
X735700Y303700D01*
G01D02*
X736000Y303400D01*
G01X1277100Y122670D02*
Y130601D01*
X1269058Y138643D01*
X1263257D01*
X1258000Y143900D01*
Y148550D01*
X1249433Y157117D01*
X1236257D01*
X1212850Y180524D01*
Y200850D01*
X1208519Y205181D01*
Y218147D01*
G01X1277100Y122670D02*
X1288530D01*
X1292008Y119192D01*
X1295592D01*
X1296300Y119900D01*
Y122100D01*
X1300800Y126600D01*
X1303500D01*
X1307300Y122800D01*
Y109500D01*
X1310300Y106500D01*
X1313455D01*
X1324655Y95300D01*
X1329100D01*
X1331100Y93300D01*
Y89723D01*
X1338700Y82123D01*
Y78300D01*
X1336850Y76450D01*
G01X1317300Y89600D02*
X1319200D01*
X1321900Y86900D01*
Y84712D01*
X1321100Y83912D01*
Y67300D01*
X1324220Y64180D01*
Y60050D01*
X1325570Y58700D01*
X1345800D01*
X1347600Y60500D01*
Y62000D01*
X1349359Y63759D01*
X1363751D01*
X1370512Y56998D01*
X1372820D01*
X1374800Y55018D01*
Y48200D01*
X1372653Y46053D01*
X1370053D01*
X1365158Y41158D01*
Y38800D01*
X1366158Y37800D01*
X1367100D01*
G01X1331720Y334810D02*
X1328173D01*
X1326300Y336683D01*
Y341309D01*
G01X1308500Y540784D02*
Y536987D01*
X1310725Y534762D01*
Y507886D01*
X1297878Y495039D01*
Y493150D01*
G01X1295240Y493359D02*
Y495802D01*
X1308364Y508926D01*
Y533693D01*
X1305500Y536557D01*
Y542500D01*
G01X1380950Y30232D02*
X1383374D01*
X1386780Y26826D01*
Y5680D01*
X1380678Y-422D01*
G01X1380950Y30232D02*
X1384133Y33415D01*
Y48459D01*
X1383171Y49421D01*
Y57549D01*
G01X1435655Y246550D02*
X1433650D01*
X1415867Y264333D01*
X1410386D01*
X1406319Y268400D01*
X1357523D01*
X1353573Y272350D01*
X1345050D01*
G01X1476761Y157400D02*
X1476349Y156988D01*
X1473889D01*
X1470427Y153526D01*
X1450233D01*
X1448382Y151675D01*
Y137646D01*
X1449366Y136663D01*
X1450709Y135767D01*
X1450971Y135592D01*
X1455237D01*
X1468427Y122402D01*
Y115563D01*
X1468509Y115168D01*
X1468817Y113684D01*
X1470177Y107117D01*
X1471477Y106401D01*
X1471478D01*
X1472306Y105946D01*
X1472307D01*
X1473188Y105461D01*
X1475301Y104299D01*
X1481016Y98584D01*
Y87049D01*
X1498465Y69600D01*
X1542330D01*
X1547349Y64581D01*
X1568664D01*
X1573083Y69000D01*
X1579100D01*
G01X1468700Y163100D02*
X1466714Y161114D01*
X1451891D01*
X1447756Y165249D01*
Y179074D01*
X1443629Y183201D01*
X1439261D01*
X1433324Y189138D01*
X1432739D01*
X1431664Y190213D01*
G01X1464150Y235550D02*
X1446000D01*
X1437400Y244150D01*
G01X1445510Y350327D02*
X1447035Y348802D01*
X1473012D01*
X1478514Y343300D01*
X1484970D01*
X1487858Y340412D01*
G01X1415450Y350550D02*
X1410537Y355463D01*
Y381927D01*
X1417617Y389007D01*
Y406485D01*
X1424893Y413761D01*
Y432031D01*
X1426550Y433688D01*
Y443242D01*
X1428258Y444950D01*
X1432750D01*
X1434100Y446300D01*
Y465300D01*
X1431183Y468217D01*
Y493025D01*
X1436587Y498429D01*
X1438041Y498725D01*
X1461791D01*
X1463119Y497397D01*
X1469223D01*
X1469673Y497847D01*
X1474677D01*
X1476116Y496408D01*
X1494953D01*
X1497705Y493656D01*
X1526147D01*
X1528707Y496216D01*
Y511719D01*
X1531775Y514787D01*
X1569188D01*
X1581874Y502101D01*
X1601175D01*
X1606690Y499817D01*
X1613706Y492801D01*
X1618757D01*
X1621458Y490100D01*
X1624933D01*
X1628337Y493504D01*
X1630788D01*
X1630792Y493500D01*
X1640753D01*
X1642726Y491527D01*
Y490201D01*
X1642880Y490047D01*
G01X1485250Y408017D02*
X1484315Y408952D01*
X1480748D01*
X1475654Y414046D01*
X1466858D01*
X1465400Y412588D01*
Y408900D01*
X1461924Y405424D01*
X1461900Y405353D01*
X1461400Y403864D01*
Y402064D01*
X1460700Y401206D01*
X1457413Y397178D01*
X1457071Y395430D01*
Y394505D01*
X1457149Y394112D01*
X1459100Y392161D01*
Y375551D01*
X1463870Y370781D01*
Y367869D01*
G01D02*
X1467029D01*
X1477868Y357030D01*
X1479922D01*
X1481272Y355680D01*
Y351018D01*
X1481300Y350990D01*
Y350300D01*
X1481000Y350000D01*
G01X1461016Y359965D02*
Y363316D01*
X1462200Y364500D01*
X1464400D01*
X1465400Y363500D01*
Y362000D01*
X1466450Y360950D01*
X1470670D01*
X1476620Y355000D01*
X1478020D01*
X1478080Y354940D01*
X1478163D01*
G01X1441252Y548631D02*
X1442274Y549653D01*
X1456847D01*
X1458570Y547930D01*
X1512795D01*
X1514236Y546489D01*
X1546458D01*
X1550238Y550269D01*
X1566313D01*
X1569977Y553933D01*
X1583379D01*
X1585699Y556253D01*
X1598996D01*
X1609509Y551899D01*
X1609705D01*
X1617117Y548829D01*
X1652825D01*
X1661455Y540199D01*
X1666359D01*
X1668853Y537705D01*
X1677332D01*
X1682827Y543200D01*
X1725800D01*
X1740100Y528900D01*
X1746100D01*
X1766300Y508700D01*
X1798000D01*
X1809201Y519901D01*
X1814852D01*
G01X1477100Y2400D02*
X1478000Y1500D01*
X1494948D01*
X1500630Y7182D01*
X1507730D01*
X1512823Y12275D01*
X1530978D01*
X1531342Y11911D01*
X1538520D01*
G01X1599500Y75000D02*
X1599250Y75250D01*
X1598890D01*
X1594100Y80040D01*
X1589143D01*
X1587758Y78655D01*
X1552657D01*
X1545490Y71488D01*
X1499123D01*
X1482816Y87795D01*
Y99840D01*
X1477494Y105163D01*
X1475396Y107261D01*
X1473651D01*
X1473399Y107400D01*
X1471581Y109218D01*
X1470580Y114049D01*
X1470427Y114791D01*
Y123212D01*
X1466841Y126798D01*
Y130200D01*
X1467841Y131200D01*
X1468590D01*
G01X1496713Y174853D02*
X1496560Y174700D01*
X1486993D01*
X1484415Y172122D01*
X1482274D01*
X1478719Y168567D01*
X1474167D01*
X1468700Y163100D01*
G01X1514050Y327490D02*
X1521888D01*
X1522758Y326620D01*
X1531952D01*
X1533228Y325344D01*
Y325000D01*
G01X1481000Y350000D02*
X1483099Y347901D01*
X1486068D01*
X1491790Y342179D01*
Y337110D01*
X1496000Y332900D01*
X1511040D01*
X1513260Y330680D01*
X1513796D01*
G01X1553000Y591100D02*
Y592736D01*
X1549338Y596398D01*
Y603406D01*
X1547324Y605420D01*
Y611998D01*
X1548800Y613474D01*
Y618964D01*
X1546894Y620870D01*
X1545264D01*
X1542013Y617619D01*
X1537931D01*
X1534947Y620603D01*
X1519703D01*
X1518900Y619800D01*
G01X1483279Y619100D02*
Y622080D01*
X1485069Y623870D01*
X1548137D01*
X1552741Y619266D01*
Y612340D01*
X1550496Y610095D01*
Y606534D01*
X1552423Y604607D01*
Y597749D01*
X1556500Y593672D01*
Y592000D01*
X1555600Y591100D01*
G01X1541162Y607903D02*
X1540523Y607264D01*
X1524126D01*
X1521526Y609864D01*
X1510187D01*
X1509187Y610864D01*
Y613961D01*
X1513700Y618474D01*
Y619900D01*
G01X1543697Y606719D02*
X1543514D01*
X1540736Y603941D01*
X1523089D01*
X1521530Y605500D01*
X1476820D01*
X1473870Y608450D01*
Y612934D01*
X1478500Y617564D01*
Y619300D01*
G01X1544180Y91660D02*
X1553694D01*
X1554784Y90570D01*
X1559131D01*
X1565581Y84120D01*
X1573060D01*
G01X1587734Y70974D02*
X1587600Y70840D01*
Y61370D01*
X1607975Y40995D01*
Y37087D01*
X1611412Y33650D01*
X1648150D01*
X1651250Y36750D01*
G01X1579100Y69000D02*
X1579901D01*
X1583775Y72874D01*
X1588522D01*
X1590700Y70696D01*
Y65483D01*
X1612835Y43348D01*
X1652514D01*
X1654214Y41648D01*
X1677174D01*
X1677900Y42374D01*
X1768705D01*
X1787428Y61097D01*
X1789033D01*
X1790796Y59334D01*
X1798493D01*
X1803360Y64201D01*
X1814163D01*
X1821000Y57364D01*
Y55001D01*
X1826574Y49427D01*
X1848208D01*
G01X1549964Y424753D02*
X1549880Y424837D01*
Y428970D01*
X1550650Y429740D01*
X1550750D01*
X1551875Y430865D01*
Y436786D01*
G01X1666500Y10500D02*
X1663250Y7250D01*
X1660751D01*
X1657876Y4375D01*
X1654923D01*
X1653948Y3400D01*
X1644900D01*
X1641100Y7200D01*
X1638550D01*
G01X1642880Y490047D02*
X1644418Y491585D01*
X1661548D01*
X1664233Y488900D01*
X1672716D01*
X1676800Y484816D01*
Y483800D01*
G01X1617300Y519000D02*
X1617601Y519301D01*
X1623563D01*
X1626912Y522650D01*
X1633649D01*
X1635281Y524282D01*
Y527181D01*
X1637500Y529400D01*
G01X1692300Y56900D02*
Y48700D01*
X1689080Y45480D01*
X1676592D01*
X1675812Y44700D01*
X1658600D01*
G01X1676800Y483800D02*
X1676538D01*
X1667677Y474939D01*
Y467271D01*
X1667674D01*
G01X1789300Y520000D02*
X1772900D01*
X1769800Y523100D01*
X1767100D01*
X1766100Y522100D01*
Y521124D01*
G01X1781300Y537800D02*
X1790250Y528850D01*
Y522350D01*
G54D18*
X42724Y644684D03*
Y644656D03*
Y654684D03*
Y654656D03*
X67724Y644684D03*
Y644656D03*
Y654684D03*
Y654656D03*
X221656Y644656D03*
X196656D03*
X231446Y644756D03*
Y644784D03*
X221656Y644684D03*
X196656D03*
X221656Y654656D03*
X196656D03*
X231446Y654756D03*
Y654784D03*
X221656Y654684D03*
X196656D03*
X256446Y644756D03*
Y644784D03*
Y654756D03*
Y654784D03*
X409240Y644564D03*
X384240D03*
X418914Y644486D03*
Y644514D03*
X409240Y644536D03*
X384240D03*
X409240Y654564D03*
X384240D03*
X418914Y654486D03*
Y654514D03*
X409240Y654536D03*
X384240D03*
X596707Y644293D03*
X596708Y644266D03*
X596707Y654293D03*
X596708Y654266D03*
X606462Y644245D03*
X631462D03*
X606462Y644217D03*
X631462D03*
X606462Y654245D03*
X631462D03*
X606462Y654217D03*
X631462D03*
X912351Y644245D03*
X887351D03*
X912351Y644273D03*
X887351D03*
X912351Y654245D03*
X887351D03*
X912351Y654273D03*
X887351D03*
X922116Y644206D03*
X947116D03*
X922116Y644234D03*
X947116D03*
X922116Y654206D03*
X947116D03*
X922116Y654234D03*
X947116D03*
X1200877Y644262D03*
Y644234D03*
Y654262D03*
Y654234D03*
X1225877Y644262D03*
X1235614Y644236D03*
Y644264D03*
X1225877Y644234D03*
Y654262D03*
X1235614Y654236D03*
Y654264D03*
X1225877Y654234D03*
X1539375Y644292D03*
Y644264D03*
Y654292D03*
Y654264D03*
G54D37*
G01X-15354Y365236D02*
X-13894D01*
X-13270Y365860D01*
Y366982D01*
X-14208Y367920D01*
X-17926D01*
X-20400Y370394D01*
Y383786D01*
X-18166Y386020D01*
X34643D01*
X37505Y388882D01*
X42102Y399979D01*
Y419329D01*
X44843Y422070D01*
X48815D01*
X49265Y422520D01*
Y423995D01*
G01X-9843Y365236D02*
X-11218D01*
X-12120Y366138D01*
Y367459D01*
X-13731Y369070D01*
X-17449D01*
X-19250Y370871D01*
Y373101D01*
X-18600Y373751D01*
Y375101D01*
X-19250Y375751D01*
Y377101D01*
X-18600Y377751D01*
Y379101D01*
X-19250Y379751D01*
Y383309D01*
X-17689Y384870D01*
X-14835D01*
X-14185Y384220D01*
X-12835D01*
X-12185Y384870D01*
X35120D01*
X38481Y388230D01*
X43252Y399750D01*
Y418852D01*
X45320Y420920D01*
X48815D01*
X49265Y420470D01*
Y418995D01*
G01X37550Y425400D02*
X38595Y426636D01*
X39229Y426688D01*
X39924Y426100D01*
X54199D01*
X59999Y431900D01*
X62999D01*
X65425Y429474D01*
Y428555D01*
X66380Y427600D01*
X67299D01*
X68254Y426645D01*
Y425726D01*
X69208Y424772D01*
X70127D01*
X72950Y421949D01*
Y420599D01*
X72300Y419949D01*
Y418599D01*
X72950Y417949D01*
Y416599D01*
X72300Y415949D01*
Y414599D01*
X72950Y413949D01*
Y398941D01*
X72300Y398291D01*
Y396941D01*
X72950Y396291D01*
Y394941D01*
X66109Y388100D01*
X62173D01*
X58355Y384282D01*
X57436D01*
X56482Y383328D01*
Y382409D01*
X55527Y381454D01*
X54608D01*
X53654Y380500D01*
Y379581D01*
X52699Y378626D01*
X50872Y374213D01*
Y372863D01*
X50222Y372213D01*
Y370863D01*
X50872Y370213D01*
Y368863D01*
X50222Y368213D01*
Y366863D01*
X50872Y366213D01*
Y362635D01*
X53873Y359634D01*
Y343850D01*
X50850Y340827D01*
Y340000D01*
X49977Y339127D01*
Y331823D01*
X52650Y329150D01*
X53523D01*
X54750Y327923D01*
Y322877D01*
X48950Y317077D01*
Y313123D01*
X53124Y308949D01*
X54324D01*
X55350Y307923D01*
Y278108D01*
X60525Y272933D01*
X73751D01*
X79444Y267240D01*
Y220735D01*
X74836Y216127D01*
X57671D01*
X53825Y212281D01*
Y196665D01*
X55647Y194843D01*
X64478D01*
X68391Y190930D01*
Y170595D01*
X54269Y156473D01*
Y151470D01*
X51349Y148550D01*
X44124D01*
X41350Y145776D01*
Y136670D01*
X34080Y129400D01*
X28260D01*
X26166Y131494D01*
Y132267D01*
X26616Y132717D01*
X28346D01*
G01X40965Y429434D02*
X39920Y428199D01*
X39974Y427565D01*
X40348Y427250D01*
X53722D01*
X59522Y433050D01*
X63476D01*
X74100Y422426D01*
Y394464D01*
X66586Y386950D01*
X62650D01*
X53675Y377974D01*
X52022Y373984D01*
Y363112D01*
X55023Y360111D01*
Y343373D01*
X52000Y340350D01*
Y339523D01*
X51127Y338650D01*
Y332300D01*
X53127Y330300D01*
X54000D01*
X55900Y328400D01*
Y322400D01*
X50100Y316600D01*
Y313600D01*
X53601Y310099D01*
X54801D01*
X56500Y308400D01*
Y278585D01*
X61002Y274083D01*
X74228D01*
X80594Y267717D01*
Y220258D01*
X75313Y214977D01*
X58148D01*
X54975Y211804D01*
Y197142D01*
X56124Y195993D01*
X64955D01*
X69541Y191407D01*
Y170118D01*
X55419Y155996D01*
Y150993D01*
X51826Y147400D01*
X44601D01*
X42500Y145299D01*
Y136193D01*
X34557Y128250D01*
X27783D01*
X25016Y131017D01*
Y132267D01*
X24566Y132717D01*
X22835D01*
G01X-9843Y396732D02*
X-11933D01*
X-12383Y396282D01*
Y394711D01*
X-11062Y393390D01*
X31494D01*
X32449Y394345D01*
Y395264D01*
X33403Y396218D01*
X34322D01*
X35277Y397173D01*
Y398092D01*
X36232Y399047D01*
X37151D01*
X38962Y400858D01*
Y415861D01*
X38007Y416816D01*
X37088D01*
X36134Y417770D01*
Y418689D01*
X35179Y419644D01*
X34260D01*
X33305Y420599D01*
Y421518D01*
X32350Y422473D01*
X31431D01*
X30477Y423427D01*
Y424346D01*
X28810Y426013D01*
Y427363D01*
X28160Y428013D01*
Y429363D01*
X28810Y430013D01*
Y431363D01*
X28160Y432013D01*
Y433363D01*
X28810Y434013D01*
Y435363D01*
X28160Y436013D01*
Y437363D01*
X28810Y438013D01*
Y440553D01*
X27854Y441509D01*
X24897D01*
X24447Y441059D01*
Y439354D01*
G01X10786Y441785D02*
X12261D01*
X12711Y441335D01*
Y439783D01*
X14064Y438430D01*
X17920D01*
X19120Y437230D01*
X24146Y425093D01*
X36200Y413039D01*
Y403349D01*
X34115Y401264D01*
X5083D01*
X3362Y399543D01*
Y397182D01*
X2912Y396732D01*
X1181D01*
G01X-15354D02*
X-13983D01*
X-13533Y396282D01*
Y394234D01*
X-11539Y392240D01*
X31971D01*
X40112Y400381D01*
Y416338D01*
X29960Y426490D01*
Y441030D01*
X28331Y442659D01*
X24897D01*
X24447Y443109D01*
Y444354D01*
G01X6693Y396732D02*
X4962D01*
X4512Y397182D01*
Y399066D01*
X5560Y400114D01*
X34592D01*
X37350Y402872D01*
Y413516D01*
X25122Y425745D01*
X20096Y437882D01*
X18397Y439580D01*
X14541D01*
X13861Y440260D01*
Y441335D01*
X14311Y441785D01*
X15786D01*
G01X22835Y357362D02*
X24566D01*
X25016Y357812D01*
Y360490D01*
X26420Y361894D01*
X31066D01*
X40070Y370898D01*
X49104Y392701D01*
X53591Y397188D01*
X61344Y400400D01*
X68461D01*
X69850Y401789D01*
Y409949D01*
X57650Y422149D01*
Y425402D01*
X59628Y427380D01*
X60555D01*
X61005Y427830D01*
Y429305D01*
G01X23228Y365236D02*
X21715D01*
X21048Y365903D01*
Y367887D01*
X22071Y368910D01*
X26622D01*
X27272Y368260D01*
X28622D01*
X29272Y368910D01*
X30622D01*
X31312Y368220D01*
X32512D01*
X33202Y368910D01*
X34911D01*
X39553Y373552D01*
X49250Y396969D01*
Y400310D01*
X49940Y401000D01*
Y402200D01*
X49250Y402890D01*
Y406374D01*
X50676Y407800D01*
X53192D01*
X54244Y406748D01*
Y405624D01*
G01X63024Y405636D02*
X65156D01*
X65928Y406408D01*
Y409013D01*
X64709Y410232D01*
X63790D01*
X62836Y411186D01*
Y412105D01*
X61881Y413060D01*
X60531D01*
X59881Y412410D01*
X58531D01*
X57881Y413060D01*
X55050D01*
X54400Y412410D01*
X53050D01*
X52400Y413060D01*
X51050D01*
X50095Y412105D01*
Y411186D01*
X49141Y410232D01*
X48222D01*
X46245Y408255D01*
Y398987D01*
X42843Y390774D01*
X43195Y389925D01*
X42678Y388678D01*
X41829Y388326D01*
X41312Y387079D01*
X38864Y384607D01*
X38868Y383688D01*
X37918Y382729D01*
X36999Y382724D01*
X36049Y381765D01*
X36053Y380846D01*
X35103Y379887D01*
X34184Y379882D01*
X33234Y378923D01*
X33238Y378004D01*
X32288Y377045D01*
X31369Y377040D01*
X30419Y376081D01*
X26870Y376080D01*
X26240Y375450D01*
Y374290D01*
X27420Y373110D01*
X28346D01*
G01X6299Y357362D02*
X8051D01*
X8481Y356932D01*
Y353531D01*
X11113Y350899D01*
X35636D01*
X44671Y359934D01*
Y369480D01*
X52618Y390690D01*
X55728Y393800D01*
X63860D01*
X64725Y392935D01*
Y391645D01*
G01X28346Y357362D02*
X26616D01*
X26166Y357812D01*
Y360013D01*
X26897Y360744D01*
X31543D01*
X41046Y370246D01*
X50080Y392049D01*
X54243Y396212D01*
X61573Y399250D01*
X68938D01*
X71000Y401312D01*
Y410426D01*
X68199Y413227D01*
Y414146D01*
X67244Y415101D01*
X66325D01*
X65370Y416056D01*
Y416975D01*
X64415Y417930D01*
X63496D01*
X62541Y418885D01*
Y419804D01*
X61587Y420758D01*
X60668D01*
X58800Y422626D01*
Y424925D01*
X60105Y426230D01*
X60555D01*
X61005Y425780D01*
Y424305D01*
G01X17716Y365236D02*
X19898Y367418D01*
Y368364D01*
X21594Y370060D01*
X34434D01*
X38577Y374204D01*
X48100Y397198D01*
Y406851D01*
X50199Y408950D01*
X53669D01*
X54456Y408163D01*
X56383D01*
G01X22835Y373110D02*
X24079D01*
X25090Y374121D01*
Y375927D01*
X26394Y377231D01*
X29939D01*
X40335Y387727D01*
X45095Y399216D01*
Y408732D01*
X50573Y414210D01*
X62358D01*
X67078Y409490D01*
Y405931D01*
X65384Y404237D01*
Y403258D01*
G01X11811Y357362D02*
X10061D01*
X9631Y356932D01*
Y354008D01*
X11590Y352049D01*
X23159D01*
X23809Y352699D01*
X25159D01*
X25809Y352049D01*
X27159D01*
X27809Y352699D01*
X29159D01*
X29809Y352049D01*
X31159D01*
X31809Y352699D01*
X33159D01*
X33809Y352049D01*
X35159D01*
X43521Y360411D01*
Y362526D01*
X42989Y363058D01*
Y364408D01*
X43521Y364940D01*
Y369689D01*
X51628Y391327D01*
X55251Y394950D01*
X63860D01*
X63880Y394930D01*
X64275D01*
X64725Y395380D01*
Y396645D01*
G01X12025Y424850D02*
X13500D01*
X13950Y424400D01*
Y422388D01*
X15360Y420070D01*
X29085Y415972D01*
X31400Y413656D01*
Y411299D01*
X29239Y409138D01*
X-6091D01*
X-8055Y407174D01*
Y405056D01*
X-8505Y404606D01*
X-10236D01*
G01X2025Y424850D02*
X3500D01*
X3950Y424400D01*
Y420757D01*
X3362Y420169D01*
Y412930D01*
X2912Y412480D01*
X1181D01*
G01X-4725Y404606D02*
X-6455D01*
X-6905Y405056D01*
Y406697D01*
X-5614Y407988D01*
X29716D01*
X32550Y410822D01*
Y414133D01*
X29693Y416991D01*
X16113Y421046D01*
X15100Y422711D01*
Y424400D01*
X15550Y424850D01*
X17025D01*
G01X6693Y412480D02*
X4962D01*
X4512Y412930D01*
Y419692D01*
X5100Y420280D01*
Y424400D01*
X5550Y424850D01*
X7025D01*
G01X559375Y296961D02*
Y298311D01*
X560025Y298961D01*
Y300311D01*
X559375Y300961D01*
Y302311D01*
X560025Y302961D01*
Y304311D01*
X559375Y304961D01*
Y306311D01*
X560025Y306961D01*
Y308311D01*
X559375Y308961D01*
Y310389D01*
X564863Y315877D01*
Y328236D01*
X582730Y346103D01*
X607847D01*
X608297Y345653D01*
Y344503D01*
X607847Y344053D01*
X583618D01*
X582416Y342851D01*
Y340826D01*
X583539Y339703D01*
X607847D01*
X608297Y339253D01*
Y338103D01*
X607847Y337653D01*
X577572D01*
X576396Y336477D01*
Y334453D01*
X577546Y333303D01*
X607847D01*
X608297Y332853D01*
Y331703D01*
X607847Y331253D01*
X570939D01*
X569729Y330043D01*
Y328013D01*
X570839Y326903D01*
X611523D01*
X612647Y328027D01*
Y345653D01*
X613097Y346103D01*
X615516D01*
X616103Y345516D01*
Y324771D01*
X626134Y314740D01*
X627988D01*
X629230Y315982D01*
Y317799D01*
X620884Y326145D01*
Y326778D01*
X621649Y327543D01*
X622389D01*
X635995Y313937D01*
X637099D01*
X637561Y313475D01*
Y312000D01*
G01X558225Y296961D02*
Y310866D01*
X563713Y316354D01*
Y328713D01*
X582253Y347253D01*
X608324D01*
X609447Y346130D01*
Y344026D01*
X608324Y342903D01*
X584095D01*
X583566Y342374D01*
Y341303D01*
X584016Y340853D01*
X608324D01*
X609447Y339730D01*
Y337626D01*
X608324Y336503D01*
X578049D01*
X577546Y336000D01*
Y334930D01*
X578023Y334453D01*
X608324D01*
X609447Y333330D01*
Y331226D01*
X608324Y330103D01*
X571416D01*
X570879Y329566D01*
Y328490D01*
X571316Y328053D01*
X611046D01*
X611497Y328504D01*
Y346130D01*
X612620Y347253D01*
X615993D01*
X617253Y345993D01*
Y325248D01*
X626611Y315890D01*
X627511D01*
X628080Y316459D01*
Y317322D01*
X619734Y325668D01*
Y327255D01*
X621172Y328693D01*
X622866D01*
X636472Y315087D01*
X637111D01*
X637561Y315537D01*
Y317000D01*
G01X568212Y353253D02*
Y358925D01*
X568862Y359575D01*
Y360925D01*
X568212Y361575D01*
Y362925D01*
X568862Y363575D01*
Y364925D01*
X568212Y365575D01*
Y366925D01*
X568862Y367575D01*
Y368925D01*
X568212Y369575D01*
Y370925D01*
X568862Y371575D01*
Y372925D01*
X568212Y373575D01*
Y388601D01*
X568862Y389251D01*
Y390601D01*
X568212Y391251D01*
Y392601D01*
X568862Y393251D01*
Y394601D01*
X568212Y395251D01*
Y396601D01*
X568862Y397251D01*
Y398601D01*
X568212Y399251D01*
Y404601D01*
X572378Y408767D01*
X610863D01*
X612000Y409904D01*
Y411994D01*
X610877Y413117D01*
X572410D01*
X571960Y413567D01*
Y414717D01*
X572410Y415167D01*
X613172D01*
X617066Y411273D01*
X620722D01*
X640037Y391958D01*
Y391320D01*
X639223Y390506D01*
X638585D01*
X620458Y408633D01*
X618545D01*
X617219Y407307D01*
Y405718D01*
X636304Y386633D01*
Y351723D01*
X637427Y350600D01*
X640777D01*
X641900Y351723D01*
Y383650D01*
X642350Y384100D01*
X643700D01*
X644150Y383650D01*
Y353273D01*
X645273Y352150D01*
X647277D01*
X648400Y353273D01*
Y383126D01*
X649072Y383798D01*
X650402D01*
X651125Y383075D01*
Y353137D01*
X649194Y351206D01*
G01X567062Y353253D02*
Y405078D01*
X571901Y409917D01*
X610386D01*
X610850Y410381D01*
Y411517D01*
X610400Y411967D01*
X571933D01*
X570810Y413090D01*
Y415194D01*
X571933Y416317D01*
X613649D01*
X617543Y412423D01*
X621199D01*
X641189Y392433D01*
Y390845D01*
X639698Y389354D01*
X638110D01*
X619981Y407483D01*
X619022D01*
X618369Y406830D01*
Y406195D01*
X637454Y387110D01*
Y352200D01*
X637904Y351750D01*
X640300D01*
X640750Y352200D01*
Y384127D01*
X641873Y385250D01*
X644177D01*
X645300Y384127D01*
Y353750D01*
X645750Y353300D01*
X646800D01*
X647250Y353750D01*
Y383603D01*
X648595Y384948D01*
X650879D01*
X652275Y383552D01*
Y353125D01*
X654194Y351206D01*
G01X565348Y347421D02*
X570494D01*
X573950Y350877D01*
Y399210D01*
X575117Y400377D01*
X577164D01*
X578300Y399241D01*
Y365247D01*
X578750Y364797D01*
X579900D01*
X580350Y365247D01*
Y398792D01*
X581473Y399915D01*
X583520D01*
X584700Y398735D01*
Y382101D01*
X585150Y381651D01*
X586300D01*
X586750Y382101D01*
Y396442D01*
X590269Y399961D01*
X609125D01*
X609603Y400439D01*
Y401561D01*
X609153Y402011D01*
X579888D01*
X578765Y403134D01*
Y405238D01*
X579888Y406361D01*
X612773D01*
X629034Y390100D01*
Y388468D01*
X627586Y387020D01*
X625957D01*
X616325Y396652D01*
X615577D01*
X614819Y395894D01*
Y395258D01*
X625300Y384777D01*
Y337000D01*
X625750Y336550D01*
X626900D01*
X627350Y337000D01*
Y383235D01*
X628473Y384358D01*
X631123D01*
X632400Y383081D01*
Y336250D01*
X633250Y335400D01*
X637101D01*
X637681Y335980D01*
Y337390D01*
G01X576941Y646238D02*
X574516Y648663D01*
X572728D01*
X568453Y649005D01*
X565349Y648018D01*
X564727Y647188D01*
X564550Y646492D01*
X564139Y644155D01*
X562837Y643243D01*
X560863Y643590D01*
X559952Y644894D01*
X561436Y653300D01*
X561069Y653824D01*
X560035Y654007D01*
X559516Y653644D01*
X557832Y644094D01*
X556528Y643180D01*
X554554Y643528D01*
X553645Y644833D01*
X555137Y653286D01*
X554773Y653807D01*
X553738Y653989D01*
X553215Y653624D01*
X551537Y644090D01*
X550234Y643180D01*
X548262Y643525D01*
X547350Y644829D01*
X548841Y653285D01*
X548477Y653806D01*
X547443Y653988D01*
X546920Y653623D01*
X545237Y644071D01*
X543934Y643162D01*
X541965Y643507D01*
X541050Y644807D01*
X542550Y653318D01*
X542186Y653839D01*
X541152Y654021D01*
X540632Y653657D01*
X538942Y644076D01*
X537639Y643160D01*
X535665Y643509D01*
X534753Y644810D01*
X536253Y653317D01*
X535890Y653839D01*
X534856Y654022D01*
X534334Y653657D01*
X532666Y644188D01*
X531363Y643274D01*
X529389Y643620D01*
X528479Y644925D01*
X529956Y653301D01*
X529592Y653822D01*
X528558Y654003D01*
X528036Y653639D01*
X526367Y644183D01*
X525065Y643273D01*
X523094Y643620D01*
X522183Y644924D01*
X523661Y653299D01*
X523296Y653821D01*
X522261Y654003D01*
X521739Y653639D01*
X520073Y644166D01*
X518767Y643257D01*
X516796Y643601D01*
X515885Y644908D01*
X517371Y653332D01*
X517006Y653854D01*
X515971Y654036D01*
X515449Y653672D01*
X513783Y644216D01*
X512443Y643277D01*
X510535Y643612D01*
X509598Y644954D01*
X511075Y653332D01*
X510711Y653854D01*
X509677Y654036D01*
X509155Y653671D01*
X507517Y644411D01*
X506214Y643501D01*
X504241Y643848D01*
X503331Y645151D01*
X504808Y653529D01*
X504417Y654089D01*
X503449Y654259D01*
X502889Y653867D01*
X501223Y644410D01*
X499920Y643501D01*
X497946Y643847D01*
X497035Y645151D01*
X498521Y653576D01*
X498156Y654100D01*
X497124Y654280D01*
X496600Y653915D01*
X494933Y644443D01*
X493630Y643534D01*
X491656Y643880D01*
X490745Y645184D01*
X492223Y653559D01*
X491858Y654081D01*
X490826Y654263D01*
X490305Y653899D01*
X488636Y644443D01*
X487333Y643534D01*
X485360Y643879D01*
X484450Y645182D01*
X485927Y653559D01*
X485563Y654081D01*
X484530Y654262D01*
X484007Y653895D01*
X482338Y644425D01*
X481035Y643515D01*
X479062Y643863D01*
X478153Y645164D01*
X479653Y653672D01*
X479288Y654193D01*
X478254Y654376D01*
X477731Y654008D01*
X476040Y644426D01*
X474740Y643515D01*
X472766Y643862D01*
X471856Y645165D01*
X473356Y653674D01*
X472990Y654194D01*
X471957Y654375D01*
X471435Y654011D01*
X469753Y644459D01*
X468449Y643549D01*
X466475Y643895D01*
X465565Y645198D01*
X467056Y653654D01*
X466691Y654176D01*
X465658Y654357D01*
X465136Y653992D01*
X463457Y644458D01*
X462153Y643548D01*
X460179Y643894D01*
X459269Y645197D01*
X460761Y653651D01*
X460397Y654174D01*
X459364Y654356D01*
X458841Y653989D01*
X457156Y644439D01*
X455856Y643529D01*
X453883Y643878D01*
X452970Y645182D01*
X454454Y653589D01*
X454089Y654111D01*
X453055Y654293D01*
X452534Y653928D01*
X452198Y652018D01*
X451954Y651057D01*
X450973Y649749D01*
X447302Y648582D01*
X442847Y648939D01*
X441106D01*
X438681Y646514D01*
G01X576941Y652238D02*
X574516Y649813D01*
X572775D01*
X568320Y650170D01*
X564649Y649003D01*
X563668Y647695D01*
X563424Y646734D01*
X563088Y644824D01*
X562567Y644459D01*
X561533Y644641D01*
X561168Y645163D01*
X562652Y653570D01*
X561739Y654874D01*
X559766Y655223D01*
X558466Y654313D01*
X556781Y644763D01*
X556258Y644396D01*
X555225Y644578D01*
X554861Y645101D01*
X556353Y653555D01*
X555443Y654858D01*
X553469Y655204D01*
X552165Y654294D01*
X550486Y644760D01*
X549964Y644395D01*
X548931Y644576D01*
X548566Y645098D01*
X550057Y653554D01*
X549147Y654857D01*
X547173Y655203D01*
X545869Y654293D01*
X544187Y644741D01*
X543665Y644377D01*
X542632Y644558D01*
X542266Y645078D01*
X543766Y653587D01*
X542856Y654890D01*
X540882Y655237D01*
X539582Y654326D01*
X537891Y644744D01*
X537368Y644376D01*
X536334Y644559D01*
X535969Y645080D01*
X537469Y653588D01*
X536560Y654889D01*
X534587Y655237D01*
X533284Y654327D01*
X531615Y644857D01*
X531092Y644490D01*
X530059Y644671D01*
X529695Y645193D01*
X531172Y653570D01*
X530262Y654873D01*
X528289Y655218D01*
X526986Y654309D01*
X525317Y644853D01*
X524796Y644489D01*
X523764Y644671D01*
X523399Y645193D01*
X524877Y653568D01*
X523966Y654872D01*
X521992Y655218D01*
X520689Y654309D01*
X519022Y644837D01*
X518498Y644472D01*
X517466Y644652D01*
X517101Y645176D01*
X518587Y653601D01*
X517676Y654905D01*
X515702Y655251D01*
X514399Y654342D01*
X512733Y644885D01*
X512173Y644493D01*
X511205Y644663D01*
X510814Y645223D01*
X512291Y653601D01*
X511381Y654904D01*
X509408Y655251D01*
X508105Y654341D01*
X506467Y645081D01*
X505945Y644716D01*
X504911Y644898D01*
X504547Y645420D01*
X506024Y653798D01*
X505087Y655140D01*
X503179Y655475D01*
X501839Y654536D01*
X500173Y645080D01*
X499651Y644716D01*
X498616Y644898D01*
X498251Y645420D01*
X499737Y653844D01*
X498826Y655151D01*
X496855Y655495D01*
X495549Y654586D01*
X493883Y645113D01*
X493361Y644749D01*
X492326Y644931D01*
X491961Y645453D01*
X493439Y653828D01*
X492528Y655132D01*
X490557Y655479D01*
X489255Y654569D01*
X487586Y645113D01*
X487064Y644749D01*
X486030Y644930D01*
X485666Y645451D01*
X487143Y653827D01*
X486233Y655132D01*
X484259Y655478D01*
X482956Y654564D01*
X481288Y645095D01*
X480766Y644730D01*
X479732Y644913D01*
X479369Y645435D01*
X480869Y653942D01*
X479957Y655243D01*
X477983Y655592D01*
X476680Y654676D01*
X474990Y645095D01*
X474470Y644731D01*
X473436Y644913D01*
X473072Y645434D01*
X474572Y653945D01*
X473657Y655245D01*
X471688Y655590D01*
X470385Y654681D01*
X468702Y645129D01*
X468179Y644764D01*
X467145Y644946D01*
X466781Y645467D01*
X468272Y653923D01*
X467360Y655227D01*
X465388Y655572D01*
X464085Y654662D01*
X462407Y645128D01*
X461884Y644763D01*
X460849Y644945D01*
X460485Y645466D01*
X461977Y653919D01*
X461068Y655224D01*
X459094Y655572D01*
X457790Y654658D01*
X456106Y645108D01*
X455587Y644745D01*
X454553Y644928D01*
X454186Y645452D01*
X455670Y653858D01*
X454759Y655162D01*
X452785Y655509D01*
X451483Y654597D01*
X451072Y652260D01*
X450895Y651564D01*
X450273Y650734D01*
X447169Y649747D01*
X442894Y650089D01*
X441106D01*
X438681Y652514D01*
G01X659694Y351206D02*
X660445D01*
X661219Y351980D01*
Y353240D01*
X660613Y353846D01*
X658574D01*
X657600Y352872D01*
Y350227D01*
X657000Y349627D01*
Y346601D01*
X655299Y344900D01*
X645928D01*
X642370Y341342D01*
Y339992D01*
X642377Y339985D01*
Y339349D01*
X642370Y339342D01*
Y298670D01*
X640100Y296400D01*
X634739D01*
X634089Y295750D01*
X632739D01*
X632089Y296400D01*
X630739D01*
X630089Y295750D01*
X628739D01*
X628089Y296400D01*
X626739D01*
X625616Y297523D01*
Y307230D01*
X625166Y307680D01*
X624096D01*
X623566Y307150D01*
Y302820D01*
X621460Y300714D01*
X616933D01*
X616483Y300264D01*
Y290864D01*
X615360Y289741D01*
X613390D01*
X612133Y290998D01*
Y300264D01*
X611683Y300714D01*
X610533D01*
X610083Y300264D01*
Y278823D01*
X608854Y277594D01*
X606883D01*
X605733Y278744D01*
Y300264D01*
X605283Y300714D01*
X604133D01*
X603683Y300264D01*
Y276986D01*
X602546Y275849D01*
X600418D01*
X599333Y276934D01*
Y300264D01*
X598883Y300714D01*
X597733D01*
X597283Y300264D01*
Y276945D01*
X596187Y275849D01*
X594083D01*
X592933Y276999D01*
Y300264D01*
X592483Y300714D01*
X591333D01*
X590883Y300264D01*
Y277042D01*
X589690Y275849D01*
X587619D01*
X586533Y276935D01*
Y300264D01*
X586083Y300714D01*
X584933D01*
X584483Y300264D01*
Y277113D01*
X583239Y275869D01*
X581229D01*
X580133Y276965D01*
Y300264D01*
X579683Y300714D01*
X578533D01*
X578083Y300264D01*
Y277118D01*
X577000Y276035D01*
X574844D01*
X573733Y277146D01*
Y300264D01*
X573283Y300714D01*
X567467D01*
X566994Y300241D01*
Y298891D01*
X567644Y298241D01*
Y296891D01*
X566994Y296241D01*
Y294891D01*
X567644Y294241D01*
Y292891D01*
X566994Y292241D01*
Y290891D01*
X567644Y290241D01*
Y288891D01*
X566994Y288241D01*
Y283367D01*
X565549Y281922D01*
X561647D01*
G01X664194Y351206D02*
X662819D01*
X662369Y351656D01*
Y353717D01*
X661090Y354996D01*
X658097D01*
X656450Y353349D01*
Y350704D01*
X655850Y350104D01*
Y347078D01*
X654822Y346050D01*
X645451D01*
X641220Y341819D01*
Y299147D01*
X639623Y297550D01*
X627216D01*
X626766Y298000D01*
Y307707D01*
X625643Y308830D01*
X623619D01*
X622416Y307627D01*
Y303297D01*
X620983Y301864D01*
X616456D01*
X615333Y300741D01*
Y291341D01*
X614883Y290891D01*
X613867D01*
X613283Y291475D01*
Y300741D01*
X612160Y301864D01*
X610056D01*
X608933Y300741D01*
Y279300D01*
X608377Y278744D01*
X607360D01*
X606883Y279221D01*
Y300741D01*
X605760Y301864D01*
X603656D01*
X602533Y300741D01*
Y277463D01*
X602069Y276999D01*
X600895D01*
X600483Y277411D01*
Y300741D01*
X599360Y301864D01*
X597256D01*
X596133Y300741D01*
Y277422D01*
X595710Y276999D01*
X594560D01*
X594083Y277476D01*
Y300741D01*
X592960Y301864D01*
X590856D01*
X589733Y300741D01*
Y277519D01*
X589213Y276999D01*
X588096D01*
X587683Y277412D01*
Y300741D01*
X586560Y301864D01*
X584456D01*
X583333Y300741D01*
Y277590D01*
X582762Y277019D01*
X581706D01*
X581283Y277442D01*
Y300741D01*
X580160Y301864D01*
X578056D01*
X576933Y300741D01*
Y277595D01*
X576523Y277185D01*
X575321D01*
X574883Y277623D01*
Y300741D01*
X573760Y301864D01*
X566990D01*
X565844Y300718D01*
Y283844D01*
X565072Y283072D01*
X561647D01*
G01X637143Y322000D02*
Y323475D01*
X636693Y323925D01*
X630551D01*
X619459Y335017D01*
Y348138D01*
X618508Y349089D01*
X583949D01*
X582720Y350318D01*
Y352182D01*
X583977Y353439D01*
X618368D01*
X618898Y353969D01*
Y355026D01*
X618435Y355489D01*
X588176D01*
X587026Y356639D01*
Y358716D01*
X588149Y359839D01*
X618417D01*
X618947Y360369D01*
Y361439D01*
X618497Y361889D01*
X589188D01*
X588065Y363012D01*
Y365009D01*
X589295Y366239D01*
X618134D01*
X618584Y366689D01*
Y367776D01*
X618071Y368289D01*
X589816D01*
X588693Y369412D01*
Y371516D01*
X589816Y372639D01*
X618497D01*
X618947Y373089D01*
Y374105D01*
X618363Y374689D01*
X588592D01*
X585852Y371949D01*
Y360893D01*
X580740Y355781D01*
Y348511D01*
X566800Y334571D01*
X564554D01*
G01X637143Y327000D02*
Y325525D01*
X636693Y325075D01*
X631028D01*
X620609Y335494D01*
Y348615D01*
X618985Y350239D01*
X584426D01*
X583870Y350795D01*
Y351705D01*
X584454Y352289D01*
X618845D01*
X620048Y353492D01*
Y355503D01*
X618912Y356639D01*
X588653D01*
X588176Y357116D01*
Y358239D01*
X588626Y358689D01*
X618894D01*
X620097Y359892D01*
Y361916D01*
X618974Y363039D01*
X589665D01*
X589215Y363489D01*
Y364532D01*
X589772Y365089D01*
X618611D01*
X619734Y366212D01*
Y368253D01*
X618548Y369439D01*
X590293D01*
X589843Y369889D01*
Y371039D01*
X590293Y371489D01*
X618974D01*
X620097Y372612D01*
Y374582D01*
X618840Y375839D01*
X588115D01*
X584702Y372426D01*
Y361370D01*
X579590Y356258D01*
Y348988D01*
X566323Y335721D01*
X564554D01*
G01X637600Y302000D02*
Y303475D01*
X637150Y303925D01*
X633449D01*
X632326Y305048D01*
Y311090D01*
X631876Y311540D01*
X626323D01*
X625673Y310890D01*
X624323D01*
X623673Y311540D01*
X622323D01*
X620755Y309972D01*
Y309053D01*
X619800Y308098D01*
X618881D01*
X617926Y307143D01*
Y306224D01*
X616972Y305270D01*
X616053D01*
X615098Y304315D01*
X566631D01*
X565455Y305491D01*
Y307542D01*
X566578Y308665D01*
X612600D01*
X613090Y309155D01*
Y310173D01*
X612548Y310715D01*
X571472D01*
X570349Y311838D01*
Y313942D01*
X571472Y315065D01*
X619314D01*
X619764Y315515D01*
Y316572D01*
X619221Y317115D01*
X571472D01*
X570349Y318238D01*
Y320342D01*
X571472Y321465D01*
X612538D01*
X613067Y321994D01*
Y323065D01*
X612617Y323515D01*
X569199D01*
X568698Y323014D01*
Y314891D01*
X563306Y309499D01*
Y302279D01*
G01X637600Y307000D02*
Y305525D01*
X637150Y305075D01*
X633926D01*
X633476Y305525D01*
Y311567D01*
X632353Y312690D01*
X621846D01*
X614621Y305465D01*
X567108D01*
X566605Y305968D01*
Y307065D01*
X567055Y307515D01*
X613077D01*
X614240Y308678D01*
Y310650D01*
X613025Y311865D01*
X571949D01*
X571499Y312315D01*
Y313465D01*
X571949Y313915D01*
X619791D01*
X620914Y315038D01*
Y317049D01*
X619698Y318265D01*
X571949D01*
X571499Y318715D01*
Y319865D01*
X571949Y320315D01*
X613015D01*
X614217Y321517D01*
Y323542D01*
X613094Y324665D01*
X568722D01*
X567548Y323491D01*
Y315368D01*
X562156Y309976D01*
Y302279D01*
G01X565348Y346271D02*
X570971D01*
X575100Y350400D01*
Y398733D01*
X575594Y399227D01*
X576687D01*
X577150Y398764D01*
Y364770D01*
X578273Y363647D01*
X580377D01*
X581500Y364770D01*
Y398315D01*
X581950Y398765D01*
X583043D01*
X583550Y398258D01*
Y381624D01*
X584673Y380501D01*
X586777D01*
X587900Y381624D01*
Y395965D01*
X590746Y398811D01*
X609602D01*
X610753Y399962D01*
Y402038D01*
X609630Y403161D01*
X580365D01*
X579915Y403611D01*
Y404761D01*
X580365Y405211D01*
X612296D01*
X627884Y389623D01*
Y388945D01*
X627110Y388171D01*
X626433D01*
X616802Y397802D01*
X615100D01*
X613669Y396371D01*
Y394781D01*
X624150Y384300D01*
Y336523D01*
X625273Y335400D01*
X627377D01*
X628500Y336523D01*
Y382758D01*
X628950Y383208D01*
X630646D01*
X631250Y382604D01*
Y335773D01*
X632773Y334250D01*
X637201D01*
X637681Y333770D01*
Y332390D01*
G01X613602Y118047D02*
Y114600D01*
X614102Y114100D01*
X616127D01*
X619777Y110450D01*
X629309D01*
X629759Y110900D01*
Y113341D01*
X630882Y114464D01*
X634386D01*
X635509Y113341D01*
Y100500D01*
X635959Y100050D01*
X638509D01*
X638959Y100500D01*
Y113127D01*
X640082Y114250D01*
X643586D01*
X644709Y113127D01*
Y100600D01*
X645159Y100150D01*
X647709D01*
X648159Y100600D01*
Y112228D01*
X649282Y113351D01*
X663351D01*
X665400Y115400D01*
Y118600D01*
X664750Y119250D01*
Y120600D01*
X665400Y121250D01*
Y122600D01*
X664750Y123250D01*
Y124600D01*
X665400Y125250D01*
Y126600D01*
X664750Y127250D01*
Y128600D01*
X665400Y129250D01*
Y130600D01*
X664750Y131250D01*
Y132600D01*
X665400Y133250D01*
Y134600D01*
X672749Y141949D01*
Y146300D01*
X671687Y147362D01*
X671050D01*
X670600Y146912D01*
Y144900D01*
G01X613602Y109247D02*
Y112450D01*
X614102Y112950D01*
X615650D01*
X619300Y109300D01*
X629786D01*
X630909Y110423D01*
Y112864D01*
X631359Y113314D01*
X633909D01*
X634359Y112864D01*
Y100023D01*
X635482Y98900D01*
X638986D01*
X640109Y100023D01*
Y112650D01*
X640559Y113100D01*
X643109D01*
X643559Y112650D01*
Y100123D01*
X644682Y99000D01*
X648186D01*
X649309Y100123D01*
Y111751D01*
X649759Y112201D01*
X663828D01*
X666550Y114923D01*
Y134123D01*
X673899Y141472D01*
Y146777D01*
X672164Y148512D01*
X670838D01*
X670519Y148831D01*
Y149919D01*
X670600Y150000D01*
G01X670800Y298400D02*
X669699Y297299D01*
Y296628D01*
X670464Y295863D01*
X673837D01*
X674900Y294800D01*
X685124D01*
X688406Y298082D01*
X694578Y312973D01*
X700579Y318975D01*
X709519Y340553D01*
Y353719D01*
X716217Y383934D01*
Y411107D01*
X716988Y411878D01*
Y422473D01*
X717318Y423834D01*
X716840Y424618D01*
X717170Y425979D01*
X717955Y426457D01*
X718285Y427818D01*
X717807Y428603D01*
X718137Y429963D01*
X718922Y430442D01*
X719252Y431802D01*
X718774Y432587D01*
X719104Y433948D01*
X719889Y434426D01*
X733191Y489239D01*
Y501178D01*
X735186Y511077D01*
Y518054D01*
X740196Y523064D01*
X746754D01*
X749372Y520446D01*
X752225D01*
X752900Y521121D01*
G01X668000Y298400D02*
X668549Y297851D01*
Y296151D01*
X669987Y294713D01*
X673360D01*
X674423Y293650D01*
X685601D01*
X689381Y297430D01*
X695554Y312321D01*
X701555Y318323D01*
X710669Y340324D01*
Y353593D01*
X717367Y383808D01*
Y410630D01*
X718138Y411401D01*
Y422335D01*
X734341Y489101D01*
Y501063D01*
X736336Y510962D01*
Y517577D01*
X740673Y521914D01*
X746277D01*
X748895Y519296D01*
X752225D01*
X752900Y518621D01*
G01X1109142Y-43700D02*
X914500D01*
G03Y-46250I0J-1275D01*
G01X1109042D01*
G02Y-51100I0J-2425D01*
G01X909373D01*
X905905Y-47632D01*
X843409D01*
X838984Y-52057D01*
G01X1109142Y-42550D02*
X914500D01*
G03Y-47400I0J-2425D01*
G01X1109042D01*
G02Y-49950I0J-1275D01*
G01X909850D01*
X906382Y-46482D01*
X843409D01*
X838984Y-42057D01*
G01X1250200Y122900D02*
Y116250D01*
X1250770Y115680D01*
X1251853D01*
X1253150Y116977D01*
Y120576D01*
X1256750Y124176D01*
Y125376D01*
X1256150Y125976D01*
Y127176D01*
X1256750Y127776D01*
Y129451D01*
X1250101Y136100D01*
X1240204D01*
X1177210Y199094D01*
X1172525D01*
X1169169Y202450D01*
X1160450D01*
X1158000Y204900D01*
Y206500D01*
G01X1251980Y106960D02*
Y114180D01*
X1254300Y116500D01*
Y120099D01*
X1257900Y123699D01*
Y129928D01*
X1250578Y137250D01*
X1240681D01*
X1177687Y200244D01*
X1173002D01*
X1169646Y203600D01*
X1160927D01*
X1159150Y205377D01*
Y206500D01*
G01X1820382Y176525D02*
X1818907D01*
X1818457Y176975D01*
Y179229D01*
X1824383Y185155D01*
X1828468D01*
X1833850Y190537D01*
Y202400D01*
X1830700Y205550D01*
X1720596D01*
X1719454Y206692D01*
X1686604D01*
X1680347Y212949D01*
X1672531D01*
X1668476Y217004D01*
X1656611D01*
X1654946Y215339D01*
X1651888D01*
X1649477Y217750D01*
X1632618D01*
X1630718Y215850D01*
X1618778D01*
X1614178Y220450D01*
X1610124D01*
X1607383Y217709D01*
X1603539D01*
X1594200Y208370D01*
X1588170D01*
X1585939Y210601D01*
X1544390D01*
X1538421Y204632D01*
X1525857D01*
X1519025Y197800D01*
X1500700D01*
X1498712Y195812D01*
X1478452D01*
X1476991Y197273D01*
X1466962D01*
X1459885Y204350D01*
X1453950D01*
X1446900Y211400D01*
X1434202D01*
X1423655Y214272D01*
X1417465Y218388D01*
X1404763Y237449D01*
X1398913Y241350D01*
X1397276Y241676D01*
X1394548Y241131D01*
X1388870Y242268D01*
X1383801Y241086D01*
X1377752Y242268D01*
X1372763Y241101D01*
X1367142Y242194D01*
X1362237Y241053D01*
X1355842Y242297D01*
X1350827Y241124D01*
X1329630Y245247D01*
X1316795Y242267D01*
X1311589Y243259D01*
X1303942Y248211D01*
X1280170Y282772D01*
X1259619Y332382D01*
X1211932Y380067D01*
X1210059D01*
G01X1208187Y377150D02*
X1211277D01*
X1257395Y331034D01*
X1257397Y331030D01*
X1277765Y281853D01*
X1312945Y230707D01*
X1314365Y230064D01*
X1373136D01*
X1402201Y220310D01*
X1403976D01*
X1413244Y217200D01*
X1421803Y211106D01*
X1443904Y205022D01*
X1448900Y200028D01*
X1460614D01*
X1465869Y194773D01*
X1475582D01*
X1477043Y193312D01*
X1501015D01*
X1504013Y190314D01*
X1516236D01*
X1517500Y189050D01*
X1520423D01*
X1522350Y190977D01*
Y194650D01*
X1526663Y198963D01*
X1536936D01*
X1546074Y208101D01*
X1577306D01*
X1579560Y205847D01*
X1595547D01*
X1601250Y211550D01*
X1630167D01*
X1633554Y214937D01*
X1640663D01*
X1644098Y211502D01*
X1657616D01*
X1658699Y210419D01*
X1667127D01*
X1670805Y206741D01*
X1672900D01*
X1676450Y210291D01*
X1678616D01*
X1684857Y204050D01*
X1718511D01*
X1718745Y203816D01*
X1718793D01*
X1729658Y192951D01*
X1797099D01*
X1805859Y184191D01*
Y176976D01*
X1806310Y176525D01*
X1807784D01*
G01X1208959Y368024D02*
X1214335Y365799D01*
X1217551Y363649D01*
X1252992Y328208D01*
X1272947Y280027D01*
X1310168Y225917D01*
X1311646Y224939D01*
X1372351D01*
X1381007Y222034D01*
X1393669Y213077D01*
X1394763Y212859D01*
X1403414Y214819D01*
X1410981Y212279D01*
X1422097Y204369D01*
X1435209Y200460D01*
X1444692Y190976D01*
X1452472D01*
X1458592Y184856D01*
X1471160D01*
X1474420Y188116D01*
X1496663D01*
X1496664Y188117D01*
X1497616D01*
X1503783Y181950D01*
X1518988D01*
X1519989Y182951D01*
X1521551D01*
X1532563Y193963D01*
X1539010D01*
X1539447Y194400D01*
X1553605D01*
X1555372Y196167D01*
X1573833D01*
X1578491Y200825D01*
X1597776D01*
X1603297Y206346D01*
X1650293D01*
X1653953Y202686D01*
X1658074D01*
X1660126Y204738D01*
X1665734D01*
X1671400Y199072D01*
Y195727D01*
X1673268Y193859D01*
X1682707D01*
X1683625Y194777D01*
Y196926D01*
X1685216Y198517D01*
X1686246D01*
X1686247Y198518D01*
X1687199D01*
X1687200Y198517D01*
X1702610D01*
X1710848Y190279D01*
X1711930D01*
X1715726Y186483D01*
X1776517D01*
X1780662Y182338D01*
Y176976D01*
X1781113Y176525D01*
X1782587D01*
G01X1815382D02*
X1816857D01*
X1817307Y176975D01*
Y179706D01*
X1823906Y186305D01*
X1827991D01*
X1832700Y191014D01*
Y201923D01*
X1830223Y204400D01*
X1828873D01*
X1828223Y203750D01*
X1826873D01*
X1826223Y204400D01*
X1824873D01*
X1824223Y203750D01*
X1822873D01*
X1822223Y204400D01*
X1820873D01*
X1820223Y203750D01*
X1818873D01*
X1818223Y204400D01*
X1816873D01*
X1816223Y203750D01*
X1814873D01*
X1814223Y204400D01*
X1720119D01*
X1718977Y205542D01*
X1686127D01*
X1679870Y211799D01*
X1672054D01*
X1667999Y215854D01*
X1658874D01*
X1658871Y215851D01*
X1658869D01*
X1658866Y215854D01*
X1657088D01*
X1655423Y214189D01*
X1651411D01*
X1649000Y216600D01*
X1633095D01*
X1631195Y214700D01*
X1618301D01*
X1613701Y219300D01*
X1610601D01*
X1607860Y216559D01*
X1604016D01*
X1594677Y207220D01*
X1587693D01*
X1585462Y209451D01*
X1544867D01*
X1538898Y203482D01*
X1526334D01*
X1519502Y196650D01*
X1501177D01*
X1499189Y194662D01*
X1477975D01*
X1476514Y196123D01*
X1466485D01*
X1459408Y203200D01*
X1453473D01*
X1446423Y210250D01*
X1433940D01*
X1433900Y210290D01*
X1423173Y213211D01*
X1416636Y217558D01*
X1403933Y236619D01*
X1398464Y240266D01*
X1397276Y240503D01*
X1394548Y239958D01*
X1388888Y241091D01*
X1383823Y239910D01*
X1377774Y241091D01*
X1372785Y239925D01*
X1367163Y241018D01*
X1362258Y239877D01*
X1355864Y241121D01*
X1350849Y239948D01*
X1329651Y244071D01*
X1316818Y241091D01*
X1311153Y242171D01*
X1303124Y247370D01*
X1279153Y282220D01*
X1258643Y331730D01*
X1221789Y368582D01*
Y368583D01*
X1211455Y378917D01*
X1210059D01*
G01X1208187Y376000D02*
X1210800D01*
X1256419Y330382D01*
X1276748Y281301D01*
X1312179Y229791D01*
X1314116Y228914D01*
X1372948D01*
X1402013Y219160D01*
X1403788D01*
X1412716Y216164D01*
X1421301Y210050D01*
X1443306Y203993D01*
X1448423Y198878D01*
X1460137D01*
X1465392Y193623D01*
X1475105D01*
X1476566Y192162D01*
X1500538D01*
X1503199Y189500D01*
Y189501D01*
X1503536Y189164D01*
X1515759D01*
X1517023Y187900D01*
X1520900D01*
X1523500Y190500D01*
Y194173D01*
X1527140Y197813D01*
X1537413D01*
X1546551Y206951D01*
X1576829D01*
X1579083Y204697D01*
X1596024D01*
X1601727Y210400D01*
X1630644D01*
X1634031Y213787D01*
X1640186D01*
X1643621Y210352D01*
X1657139D01*
X1658222Y209269D01*
X1666650D01*
X1670328Y205591D01*
X1673377D01*
X1676927Y209141D01*
X1678139D01*
X1684380Y202900D01*
X1718034D01*
X1718268Y202666D01*
X1718316D01*
X1729181Y191801D01*
X1730531D01*
X1731181Y191151D01*
X1732531D01*
X1733181Y191801D01*
X1734531D01*
X1735181Y191151D01*
X1736531D01*
X1737181Y191801D01*
X1738531D01*
X1739181Y191151D01*
X1740531D01*
X1741181Y191801D01*
X1742531D01*
X1743181Y191151D01*
X1744531D01*
X1745181Y191801D01*
X1796622D01*
X1804709Y183714D01*
Y176975D01*
X1804259Y176525D01*
X1802784D01*
G01X1208520Y366961D02*
X1213790Y364779D01*
X1216817Y362755D01*
X1252016Y327556D01*
X1271929Y279475D01*
X1271930D01*
X1309347Y225081D01*
X1311300Y223789D01*
X1372163D01*
X1380480Y220997D01*
X1393204Y211997D01*
X1394778Y211683D01*
X1403354Y213626D01*
X1410453Y211243D01*
X1421586Y203321D01*
X1434601Y199440D01*
X1444215Y189826D01*
X1451995D01*
X1458115Y183706D01*
X1471637D01*
X1474897Y186966D01*
X1497140D01*
X1503306Y180800D01*
X1519465D01*
X1520466Y181801D01*
X1522028D01*
X1533040Y192813D01*
X1539487D01*
X1539924Y193250D01*
X1554082D01*
X1555849Y195017D01*
X1574310D01*
X1578968Y199675D01*
X1598253D01*
X1603774Y205196D01*
X1649816D01*
X1653476Y201536D01*
X1658551D01*
X1660603Y203588D01*
X1665257D01*
X1670250Y198595D01*
Y195250D01*
X1672791Y192709D01*
X1683184D01*
X1684775Y194300D01*
Y196449D01*
X1685693Y197367D01*
X1702133D01*
X1710371Y189129D01*
X1711453D01*
X1715249Y185333D01*
X1743161D01*
X1743811Y184683D01*
X1745161D01*
X1745811Y185333D01*
X1747161D01*
X1747811Y184683D01*
X1749161D01*
X1749811Y185333D01*
X1751161D01*
X1751811Y184683D01*
X1753161D01*
X1753811Y185333D01*
X1776040D01*
X1779512Y181861D01*
Y176975D01*
X1779062Y176525D01*
X1777587D01*
G01X1427442Y11563D02*
X1425967D01*
X1425517Y12013D01*
Y21489D01*
X1431488Y48592D01*
X1419720Y103595D01*
X1402791Y128989D01*
X1396326Y133299D01*
X1365436Y138950D01*
X1358527Y137485D01*
X1344020D01*
X1338110Y143395D01*
Y151156D01*
X1336072Y153194D01*
X1322608D01*
X1311849Y160323D01*
X1305051Y161682D01*
X1300555Y164679D01*
X1292908Y176148D01*
X1278546Y180697D01*
X1259807Y178899D01*
X1239504Y182785D01*
X1218405Y199812D01*
X1216971Y201996D01*
X1215830Y206106D01*
X1215885Y208412D01*
X1215048Y216972D01*
X1216004Y219448D01*
X1218156Y221394D01*
X1221389Y226197D01*
X1224475Y232910D01*
X1225908Y240068D01*
X1222259Y250819D01*
X1213046Y259920D01*
X1211642Y264443D01*
X1212129Y268419D01*
X1215909Y273975D01*
X1216681Y277840D01*
X1211987Y289174D01*
X1208433Y292821D01*
X1206867D01*
G01X1431025Y7756D02*
X1432500D01*
X1432950Y8206D01*
Y14950D01*
X1435175Y17175D01*
Y18525D01*
X1434525Y19175D01*
Y20525D01*
X1435175Y21175D01*
Y22525D01*
X1434525Y23175D01*
Y24525D01*
X1435175Y25175D01*
Y26525D01*
X1434525Y27175D01*
Y28525D01*
X1435175Y29175D01*
Y30525D01*
X1434525Y31175D01*
Y32525D01*
X1435175Y33175D01*
Y41181D01*
X1422015Y102673D01*
X1403795Y130004D01*
X1396874Y134618D01*
X1365222Y140465D01*
X1358005Y138942D01*
X1345278D01*
X1341952Y142268D01*
Y155770D01*
X1340628Y157094D01*
X1320101D01*
X1312050Y162429D01*
Y166295D01*
X1311416Y169460D01*
X1310563Y170739D01*
X1306370Y173534D01*
X1278821Y182257D01*
X1260035Y180320D01*
X1239932Y184182D01*
X1219464Y200704D01*
X1218254Y202533D01*
X1217534Y205062D01*
X1217481Y207691D01*
Y207782D01*
X1217695Y209759D01*
X1222299Y214664D01*
X1228213Y235457D01*
X1227371Y244441D01*
X1223803Y252883D01*
X1221636Y254234D01*
X1218726Y260327D01*
X1220610Y271208D01*
X1212428Y290959D01*
X1208565Y295571D01*
X1207738D01*
G01X1206867Y291671D02*
X1207947D01*
X1211008Y288529D01*
X1215484Y277723D01*
X1214826Y274429D01*
X1211021Y268836D01*
X1210470Y264338D01*
X1212033Y259304D01*
X1221257Y250192D01*
X1224719Y239991D01*
X1223373Y233268D01*
X1220383Y226762D01*
X1217280Y222153D01*
X1215030Y220118D01*
X1213876Y217132D01*
X1214733Y208370D01*
X1214676Y205963D01*
X1214721Y205798D01*
X1214722D01*
X1215910Y201515D01*
X1217542Y199030D01*
X1239005Y181709D01*
X1259753Y177738D01*
X1278422Y179529D01*
X1292175Y175173D01*
X1299725Y163849D01*
X1304602Y160598D01*
X1311402Y159239D01*
X1322261Y152044D01*
X1335595D01*
X1336960Y150679D01*
Y142918D01*
X1343543Y136335D01*
X1358649D01*
X1365452Y137777D01*
X1395886Y132210D01*
X1401961Y128159D01*
X1418641Y103140D01*
X1430311Y48596D01*
X1427815Y37270D01*
X1427809Y37240D01*
X1427035Y36745D01*
X1426744Y35427D01*
X1427239Y34652D01*
X1426949Y33334D01*
X1426174Y32839D01*
X1425884Y31521D01*
X1426379Y30746D01*
X1426094Y29458D01*
X1426088Y29428D01*
X1425314Y28933D01*
X1425023Y27614D01*
X1425518Y26840D01*
X1425228Y25521D01*
X1424453Y25026D01*
X1424163Y23708D01*
X1424657Y22933D01*
X1424367Y21615D01*
Y12013D01*
X1423917Y11563D01*
X1422442D01*
G01X1192186Y196687D02*
X1204350Y184523D01*
Y180823D01*
X1229366Y155807D01*
Y154888D01*
X1230321Y153933D01*
X1231240D01*
X1232195Y152978D01*
Y152059D01*
X1233149Y151105D01*
X1234068D01*
X1235023Y150150D01*
X1243150D01*
X1251300Y142000D01*
X1253072D01*
X1256444Y138628D01*
Y137709D01*
X1257398Y136755D01*
X1258317D01*
X1259272Y135800D01*
X1265173D01*
X1267450Y133523D01*
Y129712D01*
X1265346Y127608D01*
X1264497D01*
X1263648Y126759D01*
Y125910D01*
X1262800Y125062D01*
Y121800D01*
X1262200Y121200D01*
Y120000D01*
X1262800Y119400D01*
Y117000D01*
X1261662Y115862D01*
X1258838D01*
X1257850Y116850D01*
Y116950D01*
G01X1193000Y197500D02*
X1195310Y195191D01*
X1196600Y193901D01*
Y193900D01*
X1205500Y185000D01*
Y181300D01*
X1235500Y151300D01*
X1243627D01*
X1251777Y143150D01*
X1253549D01*
X1259749Y136950D01*
X1265650D01*
X1268600Y134000D01*
Y129235D01*
X1263950Y124585D01*
Y116523D01*
X1262139Y114712D01*
X1258712D01*
X1257850Y113850D01*
G01X1436025Y7756D02*
X1434550D01*
X1434100Y8206D01*
Y14473D01*
X1436325Y16698D01*
Y41303D01*
X1423094Y103128D01*
X1404625Y130834D01*
X1397316Y135707D01*
X1365207Y141638D01*
X1357885Y140092D01*
X1345755D01*
X1343102Y142745D01*
Y156247D01*
X1341105Y158244D01*
X1320448D01*
X1313200Y163047D01*
Y166410D01*
X1312499Y169909D01*
X1311393Y171569D01*
X1306873Y174582D01*
X1278941Y183426D01*
X1260086Y181482D01*
X1240431Y185258D01*
X1220325Y201487D01*
X1219312Y203019D01*
X1218681Y205234D01*
X1218631Y207704D01*
Y207719D01*
X1218798Y209252D01*
X1223330Y214080D01*
X1229379Y235350D01*
X1228500Y244725D01*
X1224721Y253667D01*
X1222530Y255033D01*
X1219922Y260492D01*
X1221801Y271340D01*
X1213424Y291563D01*
X1209102Y296721D01*
X1207738D01*
G01X1474388Y5589D02*
X1472886D01*
X1472463Y6012D01*
Y18880D01*
X1459152Y32191D01*
X1455088Y42622D01*
X1445697Y49913D01*
X1433799Y105524D01*
X1411892Y138386D01*
X1399393Y146728D01*
X1394845Y152444D01*
X1393200Y160670D01*
X1393201D01*
X1393156Y160895D01*
X1392744Y161511D01*
Y161512D01*
X1392607Y161716D01*
X1390811Y162850D01*
X1364431D01*
X1363296Y163985D01*
Y170710D01*
X1362449Y174874D01*
X1360104Y178416D01*
X1353069Y180302D01*
X1344201Y178498D01*
X1335668Y180234D01*
X1327659Y178602D01*
X1296192Y188555D01*
X1279571Y199313D01*
X1274456Y206757D01*
X1270929Y208195D01*
X1244945Y245972D01*
X1223296Y298234D01*
X1216708Y306263D01*
X1211737Y310770D01*
X1210146Y311832D01*
X1208963D01*
G01X1465237Y11563D02*
X1463762D01*
X1463312Y12013D01*
Y14412D01*
X1460297Y22056D01*
X1460277Y22116D01*
X1452767Y41144D01*
X1452766D01*
X1443350Y48297D01*
X1431269Y104769D01*
X1410201Y136374D01*
X1396500Y145506D01*
X1386971Y157476D01*
X1385634Y158075D01*
X1359326D01*
X1358284Y159117D01*
Y170916D01*
X1357577Y174390D01*
X1356190Y176485D01*
X1352695Y177421D01*
X1344447Y175744D01*
X1335476Y177568D01*
X1327616Y175966D01*
X1279630Y191152D01*
X1260205Y189163D01*
X1251745Y190783D01*
X1240267Y200049D01*
X1236621Y208180D01*
X1237362Y212332D01*
X1236599Y216163D01*
X1237434Y219473D01*
X1236798Y221991D01*
X1239236Y237813D01*
X1237377Y257643D01*
X1221439Y296122D01*
X1213775Y305460D01*
X1209343Y308422D01*
X1206987D01*
G01X1454991Y5589D02*
X1453465D01*
X1453066Y5988D01*
Y19125D01*
X1448187Y37023D01*
X1441997Y41807D01*
X1428681Y104051D01*
X1408309Y134611D01*
X1393516Y144473D01*
X1387072Y152609D01*
X1385945Y153075D01*
X1354129D01*
X1353387Y153817D01*
Y166440D01*
X1351677Y168150D01*
X1343777D01*
X1343150Y168777D01*
Y172566D01*
X1342309Y173407D01*
Y173473D01*
X1335477Y174863D01*
X1327713Y173281D01*
X1279355Y188587D01*
X1260121Y186614D01*
X1250074Y188536D01*
X1238468Y197901D01*
X1234011Y207844D01*
X1234806Y212305D01*
X1234016Y216286D01*
X1234821Y219493D01*
X1234206Y221939D01*
X1236608Y238411D01*
X1236609Y238415D01*
X1236654Y238552D01*
X1235013Y256059D01*
X1218912Y294937D01*
X1211918Y302484D01*
X1208525Y304200D01*
X1207171D01*
G01X1441340Y11563D02*
X1442815D01*
X1443265Y12013D01*
Y16384D01*
X1441822Y18549D01*
X1441557Y19873D01*
X1440792Y20383D01*
X1440528Y21706D01*
X1441037Y22471D01*
X1440773Y23795D01*
X1440008Y24305D01*
X1439743Y25629D01*
X1440253Y26394D01*
X1439988Y27717D01*
X1439223Y28227D01*
X1438958Y29551D01*
X1439468Y30316D01*
X1438593Y34692D01*
X1439057Y37014D01*
X1425104Y102693D01*
X1415381Y117277D01*
X1405658Y131860D01*
X1392704Y140497D01*
X1391803Y140317D01*
X1390679Y141066D01*
X1390499Y141967D01*
X1389376Y142716D01*
X1386637Y146241D01*
X1384983Y146925D01*
X1348059D01*
X1346936Y148048D01*
Y161250D01*
X1346486Y161700D01*
X1323574D01*
X1321896Y163378D01*
Y170581D01*
X1320894Y171583D01*
X1278935Y184867D01*
X1259931Y182917D01*
X1247635Y185265D01*
X1235776Y194839D01*
X1230193Y207292D01*
X1231082Y212270D01*
X1230257Y216416D01*
X1230992Y219350D01*
X1230337Y221944D01*
X1232725Y239490D01*
X1231207Y255704D01*
X1230938Y256353D01*
X1230937Y256356D01*
X1216588Y290993D01*
X1209710Y298793D01*
X1208384Y299550D01*
X1208025D01*
G01X1212087Y340950D02*
X1216421D01*
X1219950Y338524D01*
X1222827Y334291D01*
X1234382Y323818D01*
X1240549Y316303D01*
X1261300Y266221D01*
X1295902Y215918D01*
X1305478Y209619D01*
Y209620D01*
X1328837Y202268D01*
X1337912Y204115D01*
X1346770Y202313D01*
X1354333Y203852D01*
X1413461Y187999D01*
X1422137Y182258D01*
X1428717Y172315D01*
X1433095Y150442D01*
X1443497Y134806D01*
X1453515Y128127D01*
X1454667Y126418D01*
X1454670Y126414D01*
X1454695Y126376D01*
X1462332Y121089D01*
X1465950Y104001D01*
X1471366Y101040D01*
X1479846Y64677D01*
X1490647Y51555D01*
X1500869Y46070D01*
X1514746Y43124D01*
X1536478Y47664D01*
X1562567Y42571D01*
X1565192Y40822D01*
X1566830Y39730D01*
X1569630Y35530D01*
X1579745Y28787D01*
X1585484Y20531D01*
X1602949Y14558D01*
X1603873Y13265D01*
Y11886D01*
X1604404Y11355D01*
X1605898D01*
G01X1217384Y336944D02*
X1218723Y335928D01*
X1220603Y333043D01*
X1225988Y327658D01*
X1233440Y320906D01*
X1238342Y314921D01*
X1258906Y265287D01*
X1294337Y213777D01*
X1304434Y207236D01*
X1328708Y199590D01*
X1337783Y201439D01*
X1346453Y199674D01*
X1354223Y201254D01*
X1354484Y201185D01*
Y201184D01*
X1412133Y185730D01*
X1420395Y180262D01*
X1426062Y171699D01*
X1430520Y149796D01*
X1441751Y132915D01*
X1451414Y126481D01*
X1452891Y124212D01*
X1460030Y119273D01*
X1463805Y102066D01*
X1469074Y99201D01*
X1477407Y63467D01*
X1488929Y49470D01*
X1499937Y43563D01*
X1516971Y39944D01*
X1539387Y44426D01*
X1554526Y41398D01*
X1556730Y39930D01*
X1558449Y37351D01*
X1564250Y33482D01*
X1567178Y32897D01*
X1572873Y29101D01*
X1586749Y15221D01*
X1592813D01*
X1594373Y13661D01*
Y11856D01*
X1594823Y11406D01*
X1595848D01*
G01X1215321Y334900D02*
X1215903Y334477D01*
X1218514Y331866D01*
X1219300Y330642D01*
X1219417Y330460D01*
X1222970Y326907D01*
X1231210Y319441D01*
X1236316Y313208D01*
X1260983Y253660D01*
X1282484Y222399D01*
X1286354Y220820D01*
X1292392Y212039D01*
X1303377Y204924D01*
X1328596Y196975D01*
X1337508Y198789D01*
X1346233Y197014D01*
X1354235Y198643D01*
X1410712Y183507D01*
X1418500Y178350D01*
X1423726Y170454D01*
X1428788Y145492D01*
X1444900Y121282D01*
X1455272Y119175D01*
X1457727Y117489D01*
X1461541Y100348D01*
X1466738Y97547D01*
X1474962Y62269D01*
Y62270D01*
X1487216Y47383D01*
X1499021Y41048D01*
X1518710Y36862D01*
X1533563Y40019D01*
X1570883Y27260D01*
X1578979Y19164D01*
X1578980D01*
X1585073Y13071D01*
Y11805D01*
X1585523Y11355D01*
X1586998D01*
G01X1207232Y330662D02*
X1213912D01*
X1217994Y327935D01*
X1228950Y318005D01*
X1234304Y311479D01*
X1258740Y252490D01*
X1280830Y220373D01*
X1284655Y218812D01*
X1290579Y210200D01*
X1302272Y202626D01*
X1328541Y194348D01*
X1337291Y196129D01*
X1345931Y194372D01*
X1354115Y196037D01*
X1409300Y181245D01*
X1409749Y181125D01*
X1416479Y176671D01*
X1421310Y169374D01*
X1426356Y144553D01*
X1443390Y118990D01*
X1453899Y116890D01*
X1455310Y115948D01*
X1459219Y98649D01*
X1464402Y95897D01*
X1472522Y61061D01*
X1485502Y45296D01*
X1498129Y38520D01*
X1519781Y33920D01*
X1534511Y37045D01*
X1566747Y26026D01*
X1575523Y17250D01*
Y13176D01*
X1576193Y12506D01*
X1577048D01*
G01X1210188Y328000D02*
X1213015D01*
X1214727Y326855D01*
X1228176Y314667D01*
X1232398Y309522D01*
X1256535Y251266D01*
X1279179Y218345D01*
X1282963Y216801D01*
X1288762Y208367D01*
X1301561Y200078D01*
X1328225Y191667D01*
X1337071Y193470D01*
X1345658Y191723D01*
X1354111Y193444D01*
X1408227Y178940D01*
X1414864Y174548D01*
X1418955Y168365D01*
X1424015Y143415D01*
Y143413D01*
X1447962Y107546D01*
X1449279Y101144D01*
X1462090Y94130D01*
X1466868Y73635D01*
X1470080Y59858D01*
X1483817Y43170D01*
X1491181Y39234D01*
X1500141Y26691D01*
X1506642Y25371D01*
X1513634Y29728D01*
X1534835Y34229D01*
X1556467Y26833D01*
X1566129Y17171D01*
Y13306D01*
X1566929Y12506D01*
X1567498D01*
G01X1554148Y12306D02*
X1555064D01*
X1555666Y12908D01*
Y15846D01*
X1552763Y18749D01*
X1548189Y19721D01*
X1543367Y18697D01*
X1540537Y19298D01*
X1529145Y16878D01*
X1519631Y18899D01*
X1504605Y15705D01*
X1499201Y18071D01*
X1495801Y22201D01*
X1494886Y22290D01*
X1494028Y23332D01*
X1494116Y24247D01*
X1493258Y25290D01*
X1492344Y25378D01*
X1491485Y26421D01*
X1491574Y27336D01*
X1490716Y28378D01*
X1489801Y28467D01*
X1488943Y29509D01*
X1489032Y30424D01*
X1466494Y57802D01*
X1460300Y84372D01*
X1460237Y84642D01*
X1455216Y87989D01*
Y87990D01*
X1450195Y91336D01*
X1446059Y97535D01*
X1444285Y106408D01*
X1420456Y142151D01*
X1415432Y166935D01*
X1412184Y171845D01*
X1406554Y175570D01*
X1353977Y189664D01*
X1345348Y187908D01*
X1336746Y189658D01*
X1327941Y187866D01*
X1300086Y196666D01*
X1286107Y205719D01*
X1280509Y213859D01*
X1276777Y215381D01*
Y215382D01*
X1276775Y215383D01*
X1253169Y249700D01*
X1253165Y249709D01*
X1229547Y306729D01*
X1225932Y311136D01*
X1211678Y324054D01*
X1210883D01*
G01X1548698Y12506D02*
X1547934D01*
X1547200Y13240D01*
Y15297D01*
X1545864Y16632D01*
X1540537Y17765D01*
X1529143Y15345D01*
X1519281Y17440D01*
X1504217Y14242D01*
X1486748Y21895D01*
X1473397Y40537D01*
X1452753Y56584D01*
X1442050Y107250D01*
X1419130Y141629D01*
X1414142Y166145D01*
X1414143D01*
X1414098Y166365D01*
X1411241Y170680D01*
X1405695Y174352D01*
X1353852Y188246D01*
X1345004Y186447D01*
X1336420Y188194D01*
X1327896Y186458D01*
X1299469Y195442D01*
X1285151Y204703D01*
X1279606Y212768D01*
X1275876Y214290D01*
X1251884Y249170D01*
X1228768Y304968D01*
X1224251Y310476D01*
X1211459Y322070D01*
X1210096D01*
G01X1209321Y317612D02*
X1212333D01*
X1212661Y317315D01*
Y317314D01*
X1221510Y309298D01*
X1227035Y302563D01*
X1249619Y248035D01*
X1274226Y212260D01*
X1277885Y210769D01*
X1283287Y202911D01*
X1298371Y193139D01*
X1327774Y183840D01*
X1336150Y185545D01*
X1344689Y183807D01*
X1353658Y185631D01*
X1404567Y171986D01*
X1409518Y168709D01*
X1411673Y165454D01*
X1416722Y140493D01*
X1439017Y107048D01*
X1450672Y52570D01*
X1465659Y41440D01*
X1468617Y34032D01*
X1470968Y31681D01*
X1472801D01*
X1491845Y12637D01*
Y7359D01*
X1492295Y6909D01*
X1493770D01*
G01X1208852Y314852D02*
X1211111D01*
X1212506Y313919D01*
X1217934Y309000D01*
X1225330Y299985D01*
X1247262Y247031D01*
X1272574Y210232D01*
X1276166Y208769D01*
X1276500Y208283D01*
X1281434Y201106D01*
X1297255Y190858D01*
X1327626Y181250D01*
X1335787Y182915D01*
X1344459Y181150D01*
X1353377Y182963D01*
X1403803Y169447D01*
X1407590Y166939D01*
X1409274Y164399D01*
Y164398D01*
X1414272Y139564D01*
X1436206Y106665D01*
X1448056Y51274D01*
X1462437Y40542D01*
X1466132Y31008D01*
X1482210Y14930D01*
Y12013D01*
X1482660Y11563D01*
X1484135D01*
G01X1213724Y342300D02*
X1216795D01*
X1219300Y340655D01*
X1221520Y339198D01*
X1224012Y335150D01*
X1234912Y325309D01*
X1241922Y316768D01*
X1241921D01*
X1262714Y266571D01*
X1296689Y217172D01*
X1306050Y211010D01*
X1329124Y203752D01*
X1338170Y205594D01*
X1347089Y203779D01*
X1355021Y205393D01*
X1414030Y189293D01*
X1423333Y183138D01*
X1429930Y173170D01*
X1434290Y151373D01*
X1444709Y135710D01*
X1455107Y128776D01*
X1455955Y127501D01*
X1455956D01*
X1456316Y126960D01*
X1463667Y121893D01*
X1467186Y104908D01*
X1472604Y101929D01*
X1481094Y65519D01*
X1491612Y52740D01*
X1501390Y47495D01*
X1512483Y45138D01*
X1513804Y45414D01*
X1514574Y44911D01*
X1515895Y45187D01*
X1516398Y45956D01*
X1517720Y46233D01*
X1518489Y45729D01*
X1519811Y46006D01*
X1520314Y46775D01*
X1521635Y47051D01*
X1522404Y46548D01*
X1523726Y46824D01*
X1524229Y47593D01*
X1534304Y49699D01*
X1569800Y42600D01*
X1576100Y38400D01*
X1576849Y37277D01*
X1576669Y36375D01*
X1577417Y35252D01*
X1578319Y35072D01*
X1587366Y21500D01*
X1610416Y14418D01*
X1611596Y13238D01*
Y6404D01*
X1610618Y5426D01*
Y5425D01*
X1609833D01*
G01X1469388Y5589D02*
X1470863D01*
X1471313Y6039D01*
Y18403D01*
X1470358Y19358D01*
X1469439D01*
X1468485Y20312D01*
X1468484Y21231D01*
X1467530Y22186D01*
X1466611D01*
X1465656Y23140D01*
Y24060D01*
X1464701Y25014D01*
X1463782D01*
X1462827Y25969D01*
Y26888D01*
X1458167Y31548D01*
X1454131Y41908D01*
X1444660Y49262D01*
X1432720Y105069D01*
X1411062Y137556D01*
X1398605Y145871D01*
X1393771Y151945D01*
X1392072Y160445D01*
X1391786Y160874D01*
X1390478Y161700D01*
X1363954D01*
X1362146Y163508D01*
Y170594D01*
X1361366Y174425D01*
X1359385Y177418D01*
X1353033Y179121D01*
X1344201Y177324D01*
X1335668Y179060D01*
X1327596Y177415D01*
X1295697Y187505D01*
X1278753Y198472D01*
X1273703Y205822D01*
X1270176Y207259D01*
X1243928Y245420D01*
X1243927Y245422D01*
X1240864Y252819D01*
X1240010Y253173D01*
X1239493Y254420D01*
X1239845Y255270D01*
X1222298Y297636D01*
X1215875Y305463D01*
X1211027Y309860D01*
X1209797Y310682D01*
X1208963D01*
G01X1460237Y11563D02*
X1461712D01*
X1462162Y12013D01*
Y14193D01*
X1461667Y15449D01*
X1460823Y15815D01*
X1460328Y17071D01*
X1460694Y17914D01*
X1460199Y19170D01*
X1459356Y19536D01*
X1458860Y20792D01*
X1459226Y21635D01*
X1459206Y21695D01*
X1451816Y40418D01*
X1451815Y40421D01*
X1450740Y41238D01*
X1449829Y41113D01*
X1448754Y41930D01*
X1448630Y42841D01*
X1447555Y43658D01*
X1446644Y43533D01*
X1445569Y44350D01*
X1445445Y45261D01*
X1442314Y47639D01*
X1430190Y104314D01*
X1409371Y135544D01*
X1395712Y144649D01*
X1386245Y156540D01*
X1385387Y156925D01*
X1358849D01*
X1357134Y158640D01*
Y170800D01*
X1356494Y173941D01*
X1355471Y175486D01*
X1352659Y176240D01*
X1344447Y174570D01*
X1335476Y176394D01*
X1327553Y174779D01*
X1303277Y182460D01*
Y182462D01*
X1279510Y189983D01*
X1260154Y188001D01*
X1251247Y189706D01*
X1239330Y199327D01*
X1235426Y208033D01*
X1236191Y212320D01*
X1235420Y216193D01*
X1236247Y219472D01*
X1235625Y221938D01*
X1238077Y237847D01*
X1236248Y257363D01*
X1220441Y295524D01*
X1212993Y304599D01*
X1208994Y307272D01*
X1206987D01*
G01X1449991Y5589D02*
X1450003Y5601D01*
X1451518D01*
X1451916Y5999D01*
Y18971D01*
X1451561Y20273D01*
X1450763Y20730D01*
X1450408Y22032D01*
X1450864Y22830D01*
X1450509Y24133D01*
X1449711Y24589D01*
X1449355Y25891D01*
X1449812Y26689D01*
X1449457Y27992D01*
X1448658Y28448D01*
X1448303Y29750D01*
X1448759Y30548D01*
X1447178Y36348D01*
X1440960Y41154D01*
X1427602Y103596D01*
X1407479Y133781D01*
X1392726Y143616D01*
X1386355Y151660D01*
X1385716Y151925D01*
X1353652D01*
X1352237Y153340D01*
Y165963D01*
X1351200Y167000D01*
X1343300D01*
X1342000Y168300D01*
Y172089D01*
X1341657Y172432D01*
X1335477Y173689D01*
X1327650Y172094D01*
X1279235Y187418D01*
X1260071Y185452D01*
X1249575Y187460D01*
X1237531Y197179D01*
X1232816Y207697D01*
X1233635Y212294D01*
X1232837Y216315D01*
X1233635Y219493D01*
X1233035Y221880D01*
X1235486Y238689D01*
X1233884Y255778D01*
X1217928Y294306D01*
X1211215Y301549D01*
X1208250Y303050D01*
X1207171D01*
G01X1446340Y11563D02*
X1444865D01*
X1444415Y12013D01*
Y16829D01*
X1444222Y17022D01*
X1442905Y18998D01*
X1439766Y34692D01*
X1440232Y37021D01*
X1426184Y103148D01*
X1406488Y132690D01*
X1390170Y143570D01*
X1387359Y147188D01*
X1385212Y148075D01*
X1348536D01*
X1348086Y148525D01*
Y161727D01*
X1346963Y162850D01*
X1324051D01*
X1323046Y163855D01*
Y171058D01*
X1321509Y172595D01*
X1279055Y186036D01*
X1259981Y184079D01*
X1248133Y186341D01*
X1236713Y195561D01*
X1231388Y207439D01*
X1232253Y212281D01*
X1231436Y216387D01*
X1232178Y219351D01*
X1231507Y222010D01*
X1233883Y239466D01*
X1232336Y255984D01*
X1217578Y291611D01*
X1210447Y299698D01*
X1208690Y300700D01*
X1208025D01*
G01X1212087Y339800D02*
X1216063D01*
X1219120Y337699D01*
X1219300Y337434D01*
X1221951Y333533D01*
X1221953Y333531D01*
X1233546Y323022D01*
X1239553Y315703D01*
X1239552Y315702D01*
X1260283Y265669D01*
X1295081Y215080D01*
X1304980Y208570D01*
X1328775Y201081D01*
X1337912Y202941D01*
X1346770Y201139D01*
X1354297Y202671D01*
X1412982Y186936D01*
X1421307Y181428D01*
X1427633Y171868D01*
X1432011Y149993D01*
X1442667Y133977D01*
X1452688Y127296D01*
X1453712Y125776D01*
Y125775D01*
X1453719Y125765D01*
X1453860Y125555D01*
X1461301Y120403D01*
X1464934Y103245D01*
X1470362Y100277D01*
X1478787Y64154D01*
X1489903Y50649D01*
X1500469Y44978D01*
X1514744Y41948D01*
X1516427Y42300D01*
X1517197Y41796D01*
X1518518Y42072D01*
X1519021Y42842D01*
X1520343Y43118D01*
X1521112Y42614D01*
X1522434Y42890D01*
X1522937Y43660D01*
X1524258Y43936D01*
X1525028Y43432D01*
X1526349Y43708D01*
X1526852Y44478D01*
X1536486Y46490D01*
X1558195Y42252D01*
X1558709Y41490D01*
X1560034Y41231D01*
X1560796Y41745D01*
X1562121Y41486D01*
X1565192Y39439D01*
X1566000Y38900D01*
X1568800Y34700D01*
X1568991Y34572D01*
X1568992Y34573D01*
X1578925Y27951D01*
X1584754Y19564D01*
X1602228Y13589D01*
X1602723Y12896D01*
Y11805D01*
X1602273Y11355D01*
X1600898D01*
G01X1216689Y336027D02*
X1217869Y335132D01*
X1219704Y332314D01*
X1225194Y326824D01*
X1232604Y320111D01*
X1237344Y314322D01*
X1257885Y264741D01*
X1293519Y212936D01*
X1303939Y206185D01*
X1328646Y198403D01*
X1337783Y200265D01*
X1346453Y198500D01*
X1354187Y200073D01*
X1411654Y184667D01*
X1419565Y179432D01*
X1424979Y171250D01*
X1429438Y149346D01*
X1440921Y132086D01*
X1450579Y125655D01*
X1452050Y123394D01*
X1459002Y118585D01*
X1462793Y101306D01*
X1468071Y98437D01*
X1476347Y62943D01*
X1488185Y48564D01*
X1499537Y42471D01*
X1516964Y38769D01*
X1522302Y39836D01*
X1523067Y39327D01*
X1524390Y39591D01*
X1524900Y40356D01*
X1526224Y40621D01*
X1526989Y40111D01*
X1528312Y40375D01*
X1528822Y41140D01*
X1532142Y41804D01*
X1532141D01*
X1539387Y43253D01*
X1554077Y40314D01*
X1555900Y39100D01*
X1557619Y36521D01*
X1563801Y32399D01*
Y32398D01*
X1566729Y31813D01*
X1572140Y28207D01*
X1586272Y14071D01*
X1592336D01*
X1593223Y13184D01*
Y11856D01*
X1592773Y11406D01*
X1591848D01*
G01X1214644Y333970D02*
X1215153Y333599D01*
X1217613Y331140D01*
X1218516Y329734D01*
X1222176Y326073D01*
X1230374Y318645D01*
X1235318Y312610D01*
X1259966Y253108D01*
X1281731Y221464D01*
X1285601Y219885D01*
X1291574Y211198D01*
X1302884Y203872D01*
X1328534Y195788D01*
X1337508Y197615D01*
X1346233Y195840D01*
X1354199Y197462D01*
X1410233Y182444D01*
X1417670Y177520D01*
X1422643Y170006D01*
X1427705Y145042D01*
X1444205Y120249D01*
X1454813Y118094D01*
X1456702Y116797D01*
X1460532Y99585D01*
X1465735Y96780D01*
X1473903Y61746D01*
X1486472Y46477D01*
X1498621Y39956D01*
X1518710Y35686D01*
X1533491Y38828D01*
X1570258Y26258D01*
X1575338Y21178D01*
Y20259D01*
X1576292Y19305D01*
X1577211D01*
X1578166Y18350D01*
Y17431D01*
X1579121Y16476D01*
X1580040D01*
X1583922Y12594D01*
X1583923D01*
Y11805D01*
X1583473Y11355D01*
X1581998D01*
G01X1207232Y329512D02*
X1213563D01*
X1217284Y327026D01*
X1228108Y317214D01*
X1233306Y310881D01*
X1257711Y251958D01*
X1257715Y251957D01*
X1257723Y251938D01*
X1280077Y219438D01*
X1283902Y217877D01*
X1289761Y209359D01*
X1301777Y201575D01*
X1328479Y193161D01*
X1337291Y194955D01*
X1345931Y193198D01*
X1354079Y194856D01*
X1409271Y180062D01*
X1409300Y180043D01*
X1415649Y175841D01*
X1420227Y168925D01*
X1425273Y144103D01*
X1442697Y117955D01*
X1453450Y115806D01*
X1454289Y115246D01*
X1458213Y97880D01*
X1463400Y95126D01*
X1471462Y60537D01*
X1484758Y44390D01*
X1497729Y37428D01*
X1506855Y35489D01*
X1507356Y34718D01*
X1508677Y34438D01*
X1509447Y34939D01*
X1510768Y34658D01*
X1511268Y33887D01*
X1512589Y33607D01*
X1513360Y34108D01*
X1514680Y33827D01*
X1515181Y33056D01*
X1516502Y32776D01*
X1517272Y33276D01*
X1519781Y32744D01*
X1534439Y35854D01*
X1566122Y25023D01*
X1570247Y20898D01*
X1570248D01*
X1574373Y16773D01*
Y12956D01*
X1573923Y12506D01*
X1573048D01*
G01X1210188Y326850D02*
X1212665D01*
X1214018Y325945D01*
X1227347Y313864D01*
X1231400Y308924D01*
X1255513Y250724D01*
X1255518Y250714D01*
X1278426Y217410D01*
X1278428Y217409D01*
X1282210Y215866D01*
X1287944Y207526D01*
X1301067Y199027D01*
X1328163Y190480D01*
X1337071Y192296D01*
X1345658Y190549D01*
X1354075Y192263D01*
X1407748Y177877D01*
X1414034Y173718D01*
X1417872Y167917D01*
X1422932Y142965D01*
Y142964D01*
X1446880Y107094D01*
X1448259Y100390D01*
X1461086Y93367D01*
X1465747Y73374D01*
X1469020Y59334D01*
X1483074Y42263D01*
X1490401Y38346D01*
X1493145Y34506D01*
X1492994Y33599D01*
X1493778Y32500D01*
X1494685Y32349D01*
X1495470Y31251D01*
X1495319Y30344D01*
X1496104Y29246D01*
X1497010Y29094D01*
X1499468Y25654D01*
X1506862Y24152D01*
X1514071Y28645D01*
X1516032Y29061D01*
X1516803Y28560D01*
X1518123Y28841D01*
X1518624Y29612D01*
Y29611D01*
X1534763Y33038D01*
X1555842Y25831D01*
X1564979Y16694D01*
Y13056D01*
X1564429Y12506D01*
X1563498D01*
G01X1210883Y325204D02*
X1212122D01*
X1226771Y311928D01*
X1230545Y307327D01*
X1254186Y250252D01*
X1277528Y216318D01*
X1281262Y214794D01*
X1286925Y206560D01*
X1300581Y197716D01*
X1328003Y189053D01*
X1336746Y190832D01*
X1345348Y189082D01*
X1354013Y190845D01*
X1407033Y176633D01*
X1413014Y172675D01*
X1416515Y167383D01*
X1421539Y142601D01*
X1445368Y106857D01*
X1447142Y97984D01*
X1451025Y92166D01*
X1461254Y85347D01*
X1467553Y58325D01*
X1499915Y19015D01*
X1504728Y16907D01*
X1519631Y20075D01*
X1529145Y18054D01*
X1540537Y20474D01*
X1543367Y19873D01*
X1548189Y20897D01*
X1550715Y20361D01*
Y20360D01*
X1553336Y19804D01*
X1556816Y16323D01*
Y12972D01*
X1557482Y12306D01*
X1558148D01*
G01X1544698Y12506D02*
X1545346D01*
X1546050Y13210D01*
Y14820D01*
X1545291Y15577D01*
X1540537Y16589D01*
X1533056Y15000D01*
X1532555Y14229D01*
X1531234Y13949D01*
X1530464Y14449D01*
X1529143Y14169D01*
X1519281Y16264D01*
X1515832Y15532D01*
X1515332Y14761D01*
X1514011Y14481D01*
X1513240Y14982D01*
X1511920Y14701D01*
X1511419Y13930D01*
X1510098Y13650D01*
X1509327Y14151D01*
X1508007Y13871D01*
X1507506Y13100D01*
X1506185Y12819D01*
X1505415Y13320D01*
X1504094Y13040D01*
X1485997Y20968D01*
X1472559Y39731D01*
X1451714Y55934D01*
X1440970Y106796D01*
X1418047Y141178D01*
X1413015Y165916D01*
X1410411Y169850D01*
X1405216Y173289D01*
X1353816Y187065D01*
X1345004Y185273D01*
X1336420Y187020D01*
X1327833Y185271D01*
X1298974Y194391D01*
X1284333Y203861D01*
X1278853Y211833D01*
X1275126Y213353D01*
X1275123Y213355D01*
X1250867Y248618D01*
X1250864Y248624D01*
X1250865D01*
X1227770Y304370D01*
X1223415Y309679D01*
X1211015Y320920D01*
X1210096D01*
G01X1209321Y316462D02*
X1211888D01*
X1220672Y308503D01*
X1226037Y301965D01*
X1248600Y247486D01*
X1273473Y211324D01*
X1277132Y209834D01*
X1282469Y202070D01*
X1297871Y192091D01*
X1327711Y182653D01*
X1336150Y184371D01*
X1344689Y182633D01*
X1353622Y184450D01*
X1404088Y170923D01*
X1408688Y167879D01*
X1410590Y165006D01*
X1415639Y140043D01*
X1437938Y106593D01*
X1449638Y51905D01*
X1449985Y51647D01*
X1449986D01*
X1464711Y40710D01*
X1467636Y33385D01*
X1470491Y30531D01*
X1472324D01*
X1473279Y29576D01*
Y28657D01*
X1474233Y27703D01*
X1475152D01*
X1476107Y26748D01*
Y25829D01*
X1477062Y24874D01*
X1477981D01*
X1478935Y23920D01*
Y23000D01*
X1479890Y22046D01*
X1480809D01*
X1490695Y12160D01*
Y7359D01*
X1490245Y6909D01*
X1488770D01*
G01X1208852Y313702D02*
X1210761D01*
X1211796Y313010D01*
X1217098Y308204D01*
X1224332Y299387D01*
X1246243Y246485D01*
X1246242D01*
X1246245Y246479D01*
X1271821Y209296D01*
X1271824Y209294D01*
X1275413Y207833D01*
X1280616Y200265D01*
X1296757Y189809D01*
X1327564Y180063D01*
X1335787Y181741D01*
X1344459Y179976D01*
X1353341Y181782D01*
X1403324Y168384D01*
X1406760Y166109D01*
X1408191Y163950D01*
X1413189Y139115D01*
X1435127Y106210D01*
X1447021Y50610D01*
X1460000Y40925D01*
X1460300Y40701D01*
X1461484Y39818D01*
X1465147Y30366D01*
X1469746Y25767D01*
Y24847D01*
X1470701Y23893D01*
X1471620D01*
X1472575Y22938D01*
Y22019D01*
X1473529Y21064D01*
X1474449D01*
X1475403Y20110D01*
Y19191D01*
X1476358Y18236D01*
X1477277D01*
X1478232Y17281D01*
Y16362D01*
X1479186Y15408D01*
X1480105D01*
X1481060Y14453D01*
Y12013D01*
X1480610Y11563D01*
X1479135D01*
G01X1213724Y343450D02*
X1217139D01*
X1222366Y340020D01*
X1224906Y335894D01*
X1235747Y326106D01*
X1242919Y317366D01*
X1263731Y267123D01*
X1297510Y218010D01*
X1306548Y212059D01*
X1329186Y204939D01*
X1338170Y206768D01*
X1347089Y204953D01*
X1355060Y206575D01*
X1414511Y190354D01*
X1424163Y183968D01*
X1431014Y173617D01*
X1435374Y151821D01*
X1445539Y136539D01*
X1455937Y129605D01*
X1457093Y127869D01*
X1457094Y127868D01*
X1457152Y127782D01*
X1464700Y122579D01*
X1468205Y105661D01*
X1470905Y104176D01*
X1470906D01*
X1473608Y102690D01*
X1482153Y66042D01*
X1492356Y53646D01*
X1501789Y48586D01*
X1512485Y46314D01*
X1534299Y50873D01*
X1570249Y43683D01*
X1576930Y39230D01*
X1588096Y22479D01*
X1611028Y15434D01*
X1612746Y13715D01*
Y6404D01*
X1613725Y5425D01*
X1614833D01*
G01X1211093Y372772D02*
X1212027D01*
X1255171Y329631D01*
X1275311Y281006D01*
X1311785Y227980D01*
X1312599Y227443D01*
X1372749D01*
X1401454Y217810D01*
X1403531D01*
X1411705Y215067D01*
X1423073Y206977D01*
X1436864Y203041D01*
X1446430Y193476D01*
X1452499D01*
X1454584Y195561D01*
X1461544D01*
X1464832Y192273D01*
X1474349D01*
X1475995Y190627D01*
X1497798D01*
X1497799Y190628D01*
X1498751D01*
X1504929Y184450D01*
X1517951D01*
X1518952Y185451D01*
X1520425D01*
X1525787Y190813D01*
Y194550D01*
X1527700Y196463D01*
X1537973D01*
X1547110Y205600D01*
X1554708D01*
X1558305Y202003D01*
X1576132D01*
X1577454Y203325D01*
X1596739D01*
X1602464Y209050D01*
X1631423D01*
X1634211Y211838D01*
X1639365D01*
X1642357Y208846D01*
X1651330D01*
X1654901Y205275D01*
X1657010D01*
X1658975Y207240D01*
X1666769D01*
X1669808Y204201D01*
X1678708D01*
X1681359Y201550D01*
X1717474D01*
X1729269Y189755D01*
X1786545D01*
X1793260Y183040D01*
Y176976D01*
X1793711Y176525D01*
X1795185D01*
G01X1764988D02*
X1766375D01*
X1766913Y177063D01*
Y180510D01*
X1765873Y181550D01*
X1763277D01*
X1762150Y180423D01*
Y170923D01*
X1758817Y167590D01*
X1714283D01*
X1713348Y168525D01*
X1693652D01*
X1690577Y165450D01*
X1687283D01*
X1683930Y168803D01*
Y170752D01*
X1679769Y174913D01*
X1677611D01*
X1674710Y177814D01*
X1668403D01*
X1668402Y177815D01*
X1667358D01*
X1664150Y181023D01*
Y181823D01*
X1659838Y186135D01*
X1654336D01*
X1651141Y189330D01*
X1635059D01*
X1634409Y188680D01*
X1633059D01*
X1632409Y189330D01*
X1631059D01*
X1630409Y188680D01*
X1629059D01*
X1628409Y189330D01*
X1627059D01*
X1625639Y190750D01*
X1605129D01*
X1599852Y185473D01*
X1583173D01*
X1574570Y176870D01*
X1568654D01*
X1567951Y177573D01*
X1556301D01*
X1553659Y174931D01*
X1551259D01*
X1549688Y173360D01*
X1528124D01*
X1526014Y171250D01*
X1525150D01*
X1522248Y168348D01*
X1500375D01*
X1498734Y166707D01*
X1495574D01*
X1495568Y166701D01*
X1484748D01*
X1478277Y160230D01*
X1474832D01*
X1470333Y155731D01*
X1449106D01*
X1442217Y162620D01*
Y169155D01*
X1426185Y185187D01*
X1415730Y192054D01*
X1383633Y200904D01*
X1367368Y212479D01*
X1341803D01*
X1340308Y210984D01*
X1316501D01*
X1307668Y213806D01*
X1302522Y217212D01*
X1262486Y275407D01*
X1243180Y322020D01*
X1222366Y342834D01*
X1220457Y344077D01*
X1216494Y345471D01*
G01X1752390Y176525D02*
X1753865D01*
X1754315Y176075D01*
Y172650D01*
X1752905Y171240D01*
X1751555D01*
X1750905Y171890D01*
X1749555D01*
X1748905Y171240D01*
X1747555D01*
X1746905Y171890D01*
X1745555D01*
X1744905Y171240D01*
X1743555D01*
X1742905Y171890D01*
X1741555D01*
X1740905Y171240D01*
X1739555D01*
X1738905Y171890D01*
X1737555D01*
X1736905Y171240D01*
X1716200D01*
X1715265Y172175D01*
X1687692D01*
X1681115Y178752D01*
X1679026D01*
X1676580Y181198D01*
X1670601D01*
X1669950Y181849D01*
Y183577D01*
X1668177Y185350D01*
X1666777D01*
X1662331Y189796D01*
X1656054D01*
X1652870Y192980D01*
X1628573D01*
X1627153Y194400D01*
X1603531D01*
X1598299Y189168D01*
X1581102D01*
X1576943Y185009D01*
X1565214D01*
X1561705Y181500D01*
X1555064D01*
X1552145Y178581D01*
X1549745D01*
X1548174Y177010D01*
X1539390D01*
X1536800Y179600D01*
X1529200D01*
X1524500Y174900D01*
X1523636D01*
X1520734Y171998D01*
X1498471D01*
X1496923Y170450D01*
X1483050D01*
X1476600Y164000D01*
X1473438D01*
X1468819Y159381D01*
X1450824D01*
X1446131Y164074D01*
Y174032D01*
X1437917Y182246D01*
X1418051Y195220D01*
X1384712Y204653D01*
X1368594Y216129D01*
X1339659D01*
X1338164Y214634D01*
X1317112D01*
X1309664Y217019D01*
X1304932Y220151D01*
X1265731Y277134D01*
X1246244Y324184D01*
X1223453Y346975D01*
X1213973Y350900D01*
X1211585D01*
X1207730Y354755D01*
G01X1215130Y357270D02*
X1247495Y324905D01*
X1267001Y277810D01*
X1305988Y221136D01*
X1309617Y218736D01*
X1367555D01*
X1384881Y206400D01*
X1429165Y193368D01*
X1433247D01*
X1441789Y184826D01*
X1448537D01*
X1457112Y176251D01*
X1482703D01*
X1488364Y181912D01*
X1494865D01*
X1500977Y175800D01*
X1521539D01*
X1522540Y176801D01*
X1524102D01*
X1528451Y181150D01*
X1538823D01*
X1541572Y178401D01*
X1547655D01*
X1549185Y179931D01*
X1551482D01*
X1554551Y183000D01*
X1560721D01*
X1564184Y186463D01*
X1573423D01*
X1581440Y194480D01*
X1600157D01*
X1605873Y200196D01*
X1620266D01*
X1620916Y199546D01*
X1622266D01*
X1622916Y200196D01*
X1624266D01*
X1624916Y199546D01*
X1626266D01*
X1626916Y200196D01*
X1647731D01*
X1656481Y191446D01*
X1663127D01*
X1668123Y186450D01*
X1675423D01*
X1677350Y184523D01*
Y182347D01*
X1679304Y180393D01*
X1681944D01*
X1685837Y176500D01*
X1702429D01*
X1704298Y178369D01*
X1714692D01*
X1716124Y176937D01*
Y174482D01*
X1718016Y172590D01*
X1733456D01*
X1736850Y175984D01*
Y180523D01*
X1737827Y181500D01*
X1740773D01*
X1741717Y180556D01*
Y176975D01*
X1741267Y176525D01*
X1739792D01*
G01X1732193D02*
X1730776D01*
X1730326Y176975D01*
Y180301D01*
X1727127Y183500D01*
X1715073D01*
X1713904Y182331D01*
X1703096D01*
X1701015Y180250D01*
X1689950D01*
X1689500Y180700D01*
Y182001D01*
X1680890Y190611D01*
X1679346D01*
X1679345Y190610D01*
X1669490D01*
X1667996Y192104D01*
Y196911D01*
X1665899Y199008D01*
X1662887D01*
X1662133Y198254D01*
X1660403D01*
X1659265Y199392D01*
X1653710D01*
X1649256Y203846D01*
X1604360D01*
X1598826Y198325D01*
X1579528D01*
X1571684Y190481D01*
X1562954D01*
X1559392Y186919D01*
X1549481D01*
X1545700Y190700D01*
X1541000D01*
X1536400Y186100D01*
X1528237D01*
X1522588Y180451D01*
X1521026D01*
X1520025Y179450D01*
X1502574D01*
X1496449Y185575D01*
X1495497D01*
X1495496Y185574D01*
X1482961D01*
X1480702Y183315D01*
Y181013D01*
X1479739Y180050D01*
X1459243D01*
X1450817Y188476D01*
X1443313D01*
X1434741Y197049D01*
X1423476Y200291D01*
X1409039Y209916D01*
X1403733Y211696D01*
X1395311Y210016D01*
X1383219Y212434D01*
X1369080Y222436D01*
X1310653D01*
X1308586Y223804D01*
Y223803D01*
X1270632Y278977D01*
X1250823Y326805D01*
X1215979Y361649D01*
X1211629Y363450D01*
X1210387D01*
G01X1211093Y371622D02*
X1211550D01*
X1254195Y328979D01*
X1274294Y280454D01*
X1310964Y227144D01*
X1312253Y226293D01*
X1372561D01*
X1401266Y216660D01*
X1403343D01*
X1411177Y214031D01*
X1422567Y205925D01*
X1436261Y202016D01*
X1445953Y192326D01*
X1452976D01*
X1455061Y194411D01*
X1461067D01*
X1464355Y191123D01*
X1473872D01*
X1475518Y189477D01*
X1498275D01*
X1504452Y183300D01*
X1518428D01*
X1519429Y184301D01*
X1520902D01*
X1526937Y190336D01*
Y194073D01*
X1528177Y195313D01*
X1538450D01*
X1547587Y204450D01*
X1554231D01*
X1557829Y200852D01*
X1558781D01*
X1558782Y200853D01*
X1576609D01*
X1577931Y202175D01*
X1597216D01*
X1602941Y207900D01*
X1631900D01*
X1634688Y210688D01*
X1638888D01*
X1641880Y207696D01*
X1650851D01*
X1650852Y207697D01*
X1654424Y204125D01*
X1657487D01*
X1659452Y206090D01*
X1666292D01*
X1669331Y203051D01*
X1678231D01*
X1680882Y200400D01*
X1716997D01*
X1728792Y188605D01*
X1730142D01*
X1730792Y187955D01*
X1732142D01*
X1732792Y188605D01*
X1734142D01*
X1734792Y187955D01*
X1736142D01*
X1736792Y188605D01*
X1738142D01*
X1738792Y187955D01*
X1740142D01*
X1740792Y188605D01*
X1786068D01*
X1792110Y182563D01*
Y176975D01*
X1791660Y176525D01*
X1790185D01*
G01X1769988D02*
X1768514D01*
X1768063Y176976D01*
Y180987D01*
X1766350Y182700D01*
X1762800D01*
X1761000Y180900D01*
Y171400D01*
X1758340Y168740D01*
X1714760D01*
X1713825Y169675D01*
X1693175D01*
X1690100Y166600D01*
X1687760D01*
X1685080Y169280D01*
Y171229D01*
X1680246Y176063D01*
X1678088D01*
X1675187Y178964D01*
X1668880D01*
X1668879Y178965D01*
X1667835D01*
X1665300Y181500D01*
Y182300D01*
X1660315Y187285D01*
X1654813D01*
X1651618Y190480D01*
X1627536D01*
X1626116Y191900D01*
X1604652D01*
X1599375Y186623D01*
X1582696D01*
X1574093Y178020D01*
X1569131D01*
X1568428Y178723D01*
X1555824D01*
X1553182Y176081D01*
X1550782D01*
X1549211Y174510D01*
X1527647D01*
X1525537Y172400D01*
X1524673D01*
X1521771Y169498D01*
X1499898D01*
X1498257Y167857D01*
X1495097D01*
X1495091Y167851D01*
X1484271D01*
X1477800Y161380D01*
X1474355D01*
X1469856Y156881D01*
X1449583D01*
X1443367Y163097D01*
Y169632D01*
X1426915Y186084D01*
X1416210Y193115D01*
X1384134Y201959D01*
X1367736Y213629D01*
X1341326D01*
X1339831Y212134D01*
X1316681D01*
X1308170Y214853D01*
X1303343Y218048D01*
X1263503Y275959D01*
X1244156Y322672D01*
X1223095Y343733D01*
X1220969Y345116D01*
X1216876Y346556D01*
G01X1757390Y176525D02*
X1755916D01*
X1755465Y176074D01*
Y172173D01*
X1753382Y170090D01*
X1715723D01*
X1714788Y171025D01*
X1687215D01*
X1680638Y177602D01*
X1678549D01*
X1676103Y180048D01*
X1670124D01*
X1668800Y181372D01*
Y183100D01*
X1667700Y184200D01*
X1666300D01*
X1661854Y188646D01*
X1655577D01*
X1652393Y191830D01*
X1628096D01*
X1626676Y193250D01*
X1604008D01*
X1598776Y188018D01*
X1581579D01*
X1577420Y183859D01*
X1565691D01*
X1562182Y180350D01*
X1555541D01*
X1552622Y177431D01*
X1550222D01*
X1548651Y175860D01*
X1538913D01*
X1536323Y178450D01*
X1529677D01*
X1524977Y173750D01*
X1524113D01*
X1521211Y170848D01*
X1498948D01*
X1497400Y169300D01*
X1483527D01*
X1477077Y162850D01*
X1473915D01*
X1469296Y158231D01*
X1450347D01*
X1444981Y163597D01*
Y173555D01*
X1437188Y181348D01*
X1417569Y194161D01*
X1384207Y203600D01*
X1368226Y214979D01*
X1340136D01*
X1338641Y213484D01*
X1316932D01*
X1309161Y215972D01*
X1304111Y219315D01*
X1264714Y276582D01*
X1245268Y323532D01*
X1222801Y345999D01*
X1213744Y349750D01*
X1211108D01*
X1206916Y353941D01*
G01X1215944Y358084D02*
X1248471Y325557D01*
X1268018Y278362D01*
X1306809Y221972D01*
Y221973D01*
X1309963Y219886D01*
X1367923D01*
X1385391Y207449D01*
X1429331Y194518D01*
X1433724D01*
X1442266Y185976D01*
X1449014D01*
X1457589Y177401D01*
X1482226D01*
X1487887Y183062D01*
X1495342D01*
X1501454Y176950D01*
X1521062D01*
X1522063Y177951D01*
X1523625D01*
X1527974Y182300D01*
X1539300D01*
X1542049Y179551D01*
X1547178D01*
X1548708Y181081D01*
X1551005D01*
X1554074Y184150D01*
X1560244D01*
X1563707Y187613D01*
X1572946D01*
X1580963Y195630D01*
X1599680D01*
X1605396Y201346D01*
X1648208D01*
X1656958Y192596D01*
X1663604D01*
X1668600Y187600D01*
X1675900D01*
X1678500Y185000D01*
Y182824D01*
X1679781Y181543D01*
X1682421D01*
X1686314Y177650D01*
X1701952D01*
X1703821Y179519D01*
X1715169D01*
X1717274Y177414D01*
Y174959D01*
X1718493Y173740D01*
X1732979D01*
X1735700Y176461D01*
Y181000D01*
X1737350Y182650D01*
X1741250D01*
X1742867Y181033D01*
Y176976D01*
X1743318Y176525D01*
X1744792D01*
G01X1210387Y362300D02*
X1211400D01*
X1215327Y360673D01*
X1249847Y326153D01*
X1269613Y278429D01*
X1307765Y222967D01*
X1310306Y221286D01*
X1368714D01*
X1382754Y211354D01*
X1395311Y208843D01*
X1403658Y210508D01*
X1408528Y208874D01*
X1422986Y199234D01*
X1434137Y196025D01*
X1442836Y187326D01*
X1450340D01*
X1458766Y178900D01*
X1480216D01*
X1481852Y180536D01*
Y182838D01*
X1483438Y184424D01*
X1495973D01*
X1502097Y178300D01*
X1520502D01*
X1521503Y179301D01*
X1523065D01*
X1528714Y184950D01*
X1536877D01*
X1541477Y189550D01*
X1545223D01*
X1549004Y185769D01*
X1559869D01*
X1563431Y189331D01*
X1572161D01*
X1580005Y197175D01*
X1599302D01*
X1604836Y202696D01*
X1648779D01*
X1653233Y198242D01*
X1658788D01*
X1659926Y197104D01*
X1662610D01*
X1663364Y197858D01*
X1665422D01*
X1666846Y196434D01*
Y191627D01*
X1669013Y189460D01*
X1679822D01*
X1679823Y189461D01*
X1680413D01*
X1681368Y188506D01*
Y187587D01*
X1682322Y186633D01*
X1683241D01*
X1688350Y181524D01*
Y180223D01*
X1689473Y179100D01*
X1701492D01*
X1703573Y181181D01*
X1714381D01*
X1715550Y182350D01*
X1716900D01*
X1717550Y181700D01*
X1718900D01*
X1719550Y182350D01*
X1720900D01*
X1721550Y181700D01*
X1722900D01*
X1723550Y182350D01*
X1726650D01*
X1729176Y179824D01*
Y177033D01*
X1728668Y176525D01*
X1727193D01*
G01X1814125Y212231D02*
X1812651D01*
X1812200Y212682D01*
Y216427D01*
X1807977Y220650D01*
X1804877D01*
X1797850Y227677D01*
Y236377D01*
X1793138Y241089D01*
X1710620D01*
X1703584Y248125D01*
X1695460D01*
X1689706Y242371D01*
Y232877D01*
X1688295Y231466D01*
X1679698D01*
X1675906Y235258D01*
X1659456D01*
X1658759Y235955D01*
X1654706D01*
X1649411Y241250D01*
X1638718D01*
X1630908Y249060D01*
X1624114D01*
X1618823Y243769D01*
X1613601D01*
X1608507Y238675D01*
X1601040D01*
X1598728Y236363D01*
X1595626D01*
X1594621Y235358D01*
X1578457D01*
X1572299Y229200D01*
X1539228D01*
X1538512Y229916D01*
X1505498D01*
X1503657Y228075D01*
X1497843D01*
X1494330Y224562D01*
X1490404D01*
X1487190Y227776D01*
X1478466D01*
X1477940Y227250D01*
X1457951D01*
X1454404Y230797D01*
X1441603D01*
X1412281Y260119D01*
X1408261D01*
X1405780Y262592D01*
X1399495Y263848D01*
X1380998Y260149D01*
X1377514Y260828D01*
X1372518Y259662D01*
X1366529Y260826D01*
X1361663Y259694D01*
X1354753Y261038D01*
X1351062Y260176D01*
X1331974Y263894D01*
X1306684Y280544D01*
X1292577Y301050D01*
X1274833Y343880D01*
X1210722Y407963D01*
X1203507Y410950D01*
X1198887D01*
G01X1801526Y212231D02*
X1800052D01*
X1799383Y212900D01*
Y216344D01*
X1785695Y230032D01*
X1714515D01*
X1707843Y223360D01*
X1696297D01*
X1690780Y228877D01*
X1678750D01*
X1674869Y232758D01*
X1658419D01*
X1657722Y233455D01*
X1653669D01*
X1648374Y238750D01*
X1637681D01*
X1629901Y246530D01*
X1625143D01*
X1619831Y241218D01*
X1614587D01*
X1609544Y236175D01*
X1602077D01*
X1599762Y233860D01*
X1596880D01*
X1595878Y232858D01*
X1579494D01*
X1573336Y226700D01*
X1538191D01*
X1537513Y227378D01*
X1507029D01*
X1500859Y221208D01*
Y217490D01*
X1498825Y215456D01*
X1490940D01*
X1490939Y215457D01*
X1488900D01*
X1488899Y215456D01*
X1485122D01*
X1481778Y218800D01*
X1480327D01*
X1474377Y224750D01*
X1456914D01*
X1453382Y228282D01*
X1440418D01*
X1411134Y257566D01*
X1407186D01*
X1404670Y260073D01*
X1399304Y261143D01*
X1381276Y257536D01*
X1377539Y258264D01*
X1372549Y257097D01*
X1366560Y258261D01*
X1361694Y257129D01*
X1354998Y258431D01*
X1351308Y257569D01*
X1330970Y261531D01*
X1330963Y261536D01*
X1304939Y278665D01*
X1290265Y299996D01*
X1272766Y342244D01*
X1210800Y404210D01*
X1208583D01*
G01X1788925Y211631D02*
X1787450D01*
X1787000Y212081D01*
Y216628D01*
X1776528Y227100D01*
X1716150D01*
X1709801Y220751D01*
X1695369D01*
X1689743Y226377D01*
X1677637D01*
X1673756Y230258D01*
X1657382D01*
X1656685Y230955D01*
X1641465D01*
X1635750Y236670D01*
X1613576D01*
X1610581Y233675D01*
X1603114D01*
X1600789Y231350D01*
X1597923D01*
X1596931Y230358D01*
X1580531D01*
X1574173Y224000D01*
X1534929D01*
X1532438Y221509D01*
X1524149D01*
X1521483Y224175D01*
X1508515D01*
X1503756Y219416D01*
Y216115D01*
X1500597Y212956D01*
X1484085D01*
X1480849Y216192D01*
X1478735D01*
X1473657Y221270D01*
X1469243D01*
X1466923Y218950D01*
X1458809D01*
X1451977Y225782D01*
X1439219D01*
X1410009Y254992D01*
X1409057D01*
X1409056Y254991D01*
X1406219D01*
X1403567Y257623D01*
X1399368Y258463D01*
X1381609Y254911D01*
X1377570Y255699D01*
X1372580Y254532D01*
X1366580Y255698D01*
X1361711Y254565D01*
X1355214Y255830D01*
X1351523Y254968D01*
X1329735Y259212D01*
X1303328Y276592D01*
X1287867Y299067D01*
X1270667Y340596D01*
X1222825Y388438D01*
X1222824D01*
X1210834Y400428D01*
X1205825D01*
G01X1776325Y211631D02*
X1774851D01*
X1774400Y212082D01*
Y218527D01*
X1768327Y224600D01*
X1717771D01*
X1710726Y217555D01*
X1695028D01*
X1688841Y223742D01*
X1676735D01*
X1672719Y227758D01*
X1656345D01*
X1655648Y228455D01*
X1640428D01*
X1634713Y234170D01*
X1614613D01*
X1611618Y231175D01*
X1604151D01*
X1601819Y228843D01*
X1599081D01*
X1598044Y227806D01*
X1581579D01*
X1575273Y221500D01*
X1537092D01*
X1534192Y218600D01*
X1528276D01*
X1525779Y216103D01*
X1522523D01*
X1517126Y221500D01*
X1513062D01*
X1502018Y210456D01*
X1483048D01*
X1479812Y213692D01*
X1466535D01*
X1463977Y216250D01*
X1457493D01*
X1451323Y222420D01*
X1438980D01*
X1409033Y252367D01*
X1405142D01*
X1402238Y255245D01*
X1399153Y255861D01*
X1381602Y252354D01*
X1377601Y253134D01*
X1372611Y251967D01*
X1366710Y253114D01*
X1361841Y251981D01*
X1355359Y253243D01*
X1351664Y252382D01*
X1328663Y256861D01*
X1301620Y274659D01*
X1285585Y297968D01*
X1268490Y339236D01*
X1210991Y396735D01*
X1207140D01*
G01X1209318Y392030D02*
X1211596D01*
X1266729Y336897D01*
X1283320Y296845D01*
X1299981Y272627D01*
X1327470Y254536D01*
X1351762Y249804D01*
X1355465Y250663D01*
X1361867Y249417D01*
X1366736Y250550D01*
X1372642Y249402D01*
X1377632Y250569D01*
X1383685Y249388D01*
X1393662Y251716D01*
X1409190Y248611D01*
X1437951Y219850D01*
X1450298D01*
X1457698Y212450D01*
X1463244D01*
X1470294Y205400D01*
X1483199D01*
X1485755Y207956D01*
X1503239D01*
X1509372Y214089D01*
X1509425D01*
X1509943Y214607D01*
X1520169D01*
X1521561Y213215D01*
X1527211D01*
X1530096Y216100D01*
X1535648D01*
X1538496Y218948D01*
X1576341D01*
X1581798Y224405D01*
X1589381D01*
X1590411Y223375D01*
X1597417D01*
X1600330Y226288D01*
X1602863D01*
X1605175Y228600D01*
X1612700D01*
X1615770Y231670D01*
X1633676D01*
X1639391Y225955D01*
X1654611D01*
X1655308Y225258D01*
X1671682D01*
X1675788Y221152D01*
X1687894D01*
X1693991Y215055D01*
X1711763D01*
X1718808Y222100D01*
X1754199D01*
X1761661Y214638D01*
Y212220D01*
X1762250Y211631D01*
X1763725D01*
G01X1751125D02*
X1749650D01*
X1749200Y212081D01*
Y215539D01*
X1745239Y219500D01*
X1720255D01*
X1713310Y212555D01*
X1692954D01*
X1686905Y218604D01*
X1674799D01*
X1670645Y222758D01*
X1654271D01*
X1653574Y223455D01*
X1638354D01*
X1632639Y229170D01*
X1616807D01*
X1613737Y226100D01*
X1606212D01*
X1603741Y223629D01*
X1601256D01*
X1598502Y220875D01*
X1588625D01*
X1588079Y221421D01*
X1582351D01*
X1577378Y216448D01*
X1540608D01*
X1537009Y212849D01*
X1531741D01*
X1529592Y210700D01*
X1520500D01*
X1519093Y212107D01*
X1510980D01*
X1504329Y205456D01*
X1486792D01*
X1484236Y202900D01*
X1469257D01*
X1462207Y209950D01*
X1456272D01*
X1448922Y217300D01*
X1436942D01*
X1418902Y235341D01*
X1399979Y247867D01*
X1393636Y249135D01*
X1383716Y246823D01*
X1377663Y248004D01*
X1372673Y246837D01*
X1366831Y247972D01*
X1361962Y246839D01*
X1355625Y248073D01*
X1351936Y247211D01*
X1329532Y251567D01*
X1315894Y248407D01*
X1313756Y248823D01*
X1307823Y252728D01*
X1285201Y285612D01*
X1264562Y335439D01*
X1210526Y389475D01*
X1210525D01*
X1210524Y389476D01*
X1209572D01*
X1209571Y389475D01*
G01X1738484Y211631D02*
X1737419D01*
X1736450Y212600D01*
Y213677D01*
X1734277Y215850D01*
X1720973D01*
X1715139Y210015D01*
X1687838D01*
X1681794Y216059D01*
X1673807D01*
X1669608Y220258D01*
X1653234D01*
X1652537Y220955D01*
X1618572D01*
X1615976Y223551D01*
X1607200D01*
X1604778Y221129D01*
X1602453D01*
X1593324Y212000D01*
X1589421D01*
X1587571Y213850D01*
X1542176D01*
X1538675Y210349D01*
X1532778D01*
X1530629Y208200D01*
X1524800D01*
X1517700Y201100D01*
X1515527D01*
X1513671Y202956D01*
X1487829D01*
X1485273Y200400D01*
X1468220D01*
X1461170Y207450D01*
X1455235D01*
X1448155Y214530D01*
X1435026D01*
X1414035Y235522D01*
X1398462Y245336D01*
X1393032Y246422D01*
X1383747Y244258D01*
X1377694Y245439D01*
X1372704Y244272D01*
X1366859Y245408D01*
X1361990Y244275D01*
X1355651Y245509D01*
X1351963Y244647D01*
X1330351Y248848D01*
X1316399Y245615D01*
X1312789Y246318D01*
X1306115Y250637D01*
X1282981Y284269D01*
X1262368Y334033D01*
X1211951Y384450D01*
X1210187D01*
G01X1184341Y410292D02*
X1188716D01*
X1194042Y412500D01*
X1203905D01*
X1211212Y409475D01*
X1276023Y344692D01*
X1294914Y300099D01*
X1295027Y299893D01*
X1307664Y281517D01*
X1332494Y265175D01*
X1350943Y261586D01*
X1354639Y262447D01*
X1361625Y261087D01*
X1366494Y262220D01*
X1372509Y261051D01*
X1377499Y262218D01*
X1380951Y261544D01*
X1399585Y265270D01*
X1406463Y263894D01*
X1408856Y261501D01*
X1412809D01*
X1442113Y232197D01*
X1455103D01*
X1458700Y228600D01*
X1467100D01*
X1471024Y232524D01*
X1494717D01*
X1498192Y235999D01*
X1502042D01*
X1506775Y231266D01*
X1539084D01*
X1539800Y230550D01*
X1571659D01*
X1581848Y240739D01*
X1602055D01*
X1606556Y245240D01*
X1618360D01*
X1623530Y250410D01*
X1631490D01*
X1633900Y248000D01*
X1638892D01*
X1640147Y246745D01*
Y245191D01*
X1642253Y243085D01*
X1649486D01*
X1655266Y237305D01*
X1659319D01*
X1660016Y236608D01*
X1676483D01*
X1677489Y235602D01*
X1685592D01*
X1688356Y238366D01*
Y242931D01*
X1694900Y249475D01*
X1704144D01*
X1711180Y242439D01*
X1797208D01*
X1805180Y234467D01*
X1810496D01*
X1814955Y230008D01*
Y229032D01*
X1815910Y228078D01*
X1816885D01*
X1817840Y227123D01*
Y226147D01*
X1818795Y225193D01*
X1819770D01*
X1820725Y224238D01*
Y223262D01*
X1821680Y222308D01*
X1822655D01*
X1823610Y221353D01*
Y212611D01*
X1823160Y212161D01*
X1821685D01*
G01X1809125Y212231D02*
X1810600D01*
X1811050Y212681D01*
Y215950D01*
X1807500Y219500D01*
X1804400D01*
X1796700Y227200D01*
Y235900D01*
X1792661Y239939D01*
X1789361D01*
X1788711Y239289D01*
X1787311D01*
X1786661Y239939D01*
X1785261D01*
X1784611Y239289D01*
X1783211D01*
X1782561Y239939D01*
X1710143D01*
X1703107Y246975D01*
X1695937D01*
X1690856Y241894D01*
Y232400D01*
X1688772Y230316D01*
X1679221D01*
X1675429Y234108D01*
X1658979D01*
X1658282Y234805D01*
X1654229D01*
X1648934Y240100D01*
X1638241D01*
X1630431Y247910D01*
X1624591D01*
X1619300Y242619D01*
X1614078D01*
X1608984Y237525D01*
X1601517D01*
X1599205Y235213D01*
X1596103D01*
X1595098Y234208D01*
X1578934D01*
X1572776Y228050D01*
X1538751D01*
X1538035Y228766D01*
X1505975D01*
X1504134Y226925D01*
X1498320D01*
X1494807Y223412D01*
X1489927D01*
X1486713Y226626D01*
X1478943D01*
X1478417Y226100D01*
X1457474D01*
X1453927Y229647D01*
X1441126D01*
X1411804Y258969D01*
X1407785D01*
X1405214Y261532D01*
X1399495Y262675D01*
X1381001Y258976D01*
X1377536Y259652D01*
X1372540Y258486D01*
X1366550Y259650D01*
X1361684Y258518D01*
X1354775Y259862D01*
X1351084Y259000D01*
X1331531Y262808D01*
X1305863Y279706D01*
X1291560Y300497D01*
X1273858Y343227D01*
X1210070Y406987D01*
X1208823Y407504D01*
X1207973Y407152D01*
X1206726Y407668D01*
X1206374Y408518D01*
X1203278Y409800D01*
X1198887D01*
G01X1796526Y212231D02*
X1797551D01*
X1798233Y212913D01*
Y215867D01*
X1790907Y223193D01*
X1789988D01*
X1789033Y224148D01*
Y225067D01*
X1788078Y226022D01*
X1787159D01*
X1786205Y226976D01*
Y227895D01*
X1785218Y228882D01*
X1714992D01*
X1714037Y227927D01*
Y227008D01*
X1713083Y226054D01*
X1712164D01*
X1711209Y225099D01*
Y224180D01*
X1710255Y223226D01*
X1709336D01*
X1708320Y222210D01*
X1695820D01*
X1690303Y227727D01*
X1678273D01*
X1674392Y231608D01*
X1657942D01*
X1657245Y232305D01*
X1653192D01*
X1647897Y237600D01*
X1637204D01*
X1629424Y245380D01*
X1625620D01*
X1620308Y240068D01*
X1615064D01*
X1610021Y235025D01*
X1602554D01*
X1600239Y232710D01*
X1597357D01*
X1596355Y231708D01*
X1579971D01*
X1573813Y225550D01*
X1537714D01*
X1537036Y226228D01*
X1507506D01*
X1502009Y220731D01*
Y217013D01*
X1499302Y214306D01*
X1484645D01*
X1481301Y217650D01*
X1479850D01*
X1473900Y223600D01*
X1456437D01*
X1452905Y227132D01*
X1439941D01*
X1410657Y256416D01*
X1406710D01*
X1404104Y259013D01*
X1399304Y259970D01*
X1381279Y256363D01*
X1377561Y257088D01*
X1372571Y255921D01*
X1366581Y257085D01*
X1361715Y255953D01*
X1355020Y257255D01*
X1351330Y256393D01*
X1330527Y260445D01*
X1304118Y277827D01*
X1289247Y299445D01*
X1271792Y341590D01*
X1210322Y403060D01*
X1208583D01*
G01X1783925Y211631D02*
X1785400D01*
X1785850Y212081D01*
Y216151D01*
X1781707Y220294D01*
X1780788D01*
X1779834Y221248D01*
Y222167D01*
X1778879Y223122D01*
X1777960D01*
X1777006Y224076D01*
Y224995D01*
X1776051Y225950D01*
X1716627D01*
X1710278Y219601D01*
X1704389D01*
X1703739Y218951D01*
X1702389D01*
X1701739Y219601D01*
X1700389D01*
X1699739Y218951D01*
X1698389D01*
X1697739Y219601D01*
X1694892D01*
X1689266Y225227D01*
X1677160D01*
X1673279Y229108D01*
X1656905D01*
X1656208Y229805D01*
X1640988D01*
X1635273Y235520D01*
X1614053D01*
X1611058Y232525D01*
X1603591D01*
X1601266Y230200D01*
X1598400D01*
X1597408Y229208D01*
X1581008D01*
X1574650Y222850D01*
X1535406D01*
X1532915Y220359D01*
X1523672D01*
X1521006Y223025D01*
X1508992D01*
X1504906Y218939D01*
Y215638D01*
X1501074Y211806D01*
X1483608D01*
X1480372Y215042D01*
X1478258D01*
X1473180Y220120D01*
X1469720D01*
X1467400Y217800D01*
X1458332D01*
X1451500Y224632D01*
X1438742D01*
X1409533Y253841D01*
X1405745D01*
X1403002Y256563D01*
X1399368Y257290D01*
X1381612Y253738D01*
X1377592Y254523D01*
X1372602Y253356D01*
X1366602Y254522D01*
X1361732Y253389D01*
X1355236Y254654D01*
X1351545Y253792D01*
X1329292Y258126D01*
X1302507Y275754D01*
X1286849Y298516D01*
X1269687Y339949D01*
X1222348Y387288D01*
X1222347D01*
X1210357Y399278D01*
X1205825D01*
G01X1771325Y211631D02*
X1772800D01*
X1773250Y212081D01*
Y218050D01*
X1770678Y220622D01*
X1769759D01*
X1768805Y221576D01*
Y222495D01*
X1767850Y223450D01*
X1766500D01*
X1765850Y222800D01*
X1764500D01*
X1763850Y223450D01*
X1762500D01*
X1761850Y222800D01*
X1760500D01*
X1759850Y223450D01*
X1758500D01*
X1757850Y222800D01*
X1756500D01*
X1755850Y223450D01*
X1718248D01*
X1711203Y216405D01*
X1694551D01*
X1688364Y222592D01*
X1676258D01*
X1672242Y226608D01*
X1655868D01*
X1655171Y227305D01*
X1639951D01*
X1634236Y233020D01*
X1615090D01*
X1612095Y230025D01*
X1604628D01*
X1602296Y227693D01*
X1599558D01*
X1598521Y226656D01*
X1582056D01*
X1575750Y220350D01*
X1537569D01*
X1534669Y217450D01*
X1528753D01*
X1526256Y214953D01*
X1522046D01*
X1516649Y220350D01*
X1513539D01*
X1502495Y209306D01*
X1482571D01*
X1479335Y212542D01*
X1466058D01*
X1463500Y215100D01*
X1457016D01*
X1450846Y221270D01*
X1438503D01*
X1408556Y251217D01*
X1404668D01*
X1401673Y254184D01*
X1399153Y254688D01*
X1381605Y251181D01*
X1377623Y251958D01*
X1372633Y250791D01*
X1366732Y251938D01*
X1361862Y250805D01*
X1355381Y252067D01*
X1351685Y251206D01*
X1328220Y255775D01*
X1300799Y273821D01*
X1284568Y297416D01*
X1267514Y338584D01*
X1210514Y395585D01*
X1207140D01*
G01X1758725Y211631D02*
X1760200D01*
X1760511Y211942D01*
Y214161D01*
X1759556Y215116D01*
X1758637D01*
X1757683Y216070D01*
Y216989D01*
X1756728Y217944D01*
X1755809D01*
X1754854Y218899D01*
Y219818D01*
X1753722Y220950D01*
X1752372D01*
X1751722Y220300D01*
X1750372D01*
X1749722Y220950D01*
X1748372D01*
X1747722Y220300D01*
X1746372D01*
X1745722Y220950D01*
X1719285D01*
X1712240Y213905D01*
X1693514D01*
X1687417Y220002D01*
X1675311D01*
X1671205Y224108D01*
X1654831D01*
X1654134Y224805D01*
X1638914D01*
X1633199Y230520D01*
X1616247D01*
X1613177Y227450D01*
X1605652D01*
X1603340Y225138D01*
X1600807D01*
X1597894Y222225D01*
X1589934D01*
X1588904Y223255D01*
X1582275D01*
X1576818Y217798D01*
X1538973D01*
X1536125Y214950D01*
X1530573D01*
X1527688Y212065D01*
X1521084D01*
X1519692Y213457D01*
X1510420D01*
X1509902Y212939D01*
X1509849D01*
X1503716Y206806D01*
X1486232D01*
X1483676Y204250D01*
X1469817D01*
X1462767Y211300D01*
X1457221D01*
X1449821Y218700D01*
X1437474D01*
X1408623Y247551D01*
X1393681Y250539D01*
X1383706Y248212D01*
X1377654Y249393D01*
X1372664Y248226D01*
X1366758Y249374D01*
X1361888Y248241D01*
X1355486Y249487D01*
X1351783Y248628D01*
X1327027Y253450D01*
X1299160Y271789D01*
X1282303Y296293D01*
X1265753Y336245D01*
X1211118Y390880D01*
X1209318D01*
G01X1746125Y211631D02*
X1747600D01*
X1748050Y212081D01*
Y215062D01*
X1744762Y218350D01*
X1743412D01*
X1742762Y217700D01*
X1741412D01*
X1740762Y218350D01*
X1739412D01*
X1738762Y217700D01*
X1737412D01*
X1736762Y218350D01*
X1735412D01*
X1734762Y217700D01*
X1733412D01*
X1732762Y218350D01*
X1720732D01*
X1713787Y211405D01*
X1692477D01*
X1686428Y217454D01*
X1674322D01*
X1670168Y221608D01*
X1653794D01*
X1653097Y222305D01*
X1637877D01*
X1632162Y228020D01*
X1617284D01*
X1614214Y224950D01*
X1606689D01*
X1604218Y222479D01*
X1601733D01*
X1598979Y219725D01*
X1588148D01*
X1587602Y220271D01*
X1582828D01*
X1577855Y215298D01*
X1541085D01*
X1537486Y211699D01*
X1532218D01*
X1530069Y209550D01*
X1520023D01*
X1518616Y210957D01*
X1511457D01*
X1504806Y204306D01*
X1487269D01*
X1484713Y201750D01*
X1468780D01*
X1461730Y208800D01*
X1455795D01*
X1448445Y216150D01*
X1436465D01*
X1418170Y234445D01*
X1399532Y246783D01*
X1393655Y247958D01*
X1383737Y245647D01*
X1377685Y246828D01*
X1372695Y245661D01*
X1366853Y246796D01*
X1361983Y245663D01*
X1355647Y246897D01*
X1351958Y246035D01*
X1329553Y250391D01*
X1315915Y247231D01*
X1313313Y247737D01*
X1307001Y251891D01*
X1284184Y285060D01*
X1263586Y334787D01*
X1210048Y388325D01*
X1209572D01*
G01X1733484Y211631D02*
X1734331D01*
X1735300Y212600D01*
Y213200D01*
X1733800Y214700D01*
X1732450D01*
X1731800Y214050D01*
X1730450D01*
X1729800Y214700D01*
X1728450D01*
X1727800Y214050D01*
X1726450D01*
X1725800Y214700D01*
X1721451D01*
X1720116Y213365D01*
Y212445D01*
X1719161Y211491D01*
X1718242D01*
X1715616Y208865D01*
X1687361D01*
X1681317Y214909D01*
X1673330D01*
X1669131Y219108D01*
X1652757D01*
X1652060Y219805D01*
X1623247D01*
X1622597Y219155D01*
X1621247D01*
X1620597Y219805D01*
X1618095D01*
X1615499Y222401D01*
X1607677D01*
X1605255Y219979D01*
X1602930D01*
X1593801Y210850D01*
X1588944D01*
X1587094Y212700D01*
X1542653D01*
X1539152Y209199D01*
X1533255D01*
X1531106Y207050D01*
X1525277D01*
X1518177Y199950D01*
X1515050D01*
X1513194Y201806D01*
X1488306D01*
X1485750Y199250D01*
X1467743D01*
X1460693Y206300D01*
X1454758D01*
X1447678Y213380D01*
X1434549D01*
X1431608Y216321D01*
X1430689D01*
X1429734Y217275D01*
Y218195D01*
X1413312Y234617D01*
X1398028Y244250D01*
X1393051Y245245D01*
X1383768Y243082D01*
X1377716Y244263D01*
X1372726Y243096D01*
X1366881Y244232D01*
X1362011Y243099D01*
X1355673Y244333D01*
X1351985Y243471D01*
X1330375Y247671D01*
X1316420Y244439D01*
X1312351Y245231D01*
X1305297Y249795D01*
X1281963Y283718D01*
X1261392Y333381D01*
X1211473Y383300D01*
X1210187D01*
G01X1184341Y411442D02*
X1188484D01*
X1193813Y413650D01*
X1204134D01*
X1211864Y410451D01*
X1276995Y345347D01*
X1295973Y300548D01*
X1295975Y300546D01*
Y300545D01*
X1308485Y282355D01*
X1332937Y266261D01*
X1350921Y262762D01*
X1354617Y263623D01*
X1361604Y262263D01*
X1366472Y263396D01*
X1372487Y262227D01*
X1377477Y263395D01*
X1380948Y262717D01*
X1399585Y266443D01*
X1407030Y264954D01*
X1409333Y262651D01*
X1413286D01*
X1442590Y233347D01*
X1455580D01*
X1459177Y229750D01*
X1466623D01*
X1470547Y233674D01*
X1494240D01*
X1497715Y237149D01*
X1502519D01*
X1507252Y232416D01*
X1539561D01*
X1540277Y231700D01*
X1571182D01*
X1581371Y241889D01*
X1601578D01*
X1606079Y246390D01*
X1617883D01*
X1623053Y251560D01*
X1631967D01*
X1634377Y249150D01*
X1639369D01*
X1641297Y247222D01*
Y245668D01*
X1642730Y244235D01*
X1649963D01*
X1655743Y238455D01*
X1659796D01*
X1660493Y237758D01*
X1676960D01*
X1677966Y236752D01*
X1685115D01*
X1687206Y238843D01*
Y243408D01*
X1694423Y250625D01*
X1704621D01*
X1711657Y243589D01*
X1797685D01*
X1805657Y235617D01*
X1810973D01*
X1824760Y221830D01*
Y212611D01*
X1825210Y212161D01*
X1826685D01*
G01X1519608Y646236D02*
X1517183Y648661D01*
X1515395D01*
X1511120Y649003D01*
X1508016Y648016D01*
X1507394Y647186D01*
X1507217Y646490D01*
X1506806Y644153D01*
X1505504Y643241D01*
X1503530Y643588D01*
X1502619Y644892D01*
X1504103Y653298D01*
X1503736Y653822D01*
X1502702Y654005D01*
X1502183Y653642D01*
X1500499Y644092D01*
X1499195Y643178D01*
X1497221Y643526D01*
X1496312Y644831D01*
X1497804Y653284D01*
X1497440Y653805D01*
X1496405Y653987D01*
X1495882Y653622D01*
X1494204Y644088D01*
X1492901Y643178D01*
X1490929Y643523D01*
X1490017Y644827D01*
X1491508Y653283D01*
X1491144Y653804D01*
X1490110Y653986D01*
X1489587Y653621D01*
X1487904Y644069D01*
X1486601Y643160D01*
X1484632Y643505D01*
X1483717Y644805D01*
X1485217Y653316D01*
X1484853Y653837D01*
X1483819Y654019D01*
X1483299Y653655D01*
X1481609Y644074D01*
X1480306Y643158D01*
X1478332Y643507D01*
X1477420Y644808D01*
X1478920Y653315D01*
X1478557Y653837D01*
X1477523Y654020D01*
X1477001Y653655D01*
X1475333Y644186D01*
X1474030Y643272D01*
X1472056Y643618D01*
X1471146Y644923D01*
X1472623Y653299D01*
X1472259Y653820D01*
X1471225Y654001D01*
X1470703Y653637D01*
X1469034Y644181D01*
X1467732Y643271D01*
X1465761Y643618D01*
X1464850Y644922D01*
X1466328Y653297D01*
X1465963Y653819D01*
X1464928Y654001D01*
X1464406Y653637D01*
X1462740Y644164D01*
X1461434Y643255D01*
X1459463Y643599D01*
X1458552Y644906D01*
X1460038Y653330D01*
X1459673Y653852D01*
X1458638Y654034D01*
X1458116Y653670D01*
X1456450Y644214D01*
X1455110Y643275D01*
X1453202Y643610D01*
X1452265Y644952D01*
X1453741Y653326D01*
X1453377Y653849D01*
X1452343Y654031D01*
X1451818Y653663D01*
X1450165Y644317D01*
X1448864Y643406D01*
X1446890Y643753D01*
X1445979Y645057D01*
X1447412Y653172D01*
X1447045Y653696D01*
X1446011Y653879D01*
X1445492Y653516D01*
X1443859Y644257D01*
X1442557Y643345D01*
X1440583Y643692D01*
X1439672Y644996D01*
X1441105Y653111D01*
X1440738Y653635D01*
X1439704Y653818D01*
X1439185Y653455D01*
X1437572Y644310D01*
X1436270Y643398D01*
X1434296Y643745D01*
X1433385Y645049D01*
X1434798Y653050D01*
X1434431Y653574D01*
X1433397Y653757D01*
X1432878Y653394D01*
X1431262Y644232D01*
X1429960Y643320D01*
X1427986Y643667D01*
X1427075Y644970D01*
X1428491Y652989D01*
X1428124Y653513D01*
X1427090Y653696D01*
X1426571Y653333D01*
X1424955Y644171D01*
X1423651Y643257D01*
X1421677Y643605D01*
X1420768Y644909D01*
X1422192Y652975D01*
X1421828Y653496D01*
X1420793Y653678D01*
X1420270Y653313D01*
X1418663Y644184D01*
X1417360Y643274D01*
X1415388Y643619D01*
X1414476Y644923D01*
X1415896Y652974D01*
X1415532Y653495D01*
X1414498Y653677D01*
X1413975Y653312D01*
X1412360Y644148D01*
X1411057Y643239D01*
X1409088Y643584D01*
X1408173Y644884D01*
X1409605Y653007D01*
X1409241Y653528D01*
X1408207Y653710D01*
X1407687Y653346D01*
X1406066Y644153D01*
X1404762Y643237D01*
X1402788Y643586D01*
X1401876Y644887D01*
X1403308Y653006D01*
X1402945Y653528D01*
X1401911Y653711D01*
X1401389Y653346D01*
X1399772Y644168D01*
X1398469Y643254D01*
X1396495Y643600D01*
X1395585Y644905D01*
X1397011Y652990D01*
X1396647Y653511D01*
X1395613Y653692D01*
X1395091Y653328D01*
X1393473Y644163D01*
X1392171Y643253D01*
X1390200Y643600D01*
X1389289Y644904D01*
X1390716Y652988D01*
X1390351Y653510D01*
X1389316Y653692D01*
X1388794Y653328D01*
X1387182Y644163D01*
X1385876Y643254D01*
X1383905Y643598D01*
X1382994Y644905D01*
X1384426Y653021D01*
X1384061Y653543D01*
X1383026Y653725D01*
X1382504Y653361D01*
X1380889Y644196D01*
X1379588Y643284D01*
X1377614Y643631D01*
X1376703Y644935D01*
X1378136Y653050D01*
X1377769Y653574D01*
X1376735Y653757D01*
X1376216Y653394D01*
X1374600Y644232D01*
X1373296Y643318D01*
X1371322Y643666D01*
X1370413Y644970D01*
X1371837Y653036D01*
X1371473Y653557D01*
X1370438Y653739D01*
X1369915Y653374D01*
X1368305Y644228D01*
X1367002Y643318D01*
X1365030Y643663D01*
X1364118Y644967D01*
X1365541Y653035D01*
X1365177Y653556D01*
X1364143Y653738D01*
X1363620Y653373D01*
X1362005Y644209D01*
X1360702Y643300D01*
X1358733Y643645D01*
X1357818Y644945D01*
X1359250Y653068D01*
X1358886Y653589D01*
X1357852Y653771D01*
X1357332Y653407D01*
X1355696Y644134D01*
X1354393Y643218D01*
X1352419Y643567D01*
X1351507Y644868D01*
X1352953Y653067D01*
X1352590Y653589D01*
X1351556Y653772D01*
X1351034Y653407D01*
X1349417Y644229D01*
X1348114Y643315D01*
X1346140Y643661D01*
X1345230Y644966D01*
X1346656Y653051D01*
X1346292Y653572D01*
X1345258Y653753D01*
X1344736Y653389D01*
X1343118Y644224D01*
X1341816Y643314D01*
X1339845Y643661D01*
X1338934Y644965D01*
X1340361Y653049D01*
X1339996Y653571D01*
X1338961Y653753D01*
X1338439Y653389D01*
X1336827Y644224D01*
X1335521Y643315D01*
X1333550Y643659D01*
X1332639Y644966D01*
X1334071Y653082D01*
X1333706Y653604D01*
X1332671Y653786D01*
X1332149Y653422D01*
X1330534Y644257D01*
X1329194Y643318D01*
X1327286Y643653D01*
X1326349Y644995D01*
X1327775Y653082D01*
X1327411Y653604D01*
X1326377Y653786D01*
X1325855Y653421D01*
X1324217Y644161D01*
X1322914Y643251D01*
X1320941Y643598D01*
X1320031Y644901D01*
X1321508Y653279D01*
X1321117Y653839D01*
X1320149Y654009D01*
X1319589Y653617D01*
X1317923Y644160D01*
X1316620Y643251D01*
X1314646Y643597D01*
X1313735Y644901D01*
X1315221Y653326D01*
X1314856Y653850D01*
X1313824Y654030D01*
X1313300Y653665D01*
X1311633Y644193D01*
X1310330Y643284D01*
X1308356Y643630D01*
X1307445Y644934D01*
X1308923Y653309D01*
X1308558Y653831D01*
X1307526Y654013D01*
X1307005Y653649D01*
X1305336Y644193D01*
X1304033Y643284D01*
X1302060Y643629D01*
X1301150Y644932D01*
X1302627Y653309D01*
X1302263Y653831D01*
X1301230Y654012D01*
X1300707Y653645D01*
X1299038Y644175D01*
X1297735Y643265D01*
X1295762Y643613D01*
X1294853Y644914D01*
X1296353Y653422D01*
X1295988Y653943D01*
X1294954Y654126D01*
X1294431Y653758D01*
X1292740Y644176D01*
X1291440Y643265D01*
X1289466Y643612D01*
X1288556Y644915D01*
X1290056Y653424D01*
X1289690Y653944D01*
X1288657Y654125D01*
X1288135Y653761D01*
X1286453Y644209D01*
X1285149Y643299D01*
X1283175Y643645D01*
X1282265Y644948D01*
X1283756Y653404D01*
X1283391Y653926D01*
X1282358Y654107D01*
X1281836Y653742D01*
X1280157Y644208D01*
X1278853Y643298D01*
X1276879Y643644D01*
X1275969Y644947D01*
X1277461Y653401D01*
X1277097Y653924D01*
X1276064Y654106D01*
X1275541Y653739D01*
X1273856Y644189D01*
X1272556Y643279D01*
X1270583Y643628D01*
X1269670Y644932D01*
X1271154Y653339D01*
X1270789Y653861D01*
X1269755Y654043D01*
X1269234Y653678D01*
X1268898Y651768D01*
X1268654Y650807D01*
X1267673Y649499D01*
X1264002Y648332D01*
X1259547Y648689D01*
X1257806D01*
X1255381Y646264D01*
G01X1519608Y652236D02*
X1517183Y649811D01*
X1515442D01*
X1510987Y650168D01*
X1507316Y649001D01*
X1506335Y647693D01*
X1506091Y646732D01*
X1505755Y644822D01*
X1505234Y644457D01*
X1504200Y644639D01*
X1503835Y645161D01*
X1505319Y653568D01*
X1504406Y654872D01*
X1502433Y655221D01*
X1501133Y654311D01*
X1499448Y644761D01*
X1498925Y644394D01*
X1497892Y644576D01*
X1497528Y645099D01*
X1499020Y653553D01*
X1498110Y654856D01*
X1496136Y655202D01*
X1494832Y654292D01*
X1493153Y644758D01*
X1492631Y644393D01*
X1491598Y644574D01*
X1491233Y645096D01*
X1492724Y653552D01*
X1491814Y654855D01*
X1489840Y655201D01*
X1488536Y654291D01*
X1486854Y644739D01*
X1486332Y644375D01*
X1485299Y644556D01*
X1484933Y645076D01*
X1486433Y653585D01*
X1485523Y654888D01*
X1483549Y655235D01*
X1482249Y654324D01*
X1480558Y644742D01*
X1480035Y644374D01*
X1479001Y644557D01*
X1478636Y645078D01*
X1480136Y653586D01*
X1479227Y654887D01*
X1477254Y655235D01*
X1475951Y654325D01*
X1474282Y644855D01*
X1473759Y644488D01*
X1472726Y644669D01*
X1472362Y645191D01*
X1473839Y653568D01*
X1472929Y654871D01*
X1470956Y655216D01*
X1469653Y654307D01*
X1467984Y644851D01*
X1467463Y644487D01*
X1466431Y644669D01*
X1466066Y645191D01*
X1467544Y653566D01*
X1466633Y654870D01*
X1464659Y655216D01*
X1463356Y654307D01*
X1461689Y644835D01*
X1461165Y644470D01*
X1460133Y644650D01*
X1459768Y645174D01*
X1461254Y653599D01*
X1460343Y654903D01*
X1458369Y655249D01*
X1457066Y654340D01*
X1455400Y644883D01*
X1454840Y644491D01*
X1453872Y644661D01*
X1453481Y645221D01*
X1454956Y653594D01*
X1454048Y654899D01*
X1452073Y655247D01*
X1450768Y654332D01*
X1449115Y644987D01*
X1448594Y644622D01*
X1447560Y644804D01*
X1447195Y645326D01*
X1448628Y653442D01*
X1447715Y654746D01*
X1445742Y655095D01*
X1444442Y654185D01*
X1442808Y644926D01*
X1442287Y644561D01*
X1441253Y644743D01*
X1440888Y645265D01*
X1442321Y653381D01*
X1441408Y654685D01*
X1439435Y655034D01*
X1438135Y654124D01*
X1436521Y644979D01*
X1436000Y644614D01*
X1434966Y644796D01*
X1434601Y645318D01*
X1436014Y653320D01*
X1435101Y654624D01*
X1433128Y654973D01*
X1431828Y654063D01*
X1430212Y644901D01*
X1429690Y644536D01*
X1428657Y644717D01*
X1428292Y645240D01*
X1429707Y653259D01*
X1428794Y654563D01*
X1426821Y654912D01*
X1425521Y654002D01*
X1423905Y644840D01*
X1423381Y644473D01*
X1422349Y644654D01*
X1421984Y645177D01*
X1423408Y653244D01*
X1422498Y654547D01*
X1420524Y654893D01*
X1419220Y653983D01*
X1417612Y644854D01*
X1417090Y644489D01*
X1416057Y644670D01*
X1415692Y645192D01*
X1417112Y653243D01*
X1416202Y654546D01*
X1414228Y654892D01*
X1412924Y653982D01*
X1411310Y644818D01*
X1410788Y644454D01*
X1409755Y644635D01*
X1409389Y645155D01*
X1410821Y653276D01*
X1409911Y654579D01*
X1407937Y654926D01*
X1406637Y654015D01*
X1405015Y644821D01*
X1404491Y644453D01*
X1403457Y644636D01*
X1403092Y645157D01*
X1404524Y653277D01*
X1403615Y654578D01*
X1401642Y654926D01*
X1400339Y654016D01*
X1398721Y644837D01*
X1398198Y644470D01*
X1397165Y644651D01*
X1396801Y645173D01*
X1398227Y653259D01*
X1397317Y654562D01*
X1395344Y654907D01*
X1394041Y653998D01*
X1392423Y644833D01*
X1391902Y644469D01*
X1390870Y644651D01*
X1390505Y645173D01*
X1391932Y653257D01*
X1391021Y654561D01*
X1389047Y654907D01*
X1387744Y653998D01*
X1386131Y644834D01*
X1385607Y644469D01*
X1384575Y644649D01*
X1384210Y645173D01*
X1385642Y653290D01*
X1384731Y654594D01*
X1382757Y654940D01*
X1381454Y654031D01*
X1379839Y644865D01*
X1379318Y644500D01*
X1378284Y644682D01*
X1377919Y645204D01*
X1379352Y653320D01*
X1378439Y654624D01*
X1376466Y654973D01*
X1375166Y654063D01*
X1373550Y644901D01*
X1373026Y644534D01*
X1371994Y644715D01*
X1371629Y645238D01*
X1373053Y653305D01*
X1372143Y654608D01*
X1370169Y654954D01*
X1368865Y654044D01*
X1367254Y644898D01*
X1366732Y644533D01*
X1365699Y644714D01*
X1365334Y645236D01*
X1366757Y653304D01*
X1365847Y654607D01*
X1363873Y654953D01*
X1362569Y654043D01*
X1360955Y644879D01*
X1360433Y644515D01*
X1359400Y644696D01*
X1359034Y645216D01*
X1360466Y653337D01*
X1359556Y654640D01*
X1357582Y654987D01*
X1356282Y654076D01*
X1354645Y644802D01*
X1354122Y644434D01*
X1353088Y644617D01*
X1352723Y645138D01*
X1354169Y653338D01*
X1353260Y654639D01*
X1351287Y654987D01*
X1349984Y654077D01*
X1348366Y644898D01*
X1347843Y644531D01*
X1346810Y644712D01*
X1346446Y645234D01*
X1347872Y653320D01*
X1346962Y654623D01*
X1344989Y654968D01*
X1343686Y654059D01*
X1342068Y644894D01*
X1341547Y644530D01*
X1340515Y644712D01*
X1340150Y645234D01*
X1341577Y653318D01*
X1340666Y654622D01*
X1338692Y654968D01*
X1337389Y654059D01*
X1335776Y644895D01*
X1335252Y644530D01*
X1334220Y644710D01*
X1333855Y645234D01*
X1335287Y653351D01*
X1334376Y654655D01*
X1332402Y655001D01*
X1331099Y654092D01*
X1329484Y644926D01*
X1328924Y644534D01*
X1327956Y644704D01*
X1327565Y645264D01*
X1328991Y653351D01*
X1328081Y654654D01*
X1326108Y655001D01*
X1324805Y654091D01*
X1323167Y644831D01*
X1322645Y644466D01*
X1321611Y644648D01*
X1321247Y645170D01*
X1322724Y653548D01*
X1321787Y654890D01*
X1319879Y655225D01*
X1318539Y654286D01*
X1316873Y644830D01*
X1316351Y644466D01*
X1315316Y644648D01*
X1314951Y645170D01*
X1316437Y653594D01*
X1315526Y654901D01*
X1313555Y655245D01*
X1312249Y654336D01*
X1310583Y644863D01*
X1310061Y644499D01*
X1309026Y644681D01*
X1308661Y645203D01*
X1310139Y653578D01*
X1309228Y654882D01*
X1307257Y655229D01*
X1305955Y654319D01*
X1304286Y644863D01*
X1303764Y644499D01*
X1302730Y644680D01*
X1302366Y645201D01*
X1303843Y653577D01*
X1302933Y654882D01*
X1300959Y655228D01*
X1299656Y654314D01*
X1297988Y644845D01*
X1297466Y644480D01*
X1296432Y644663D01*
X1296069Y645185D01*
X1297569Y653692D01*
X1296657Y654993D01*
X1294683Y655342D01*
X1293380Y654426D01*
X1291690Y644845D01*
X1291170Y644481D01*
X1290136Y644663D01*
X1289772Y645184D01*
X1291272Y653695D01*
X1290357Y654995D01*
X1288388Y655340D01*
X1287085Y654431D01*
X1285402Y644879D01*
X1284879Y644514D01*
X1283845Y644696D01*
X1283481Y645217D01*
X1284972Y653673D01*
X1284060Y654977D01*
X1282088Y655322D01*
X1280785Y654412D01*
X1279107Y644878D01*
X1278584Y644513D01*
X1277549Y644695D01*
X1277185Y645216D01*
X1278677Y653669D01*
X1277768Y654974D01*
X1275794Y655322D01*
X1274490Y654408D01*
X1272806Y644858D01*
X1272287Y644495D01*
X1271253Y644678D01*
X1270886Y645202D01*
X1272370Y653608D01*
X1271459Y654912D01*
X1269485Y655259D01*
X1268183Y654347D01*
X1267772Y652010D01*
X1267595Y651314D01*
X1266973Y650484D01*
X1263869Y649497D01*
X1259594Y649839D01*
X1257806D01*
X1255381Y652264D01*
G01X1472000Y449997D02*
X1471275Y449272D01*
Y446275D01*
X1475925Y441625D01*
X1477990Y437445D01*
X1477439Y435490D01*
X1478448Y432436D01*
X1478449D01*
X1478028Y430727D01*
X1478026D01*
X1478506Y429344D01*
X1477180Y422808D01*
X1475018Y418266D01*
X1470655Y416887D01*
X1467947Y417413D01*
X1465991Y416686D01*
X1462285Y413489D01*
X1458392Y401899D01*
X1455335Y398153D01*
X1454712Y394962D01*
X1455580Y390570D01*
X1454941Y387428D01*
X1455276Y385785D01*
X1454666Y382790D01*
X1455593Y378236D01*
X1454538Y376243D01*
X1455460Y371732D01*
X1449396Y362827D01*
Y362826D01*
X1442324Y352439D01*
X1441087Y346852D01*
X1441917Y342656D01*
X1436515Y315362D01*
X1434864Y313148D01*
X1434863Y313146D01*
X1433257Y305034D01*
X1434082Y300869D01*
X1431091Y293475D01*
X1425238Y289112D01*
X1425235Y289111D01*
X1418496Y287779D01*
X1416495Y288175D01*
X1414530Y287786D01*
X1412611Y288166D01*
X1410599Y287768D01*
X1408641Y288156D01*
X1406725Y287777D01*
X1404762Y288167D01*
X1404761D01*
X1402902Y287800D01*
X1400939Y288186D01*
X1398878Y287779D01*
X1396916Y288166D01*
X1394865Y287760D01*
X1392964Y288136D01*
X1391088Y287766D01*
X1389068Y288165D01*
X1381161Y286605D01*
X1355239Y294527D01*
X1351430Y296596D01*
X1346053D01*
X1344350Y298299D01*
Y315650D01*
X1343400Y316600D01*
X1341825D01*
X1341375Y316150D01*
Y314675D01*
G01X1469400Y449997D02*
X1470125Y449272D01*
Y445798D01*
X1474977Y440945D01*
X1476763Y437332D01*
X1476236Y435463D01*
X1477252Y432390D01*
X1476828Y430671D01*
X1477316Y429264D01*
X1476081Y423175D01*
X1474194Y419213D01*
X1470587Y418072D01*
X1467849Y418604D01*
X1465396Y417692D01*
X1461295Y414154D01*
X1457368Y402464D01*
X1454261Y398657D01*
X1453539Y394961D01*
X1454407Y390573D01*
X1453767Y387428D01*
X1454102Y385785D01*
X1453492Y382790D01*
X1454383Y378410D01*
X1453328Y376417D01*
X1454235Y371978D01*
X1448445Y363474D01*
X1447542Y363303D01*
X1446782Y362187D01*
X1446954Y361284D01*
X1446194Y360168D01*
X1445291Y359997D01*
X1444531Y358881D01*
X1444703Y357978D01*
X1443943Y356862D01*
X1443040Y356691D01*
X1442280Y355575D01*
X1442451Y354672D01*
X1441248Y352904D01*
X1439912Y346865D01*
X1440744Y342656D01*
X1435437Y315841D01*
X1433786Y313627D01*
X1433784Y313620D01*
X1432084Y305031D01*
X1432085D01*
X1432887Y300982D01*
X1430145Y294205D01*
X1424759Y290190D01*
X1418496Y288952D01*
X1416495Y289348D01*
X1414530Y288959D01*
X1412611Y289339D01*
X1410599Y288941D01*
X1408641Y289329D01*
X1406725Y288950D01*
X1404762Y289340D01*
X1402902Y288973D01*
X1400940Y289359D01*
X1398878Y288952D01*
X1396916Y289339D01*
X1394865Y288933D01*
X1392964Y289309D01*
X1391088Y288939D01*
X1389068Y289338D01*
X1381221Y287790D01*
X1355686Y295593D01*
X1351723Y297746D01*
X1346530D01*
X1345500Y298776D01*
Y316127D01*
X1343877Y317750D01*
X1341825D01*
X1341375Y318200D01*
Y319675D01*
G01X1464200Y449997D02*
X1463506Y449303D01*
Y447794D01*
X1468920Y442380D01*
X1471784Y436396D01*
X1475018Y434691D01*
X1475796Y432334D01*
X1475369Y430604D01*
X1475868Y429167D01*
X1475660Y428137D01*
X1475659Y428136D01*
X1475455Y427129D01*
X1473981Y425361D01*
X1463859Y422943D01*
X1460552Y421015D01*
X1458316Y409686D01*
X1456095Y403071D01*
X1452850Y399094D01*
X1452026Y395490D01*
X1452981Y390557D01*
X1452333Y387379D01*
X1452665Y385746D01*
X1452049Y382720D01*
X1452727Y379392D01*
X1452724Y379386D01*
X1451465Y377007D01*
X1452146Y373667D01*
X1440253Y356194D01*
Y356193D01*
X1438281Y347661D01*
X1439295Y342537D01*
X1434127Y316427D01*
Y316428D01*
X1432475Y314211D01*
X1430658Y305031D01*
X1431432Y301120D01*
X1428995Y295093D01*
X1424179Y291501D01*
X1424178Y291502D01*
X1418496Y290379D01*
X1416495Y290775D01*
X1414530Y290386D01*
X1412611Y290766D01*
X1410599Y290368D01*
X1408641Y290756D01*
X1406726Y290377D01*
X1404764Y290766D01*
X1402902Y290398D01*
X1400940Y290786D01*
X1398878Y290378D01*
X1396916Y290766D01*
X1394865Y290360D01*
X1392965Y290736D01*
X1391088Y290366D01*
X1389068Y290765D01*
X1381295Y289231D01*
X1358562Y296178D01*
X1355497Y299244D01*
Y316375D01*
X1353156Y318716D01*
X1350414D01*
X1349134Y317436D01*
G01X1460391Y445071D02*
X1461538Y443924D01*
Y441898D01*
X1460925Y438876D01*
X1457414Y433978D01*
X1457186Y432824D01*
X1457580Y430838D01*
X1457191Y428876D01*
X1457574Y426938D01*
X1457187Y424977D01*
X1457962Y421057D01*
X1455856Y410395D01*
X1451911Y407749D01*
X1448395Y402535D01*
X1447230Y401370D01*
X1442564Y398282D01*
X1442000Y397431D01*
X1439064Y382616D01*
X1440645Y374631D01*
Y374451D01*
X1440600Y374406D01*
X1434893Y345563D01*
X1436094Y339497D01*
X1431737Y317486D01*
X1430084Y315267D01*
X1428058Y305031D01*
X1428783Y301371D01*
X1426898Y296711D01*
X1423115Y293891D01*
X1418498Y292978D01*
X1416535Y293366D01*
X1414573Y292978D01*
X1412611Y293366D01*
X1410599Y292968D01*
X1408641Y293356D01*
X1406726Y292977D01*
X1404764Y293365D01*
X1402902Y292997D01*
X1400940Y293385D01*
X1398878Y292977D01*
X1396916Y293365D01*
X1394865Y292959D01*
X1392902Y293347D01*
X1391030Y292977D01*
X1389068Y293365D01*
X1383538Y292273D01*
X1376526Y294416D01*
Y294417D01*
X1369514Y296559D01*
X1366238Y299836D01*
Y311336D01*
X1365450Y312124D01*
Y315451D01*
X1364551Y316350D01*
X1361619D01*
X1360294Y315025D01*
G01X1456600Y454100D02*
X1455892Y453392D01*
Y452035D01*
X1454519Y450662D01*
X1453852Y448315D01*
X1455363Y440671D01*
X1454587Y436747D01*
X1454975Y434785D01*
X1454587Y432824D01*
X1454980Y430838D01*
X1454592Y428876D01*
X1454975Y426938D01*
X1454587Y424976D01*
X1455364Y421052D01*
X1453558Y411926D01*
X1449205Y409000D01*
X1446279Y404662D01*
X1442442Y402075D01*
X1438069Y396862D01*
X1435117Y381951D01*
X1436705Y373924D01*
X1431693Y348598D01*
X1433494Y339497D01*
X1429349Y318549D01*
X1429344Y318542D01*
X1427696Y316331D01*
X1425459Y305031D01*
X1426134Y301622D01*
X1424802Y298329D01*
X1422056Y296282D01*
X1418496Y295578D01*
X1416535Y295965D01*
X1414573Y295577D01*
X1412611Y295965D01*
X1410649Y295577D01*
X1408688Y295965D01*
X1406726Y295577D01*
X1404764Y295965D01*
X1402902Y295597D01*
X1400940Y295985D01*
X1398878Y295577D01*
X1396916Y295965D01*
X1394865Y295559D01*
X1392902Y295947D01*
X1391030Y295577D01*
X1389068Y295965D01*
X1386867Y295530D01*
X1380664Y296756D01*
X1379134Y297487D01*
X1377104Y299542D01*
Y313207D01*
X1373591Y316720D01*
X1372415D01*
X1371090Y315395D01*
G01X1380904Y315947D02*
X1382207Y317250D01*
X1384628D01*
X1386323Y315555D01*
Y313581D01*
X1388587Y311317D01*
Y299987D01*
X1389771Y298803D01*
X1391541Y298278D01*
X1392992Y298565D01*
X1394954Y298177D01*
X1396916Y298565D01*
X1398878Y298177D01*
X1400840Y298565D01*
X1402802Y298177D01*
X1404764Y298565D01*
X1406726Y298177D01*
X1408688Y298565D01*
X1410649Y298177D01*
X1412611Y298565D01*
X1414573Y298177D01*
X1416535Y298565D01*
X1418496Y298177D01*
X1420995Y298672D01*
X1422706Y299947D01*
X1423485Y301873D01*
X1422860Y305031D01*
X1425307Y317392D01*
X1426958Y319608D01*
X1430895Y339497D01*
X1428698Y350599D01*
X1433710Y375926D01*
X1432024Y384443D01*
X1437725Y413270D01*
X1439661Y414804D01*
X1447643Y412946D01*
X1451419Y414255D01*
X1452764Y421051D01*
X1451987Y424976D01*
X1452376Y426938D01*
X1452008Y428800D01*
X1452007D01*
X1452395Y430762D01*
X1451978Y432872D01*
X1452366Y434832D01*
X1451987Y436749D01*
X1452017Y436900D01*
X1452764Y440668D01*
X1450715Y451031D01*
X1448725Y453021D01*
Y453961D01*
X1449045Y454281D01*
G01X1392226Y315658D02*
X1390834Y317050D01*
X1388423D01*
X1386529Y318944D01*
Y321656D01*
X1388023Y323150D01*
X1393256D01*
X1396237Y320169D01*
Y314114D01*
X1396601Y313750D01*
X1414817D01*
X1423837Y322771D01*
X1427134Y339434D01*
X1424584Y352314D01*
X1429598Y377645D01*
X1427671Y387387D01*
X1432820Y413409D01*
X1432342Y415825D01*
X1432730Y417787D01*
X1432342Y419749D01*
X1432717Y421642D01*
X1432329Y423604D01*
X1432737Y425674D01*
X1435398Y430967D01*
X1438395Y432491D01*
X1438396D01*
X1441450Y437322D01*
Y456760D01*
X1443103Y458414D01*
G01X1464400Y465500D02*
Y466882D01*
X1463675Y467607D01*
Y469344D01*
X1459793Y473226D01*
X1445353D01*
X1436350Y464223D01*
Y438787D01*
X1435157Y436900D01*
X1434845Y436407D01*
X1431267Y434587D01*
X1428427Y430168D01*
X1427142Y423672D01*
X1427521Y421757D01*
X1427133Y419799D01*
X1427531Y417787D01*
X1427143Y415825D01*
X1427458Y414235D01*
X1422306Y388219D01*
X1424399Y377644D01*
X1419074Y350740D01*
X1421611Y337919D01*
X1419529Y327400D01*
X1416178Y324049D01*
X1409122D01*
X1403903Y318830D01*
X1401885D01*
X1400558Y320157D01*
G01X1461600Y449997D02*
X1462356Y449241D01*
Y447317D01*
X1467967Y441706D01*
X1469184Y439164D01*
X1468878Y438297D01*
X1469461Y437079D01*
X1470328Y436774D01*
X1470911Y435556D01*
X1474071Y433890D01*
X1474600Y432288D01*
X1474170Y430549D01*
X1474678Y429087D01*
X1474385Y427643D01*
X1473342Y426391D01*
X1471496Y425950D01*
X1470664Y426461D01*
X1469303Y426136D01*
X1468792Y425304D01*
X1467430Y424979D01*
X1466646Y425460D01*
X1465333Y425147D01*
X1464852Y424364D01*
X1463429Y424024D01*
X1459524Y421747D01*
X1457202Y409982D01*
X1455071Y403636D01*
X1451788Y399613D01*
X1450850Y395510D01*
X1451808Y390563D01*
X1451159Y387379D01*
X1451491Y385746D01*
X1450875Y382720D01*
X1451517Y379566D01*
X1450255Y377181D01*
X1450922Y373913D01*
X1439181Y356663D01*
X1437104Y347680D01*
X1438122Y342537D01*
X1433049Y316906D01*
X1433048D01*
X1431397Y314690D01*
X1429485Y305033D01*
X1430237Y301233D01*
X1428049Y295823D01*
X1423702Y292581D01*
X1418496Y291552D01*
X1416495Y291948D01*
X1414531Y291559D01*
X1412611Y291939D01*
X1410599Y291541D01*
X1408641Y291929D01*
X1406726Y291550D01*
X1404764Y291939D01*
X1402902Y291571D01*
X1400940Y291959D01*
X1398878Y291551D01*
X1396916Y291939D01*
X1394865Y291533D01*
X1392966Y291909D01*
X1391088Y291539D01*
X1389068Y291938D01*
X1381355Y290416D01*
X1359173Y297195D01*
X1356647Y299721D01*
Y316852D01*
X1353633Y319866D01*
X1350413D01*
X1349134Y321145D01*
G01X1459578Y444257D02*
X1460388Y443447D01*
Y442014D01*
X1459846Y439346D01*
X1456333Y434444D01*
X1456013Y432824D01*
X1456407Y430838D01*
X1456018Y428876D01*
X1456401Y426938D01*
X1456014Y424976D01*
X1456789Y421057D01*
X1454820Y411085D01*
X1451083Y408579D01*
X1450956Y408392D01*
X1450957D01*
X1447503Y403270D01*
X1447502D01*
X1446498Y402266D01*
X1441734Y399112D01*
X1440915Y397878D01*
X1439477Y390620D01*
X1438666Y390078D01*
X1438404Y388753D01*
X1438946Y387942D01*
X1438684Y386618D01*
X1437873Y386075D01*
X1437611Y384751D01*
X1438153Y383940D01*
X1437891Y382616D01*
X1439472Y374630D01*
X1436150Y357842D01*
X1435386Y357331D01*
X1435124Y356007D01*
X1435635Y355243D01*
X1435373Y353918D01*
X1434609Y353407D01*
X1434347Y352083D01*
X1434859Y351319D01*
X1434597Y349995D01*
X1433833Y349483D01*
X1433571Y348159D01*
X1434082Y347395D01*
X1433720Y345563D01*
X1434921Y339497D01*
X1430659Y317964D01*
X1429007Y315748D01*
Y315747D01*
X1429006Y315745D01*
X1426885Y305031D01*
X1427588Y301484D01*
X1425952Y297441D01*
X1422636Y294969D01*
X1418498Y294151D01*
X1416535Y294539D01*
X1414573Y294151D01*
X1412611Y294539D01*
X1410599Y294141D01*
X1408641Y294529D01*
X1406726Y294150D01*
X1404764Y294538D01*
X1402902Y294170D01*
X1400940Y294558D01*
X1398878Y294150D01*
X1396916Y294538D01*
X1394865Y294132D01*
X1392902Y294520D01*
X1391030Y294150D01*
X1389068Y294538D01*
X1383598Y293458D01*
X1370125Y297576D01*
X1367388Y300313D01*
Y311813D01*
X1366600Y312601D01*
Y315928D01*
X1365028Y317500D01*
X1361619D01*
X1360294Y318825D01*
G01X1454000Y454100D02*
X1454742Y453358D01*
Y452512D01*
X1453494Y451264D01*
X1452670Y448363D01*
X1454190Y440671D01*
X1453414Y436747D01*
X1453802Y434785D01*
X1453414Y432824D01*
Y432822D01*
X1453807Y430838D01*
X1453419Y428876D01*
X1453802Y426938D01*
X1453414Y424976D01*
X1454191Y421052D01*
X1452521Y412616D01*
X1448376Y409830D01*
X1445450Y405491D01*
X1441664Y402939D01*
X1436998Y397375D01*
X1433944Y381951D01*
X1435532Y373924D01*
X1433716Y364752D01*
X1432953Y364240D01*
X1432691Y362916D01*
X1433202Y362152D01*
X1432940Y360828D01*
X1432176Y360316D01*
X1431914Y358992D01*
X1432426Y358228D01*
X1432164Y356904D01*
X1431400Y356392D01*
X1431138Y355068D01*
X1431649Y354304D01*
X1431387Y352980D01*
X1430623Y352468D01*
X1430361Y351144D01*
X1430873Y350380D01*
X1430520Y348598D01*
X1432321Y339497D01*
X1428271Y319027D01*
X1428270D01*
X1426618Y316810D01*
X1424286Y305031D01*
X1424939Y301735D01*
X1423856Y299059D01*
X1421577Y297360D01*
X1418496Y296751D01*
X1416535Y297138D01*
X1414573Y296750D01*
X1412611Y297138D01*
X1410649Y296750D01*
X1408688Y297138D01*
X1406726Y296750D01*
X1404764Y297138D01*
X1402902Y296770D01*
X1400940Y297158D01*
X1398878Y296750D01*
X1396916Y297138D01*
X1394865Y296732D01*
X1392902Y297120D01*
X1391030Y296750D01*
X1389068Y297138D01*
X1386867Y296703D01*
X1381029Y297857D01*
X1379811Y298439D01*
X1378254Y300015D01*
Y313684D01*
X1374068Y317870D01*
X1372415D01*
X1371090Y319195D01*
G01X1380904Y319747D02*
X1382251Y318400D01*
X1385105D01*
X1387473Y316032D01*
Y314058D01*
X1389737Y311794D01*
Y300464D01*
X1390378Y299823D01*
X1391596Y299462D01*
X1392992Y299738D01*
X1394954Y299350D01*
X1396916Y299738D01*
X1398878Y299350D01*
X1400840Y299738D01*
X1402802Y299350D01*
X1404764Y299738D01*
X1406726Y299350D01*
X1408688Y299738D01*
X1410649Y299350D01*
X1412611Y299738D01*
X1414573Y299350D01*
X1416535Y299738D01*
X1418496Y299350D01*
X1420516Y299750D01*
X1421760Y300677D01*
X1422290Y301986D01*
X1421687Y305031D01*
X1424229Y317871D01*
Y317870D01*
X1425879Y320085D01*
X1429722Y339497D01*
X1427525Y350599D01*
X1432537Y375926D01*
X1430851Y384443D01*
X1436678Y413909D01*
X1439381Y416051D01*
X1447580Y414142D01*
X1450419Y415126D01*
X1451591Y421051D01*
X1450814Y424976D01*
X1451203Y426938D01*
X1450835Y428800D01*
X1450834D01*
X1451222Y430762D01*
X1450805Y432872D01*
Y432874D01*
X1451193Y434832D01*
X1450814Y436748D01*
X1451591Y440668D01*
X1451117Y443066D01*
X1450353Y443578D01*
X1450091Y444902D01*
X1450603Y445666D01*
X1450341Y446990D01*
X1449577Y447502D01*
X1449315Y448826D01*
X1449827Y449590D01*
X1449654Y450465D01*
X1447575Y452544D01*
Y454438D01*
X1448231Y455094D01*
Y455095D01*
X1448232Y455096D01*
G01X1392226Y319458D02*
X1390968Y318200D01*
X1388900D01*
X1387679Y319421D01*
Y321179D01*
X1388500Y322000D01*
X1392779D01*
X1395087Y319692D01*
Y313637D01*
X1396124Y312600D01*
X1415294D01*
X1416935Y314241D01*
X1417855D01*
X1418809Y315196D01*
Y316115D01*
X1419764Y317070D01*
X1420683D01*
X1421638Y318024D01*
Y318944D01*
X1424898Y322204D01*
X1428307Y339434D01*
X1425758Y352318D01*
X1430771Y377645D01*
X1428844Y387387D01*
X1429351Y389950D01*
X1430115Y390461D01*
X1430377Y391785D01*
X1429866Y392549D01*
X1430128Y393874D01*
X1430891Y394385D01*
X1431153Y395709D01*
X1430642Y396473D01*
X1433993Y413409D01*
X1433515Y415825D01*
X1433903Y417787D01*
X1433515Y419749D01*
X1433890Y421642D01*
X1433502Y423604D01*
X1433836Y425297D01*
X1436256Y430113D01*
X1439199Y431609D01*
X1440462Y433606D01*
Y433607D01*
X1441359Y433809D01*
X1442081Y434950D01*
X1441879Y435847D01*
X1442600Y436988D01*
Y456283D01*
X1443917Y457601D01*
G01X1461800Y465500D02*
Y466834D01*
X1462525Y467559D01*
Y468867D01*
X1459316Y472076D01*
X1457966D01*
X1457316Y471426D01*
X1455966D01*
X1455316Y472076D01*
X1453966D01*
X1453316Y471426D01*
X1451966D01*
X1451316Y472076D01*
X1445830D01*
X1444875Y471121D01*
Y470202D01*
X1443921Y469248D01*
X1443002D01*
X1442047Y468293D01*
Y467374D01*
X1441092Y466419D01*
X1440173D01*
X1437500Y463746D01*
Y438453D01*
X1436518Y436900D01*
X1435648Y435525D01*
X1432066Y433703D01*
X1429513Y429730D01*
X1428315Y423672D01*
X1428694Y421757D01*
X1428306Y419799D01*
X1428704Y417787D01*
X1428316Y415825D01*
X1428631Y414235D01*
X1423479Y388219D01*
X1425572Y377644D01*
X1420247Y350740D01*
X1422784Y337919D01*
X1420590Y326834D01*
X1416655Y322899D01*
X1409599D01*
X1404380Y317680D01*
X1401881D01*
X1400558Y316357D01*
G01X1377028Y458125D02*
X1375546D01*
X1375096Y457675D01*
Y456042D01*
X1373673Y454619D01*
X1367797D01*
X1366255Y456161D01*
Y477000D01*
X1373953Y484698D01*
Y497641D01*
X1387535Y511223D01*
X1394700D01*
X1396883Y513406D01*
X1401373D01*
X1416517Y528550D01*
X1434007D01*
X1435755Y530298D01*
Y547330D01*
X1440882Y552457D01*
X1457869D01*
X1459671Y550655D01*
X1514137D01*
X1515628Y549164D01*
X1545349D01*
X1549129Y552944D01*
X1565204D01*
X1569343Y557083D01*
X1582429D01*
X1584490Y559144D01*
X1599104D01*
X1609647Y554774D01*
X1610281D01*
X1617447Y551805D01*
X1655284D01*
X1657904Y554425D01*
X1707960D01*
X1715085Y547300D01*
X1726397D01*
X1729992Y543705D01*
X1745978D01*
X1748373Y546100D01*
X1761408D01*
X1769714Y537794D01*
X1776994D01*
X1783650Y544450D01*
X1785050D01*
X1791100Y550500D01*
Y554500D01*
X1792500Y555900D01*
X1799973D01*
X1804650Y560577D01*
Y571077D01*
X1805773Y572200D01*
X1807132D01*
X1808057Y573125D01*
G01X1372028Y458125D02*
X1373496D01*
X1373946Y457675D01*
Y456519D01*
X1373196Y455769D01*
X1368274D01*
X1367405Y456638D01*
Y476523D01*
X1375103Y484221D01*
Y497164D01*
X1388012Y510073D01*
X1395177D01*
X1397360Y512256D01*
X1401850D01*
X1416994Y527400D01*
X1434484D01*
X1436905Y529821D01*
Y546853D01*
X1441359Y551307D01*
X1457392D01*
X1459194Y549505D01*
X1513660D01*
X1515151Y548014D01*
X1545826D01*
X1549606Y551794D01*
X1565681D01*
X1569820Y555933D01*
X1582906D01*
X1584967Y557994D01*
X1598875D01*
X1609418Y553624D01*
X1610052D01*
X1617218Y550655D01*
X1655761D01*
X1658381Y553275D01*
X1699483D01*
X1700133Y552625D01*
X1701483D01*
X1702133Y553275D01*
X1703483D01*
X1704133Y552625D01*
X1705483D01*
X1706133Y553275D01*
X1707483D01*
X1714608Y546150D01*
X1725920D01*
X1729515Y542555D01*
X1738021D01*
X1738671Y541905D01*
X1740021D01*
X1740671Y542555D01*
X1742021D01*
X1742671Y541905D01*
X1744021D01*
X1744671Y542555D01*
X1746455D01*
X1748850Y544950D01*
X1760931D01*
X1763581Y542300D01*
Y541381D01*
X1764535Y540427D01*
X1765454D01*
X1766409Y539472D01*
Y538553D01*
X1767363Y537599D01*
X1768282D01*
X1769237Y536644D01*
X1777471D01*
X1784127Y543300D01*
X1785527D01*
X1792250Y550023D01*
Y554023D01*
X1792977Y554750D01*
X1796450D01*
X1797100Y554100D01*
X1798450D01*
X1799100Y554750D01*
X1800450D01*
X1802972Y557272D01*
X1803891D01*
X1804845Y558226D01*
Y559145D01*
X1805800Y560100D01*
Y561450D01*
X1806450Y562100D01*
Y563450D01*
X1805800Y564100D01*
Y566600D01*
X1806450Y567250D01*
Y568600D01*
X1805800Y569250D01*
Y570600D01*
X1806250Y571050D01*
X1807132D01*
X1808057Y570125D01*
G01X1784525Y488930D02*
X1786000D01*
X1786450Y488480D01*
Y488046D01*
X1785121Y486719D01*
X1782477D01*
X1779411Y487990D01*
X1776780Y490619D01*
X1775533Y491136D01*
X1775181Y491985D01*
X1773934Y492502D01*
X1773085Y492150D01*
X1770311Y493300D01*
X1765298D01*
X1761887Y491886D01*
X1761725Y491724D01*
Y491725D01*
X1759452Y489452D01*
X1757685Y485186D01*
X1755350Y482850D01*
X1744977D01*
X1731818Y485463D01*
X1730571Y485980D01*
X1730219Y486829D01*
X1728972Y487346D01*
X1728123Y486995D01*
X1726876Y487512D01*
X1726524Y488361D01*
X1725277Y488878D01*
X1724428Y488527D01*
X1715425Y492258D01*
X1710816Y498659D01*
X1708924Y503222D01*
X1706449Y505104D01*
X1702931Y505920D01*
X1698817Y505073D01*
X1693523Y506468D01*
X1688457Y509166D01*
X1685587Y513157D01*
X1682214Y514596D01*
X1675769Y513239D01*
X1663779Y516747D01*
X1655474Y523096D01*
X1648369Y534243D01*
X1645146Y536062D01*
X1637631Y537631D01*
X1628605Y534640D01*
X1628604D01*
X1613803Y537428D01*
X1606711Y542504D01*
X1596089Y544627D01*
X1508992Y527309D01*
X1503666Y528599D01*
X1499759Y527491D01*
X1495448Y528824D01*
X1490633Y527434D01*
X1484943Y528497D01*
X1480364Y527222D01*
X1476706Y524331D01*
X1474110Y523828D01*
X1465520Y520875D01*
X1460740Y521941D01*
X1456953Y521103D01*
X1423850Y507991D01*
X1407844Y497886D01*
X1405099Y490521D01*
X1406979Y482407D01*
X1405959Y477760D01*
X1415873Y458636D01*
Y452773D01*
X1413600Y450500D01*
X1401372D01*
X1396250Y445378D01*
Y440150D01*
X1399500Y436900D01*
X1404500D01*
X1405623Y435777D01*
Y433751D01*
X1404722Y432850D01*
X1401848D01*
X1401398Y433300D01*
Y434775D01*
G01X1395375Y457561D02*
Y456650D01*
X1394925Y456200D01*
X1393996D01*
X1393334Y456862D01*
Y459037D01*
X1396097Y464259D01*
X1398205Y473853D01*
X1395739Y484506D01*
X1402678Y503119D01*
X1403915Y503900D01*
X1404811Y503697D01*
X1405953Y504418D01*
X1406155Y505314D01*
X1407297Y506035D01*
X1408193Y505833D01*
X1409335Y506554D01*
X1409538Y507450D01*
X1410679Y508171D01*
X1411576Y507969D01*
X1412717Y508690D01*
X1412920Y509586D01*
X1414061Y510307D01*
X1414958Y510105D01*
X1416099Y510826D01*
X1416302Y511722D01*
X1417443Y512443D01*
X1440758Y521678D01*
X1446570Y529389D01*
X1449801Y536294D01*
X1452128Y538041D01*
X1454880Y538628D01*
X1460029Y536585D01*
X1467607Y538174D01*
X1475970Y542927D01*
X1482563Y544594D01*
X1485594Y543742D01*
X1490299Y540286D01*
X1495842Y539019D01*
X1500683Y540091D01*
X1505912Y538446D01*
X1511691Y539595D01*
X1520341Y537122D01*
X1529997Y539042D01*
X1530761Y538532D01*
X1532085Y538795D01*
X1532596Y539559D01*
X1533920Y539822D01*
X1534684Y539312D01*
X1536008Y539575D01*
X1536519Y540339D01*
X1537843Y540602D01*
X1538607Y540092D01*
X1539931Y540355D01*
X1540442Y541119D01*
X1541766Y541382D01*
X1542530Y540872D01*
X1543854Y541135D01*
X1544365Y541899D01*
X1594127Y551797D01*
X1609322Y548756D01*
X1616661Y543505D01*
X1627881Y541392D01*
X1627883Y541391D01*
X1628029Y541364D01*
X1628176Y541336D01*
X1637262Y544347D01*
X1647552Y542200D01*
X1652945Y539155D01*
X1660346Y527544D01*
X1666748Y522650D01*
X1675890Y519975D01*
X1682774Y521427D01*
X1695088Y516172D01*
X1704240Y518006D01*
X1711484Y515591D01*
X1712814Y515820D01*
X1713565Y515290D01*
X1714896Y515520D01*
X1715426Y516271D01*
X1720282Y517108D01*
X1726414Y514970D01*
X1726931Y513723D01*
X1726580Y512874D01*
X1727097Y511627D01*
X1727947Y511275D01*
X1728464Y510028D01*
X1728113Y509179D01*
X1728630Y507932D01*
X1729479Y507580D01*
X1730600Y504878D01*
Y501300D01*
X1729385Y500085D01*
X1728639D01*
G01X1743125Y496400D02*
X1744800D01*
X1745300Y495900D01*
Y495130D01*
X1744270Y494100D01*
X1727307D01*
X1722641Y495028D01*
X1718470Y496757D01*
X1715303Y501155D01*
X1712860Y507047D01*
X1709143Y509872D01*
X1703446Y511193D01*
X1699044Y510288D01*
X1695397Y511249D01*
X1691904Y513110D01*
X1688898Y517291D01*
X1682562Y519992D01*
X1675743Y518559D01*
X1666121Y521375D01*
X1659289Y526600D01*
X1651985Y538058D01*
X1646937Y540908D01*
X1637347Y542909D01*
X1628258Y539897D01*
X1616041Y542196D01*
X1608689Y547458D01*
X1596011Y549992D01*
X1521845Y535236D01*
X1511660Y538147D01*
X1505906Y537002D01*
X1500662Y538653D01*
X1495708Y537555D01*
X1489820Y538901D01*
X1484969Y542464D01*
X1482471Y543166D01*
X1476614Y541682D01*
X1468109Y536850D01*
X1459880Y535123D01*
X1454734Y537165D01*
X1452722Y536736D01*
X1450921Y535384D01*
X1447774Y528658D01*
X1441640Y520522D01*
X1421376Y512496D01*
X1403384Y501136D01*
X1399707Y491270D01*
X1401758Y482411D01*
X1399600Y472587D01*
Y456272D01*
X1400886Y454986D01*
X1402325D01*
X1402775Y454536D01*
Y453561D01*
G01X1789525Y488930D02*
X1788050D01*
X1787600Y488480D01*
Y487569D01*
X1785598Y485569D01*
X1782248D01*
X1778758Y487014D01*
X1776128Y489644D01*
X1770081Y492150D01*
X1765527D01*
X1762539Y490911D01*
X1760429Y488801D01*
X1758661Y484534D01*
X1755827Y481700D01*
X1744863D01*
X1731482Y484356D01*
X1714682Y491320D01*
X1709804Y498095D01*
X1707980Y502494D01*
X1705949Y504039D01*
X1702916Y504742D01*
X1698785Y503892D01*
X1693100Y505389D01*
X1687679Y508276D01*
X1684840Y512224D01*
X1682096Y513395D01*
X1675723Y512054D01*
X1663251Y515703D01*
X1654613Y522305D01*
X1647551Y533384D01*
X1644739Y534971D01*
X1637699Y536441D01*
X1628684Y533454D01*
X1613340Y536344D01*
X1606243Y541424D01*
X1596088Y543454D01*
X1508969Y526131D01*
X1503691Y527409D01*
X1499745Y526291D01*
X1495437Y527623D01*
X1490690Y526253D01*
X1484994Y527317D01*
X1480896Y526175D01*
X1477199Y523254D01*
X1474423Y522717D01*
X1465587Y519681D01*
X1460739Y520762D01*
X1457291Y519999D01*
X1424373Y506961D01*
X1408786Y497119D01*
X1406298Y490443D01*
X1408158Y482414D01*
X1407172Y477920D01*
X1417023Y458917D01*
Y452296D01*
X1414077Y449350D01*
X1401849D01*
X1397400Y444901D01*
Y440627D01*
X1399977Y438050D01*
X1404977D01*
X1406773Y436254D01*
Y433274D01*
X1405199Y431700D01*
X1401848D01*
X1401398Y431250D01*
Y429775D01*
G01X1395375Y453561D02*
Y454599D01*
X1394924Y455050D01*
X1393519D01*
X1392184Y456385D01*
Y459323D01*
X1395007Y464659D01*
X1397026Y473846D01*
X1394540Y484584D01*
X1401735Y503885D01*
X1416920Y513473D01*
X1440034Y522629D01*
X1445579Y529985D01*
X1448880Y537042D01*
X1451640Y539113D01*
X1454981Y539826D01*
X1460132Y537782D01*
X1467195Y539263D01*
X1475537Y544004D01*
X1482579Y545785D01*
X1486106Y544793D01*
X1490788Y541354D01*
X1495846Y540198D01*
X1500735Y541281D01*
X1505976Y539632D01*
X1511740Y540778D01*
X1520390Y538305D01*
X1594128Y552970D01*
X1609791Y549836D01*
X1617124Y544589D01*
X1628096Y542522D01*
X1628097D01*
X1637194Y545536D01*
X1647962Y543290D01*
X1653761Y540016D01*
X1661207Y528335D01*
X1667276Y523694D01*
X1675936Y521161D01*
X1682892Y522628D01*
X1695211Y517370D01*
X1704314Y519194D01*
X1711574Y516774D01*
X1720380Y518292D01*
X1727280Y515887D01*
X1731750Y505108D01*
Y501300D01*
X1732965Y500085D01*
X1733639D01*
G01X1748125Y496400D02*
X1747100D01*
X1746450Y495750D01*
Y494653D01*
X1744747Y492950D01*
X1727193D01*
X1722305Y493922D01*
X1717728Y495818D01*
X1714291Y500591D01*
X1711916Y506319D01*
X1708643Y508807D01*
X1703431Y510015D01*
X1699012Y509107D01*
X1694974Y510171D01*
X1691126Y512220D01*
X1688151Y516358D01*
X1682444Y518792D01*
X1675697Y517374D01*
X1665592Y520331D01*
X1658428Y525810D01*
X1651169Y537197D01*
X1646527Y539818D01*
X1637415Y541720D01*
X1628338Y538711D01*
X1615578Y541112D01*
Y541113D01*
X1608221Y546378D01*
X1596010Y548819D01*
X1521797Y534053D01*
X1511611Y536964D01*
X1505841Y535816D01*
X1500610Y537463D01*
X1495704Y536376D01*
X1489330Y537833D01*
X1484458Y541412D01*
X1482456Y541975D01*
X1477047Y540605D01*
X1468521Y535761D01*
X1459777Y533926D01*
X1454633Y535967D01*
X1453210Y535664D01*
X1451842Y534636D01*
X1448768Y528066D01*
X1447178Y525957D01*
X1447306Y525047D01*
X1446493Y523969D01*
X1445583Y523841D01*
X1444770Y522763D01*
X1444898Y521853D01*
X1444085Y520775D01*
X1443175Y520647D01*
X1442362Y519569D01*
X1421902Y511467D01*
X1421900Y511466D01*
X1404327Y500370D01*
X1400906Y491192D01*
X1402938Y482418D01*
X1400750Y472462D01*
Y467112D01*
X1401400Y466462D01*
Y465112D01*
X1400750Y464462D01*
Y463112D01*
X1401400Y462462D01*
Y461112D01*
X1400750Y460462D01*
Y456749D01*
X1401363Y456136D01*
X1402325D01*
X1402775Y456586D01*
Y457561D01*
G01X1753575Y496406D02*
X1755050D01*
X1755500Y495956D01*
Y494400D01*
X1752672Y491572D01*
X1727110D01*
X1720747Y492837D01*
Y492838D01*
X1717048Y494371D01*
X1713059Y499909D01*
X1710886Y505149D01*
X1707665Y507597D01*
X1703400Y508586D01*
X1698960Y507672D01*
X1694538Y508836D01*
X1694486Y508851D01*
X1694460Y508858D01*
X1690181Y511138D01*
X1687243Y515224D01*
X1682408Y517287D01*
X1675785Y515891D01*
Y515892D01*
X1664950Y519061D01*
X1657382Y524849D01*
X1650232Y536067D01*
X1645903Y538510D01*
X1637480Y540267D01*
Y540266D01*
X1628432Y537269D01*
X1628430Y537270D01*
Y537269D01*
X1614963Y539805D01*
X1607634Y545050D01*
X1596122Y547351D01*
X1521858Y532580D01*
X1511550Y535527D01*
X1505646Y534351D01*
X1500434Y535990D01*
X1493979Y534560D01*
X1479151Y537724D01*
X1476465Y537019D01*
X1474629Y535754D01*
X1471101Y530351D01*
X1466581Y526855D01*
X1464435Y526306D01*
X1460024Y527248D01*
X1457098Y526263D01*
X1450150Y521144D01*
X1422537Y510213D01*
X1405787Y499638D01*
X1402347Y491103D01*
X1404365Y482392D01*
X1403270Y477406D01*
X1407348Y469539D01*
Y456089D01*
X1408451Y454986D01*
X1410025D01*
X1410475Y454536D01*
Y453561D01*
G01X1758575Y496406D02*
X1757100D01*
X1756650Y495956D01*
Y493923D01*
X1753149Y490422D01*
X1726996D01*
X1720411Y491731D01*
X1716305Y493433D01*
X1712047Y499345D01*
X1709942Y504421D01*
X1707165Y506532D01*
X1703385Y507408D01*
X1698928Y506491D01*
X1694233Y507727D01*
X1694167Y507746D01*
X1694037Y507780D01*
X1693918Y507843D01*
X1693919D01*
X1689403Y510248D01*
X1686496Y514291D01*
X1682290Y516086D01*
X1675739Y514706D01*
X1664422Y518017D01*
X1656521Y524058D01*
X1649416Y535206D01*
X1645493Y537420D01*
X1637548Y539077D01*
X1628512Y536083D01*
X1614500Y538721D01*
X1607166Y543970D01*
X1596121Y546178D01*
X1521809Y531397D01*
X1519194Y532145D01*
X1518390Y531698D01*
X1517092Y532069D01*
X1516646Y532873D01*
X1515348Y533244D01*
X1514544Y532798D01*
X1513246Y533169D01*
X1512800Y533973D01*
X1511502Y534344D01*
X1505582Y533165D01*
X1500382Y534800D01*
X1493984Y533383D01*
X1493979Y533384D01*
Y533383D01*
X1492659Y533665D01*
X1491887Y533165D01*
X1490567Y533447D01*
X1490067Y534218D01*
X1488747Y534500D01*
X1487975Y534000D01*
X1486655Y534282D01*
X1486155Y535053D01*
X1479179Y536542D01*
X1476952Y535957D01*
X1475469Y534935D01*
X1471959Y529559D01*
X1467094Y525797D01*
X1464459Y525124D01*
X1460092Y526057D01*
X1457636Y525230D01*
X1450712Y520129D01*
X1423060Y509183D01*
X1406716Y498863D01*
X1403550Y491009D01*
X1405544Y482399D01*
X1404483Y477566D01*
X1408450Y469913D01*
X1408498Y469820D01*
Y456566D01*
X1408928Y456136D01*
X1410025D01*
X1410475Y456586D01*
Y457561D01*
G01X1413387Y320033D02*
X1414712Y318708D01*
X1415307D01*
X1421666Y325068D01*
X1424185Y337795D01*
X1421648Y350617D01*
X1426998Y377644D01*
X1425038Y387549D01*
X1430188Y413573D01*
X1429743Y415825D01*
X1430131Y417787D01*
X1429743Y419749D01*
X1430130Y421710D01*
X1429742Y423672D01*
X1430665Y428338D01*
X1433607Y432917D01*
X1436616Y434448D01*
X1438950Y438139D01*
Y459240D01*
X1448560Y468850D01*
X1454277D01*
X1455750Y467377D01*
Y466350D01*
X1456600Y465500D01*
G01X1413387Y316233D02*
X1414712Y317558D01*
X1415784D01*
X1422727Y324501D01*
X1425358Y337795D01*
X1424374Y342769D01*
X1424885Y343533D01*
X1424623Y344857D01*
X1423859Y345369D01*
X1423597Y346693D01*
X1424109Y347457D01*
X1423847Y348781D01*
X1423083Y349293D01*
X1422821Y350617D01*
X1428171Y377644D01*
X1426211Y387549D01*
X1431361Y413573D01*
X1430916Y415825D01*
X1431304Y417787D01*
X1430916Y419749D01*
X1431303Y421710D01*
X1430915Y423672D01*
X1431751Y427900D01*
X1434406Y432033D01*
X1437419Y433566D01*
Y433565D01*
X1440100Y437805D01*
Y458763D01*
X1443381Y462044D01*
X1444300D01*
X1445254Y462998D01*
Y463917D01*
X1446209Y464872D01*
X1447128D01*
X1448082Y465826D01*
Y466745D01*
X1449037Y467700D01*
X1453800D01*
X1454600Y466900D01*
Y466100D01*
X1454000Y465500D01*
G01X1465048Y402370D02*
X1461475Y398797D01*
Y388749D01*
X1462953Y387271D01*
X1466028D01*
X1467179Y386120D01*
X1474080D01*
X1475300Y384900D01*
Y376123D01*
X1482904Y368519D01*
X1489160D01*
X1492701Y364978D01*
Y348372D01*
X1494154Y346919D01*
X1501243D01*
X1502871Y345291D01*
X1507984D01*
X1518109Y335166D01*
X1529060D01*
X1530476Y333750D01*
X1539615D01*
X1544779Y328586D01*
X1549686D01*
X1554793Y323479D01*
X1582753D01*
X1587312Y318920D01*
X1596589D01*
X1601711Y324042D01*
X1608067D01*
X1608090Y324065D01*
X1609438D01*
X1609461Y324042D01*
X1619817D01*
X1622471Y321388D01*
X1640801D01*
X1643375Y318814D01*
Y279398D01*
X1651073Y271700D01*
X1655498D01*
X1657498Y269700D01*
G01X1468048Y402370D02*
X1466178Y400500D01*
X1464805D01*
X1462625Y398320D01*
Y389226D01*
X1463430Y388421D01*
X1466505D01*
X1467656Y387270D01*
X1474557D01*
X1476450Y385377D01*
Y376600D01*
X1483381Y369669D01*
X1489637D01*
X1493851Y365455D01*
Y348849D01*
X1494631Y348069D01*
X1501720D01*
X1503348Y346441D01*
X1508460D01*
X1516668Y338233D01*
X1518586Y336316D01*
X1529537D01*
X1530953Y334900D01*
X1540092D01*
X1545256Y329736D01*
X1550163D01*
X1555270Y324629D01*
X1583230D01*
X1587789Y320070D01*
X1596112D01*
X1601234Y325192D01*
X1607590D01*
X1607613Y325215D01*
X1609915D01*
X1609938Y325192D01*
X1620294D01*
X1622948Y322538D01*
X1641278D01*
X1644525Y319291D01*
Y279875D01*
X1651550Y272850D01*
X1655648D01*
X1657498Y274700D01*
G01X1765325Y487355D02*
X1766800D01*
X1767250Y486905D01*
Y485877D01*
X1766715Y485342D01*
X1758737Y482037D01*
X1756351Y479650D01*
X1747231D01*
X1727005Y483674D01*
X1726494Y484438D01*
X1725170Y484702D01*
X1724406Y484191D01*
X1723003Y484470D01*
X1710645Y491798D01*
X1710417Y492688D01*
X1709256Y493377D01*
X1708365Y493149D01*
X1707204Y493838D01*
X1706976Y494729D01*
X1705815Y495417D01*
X1704924Y495189D01*
X1703763Y495878D01*
X1695148Y498079D01*
X1691163Y497208D01*
X1686899Y498332D01*
X1685315Y499375D01*
X1679265Y509323D01*
X1670953Y511311D01*
X1665684Y509738D01*
Y509737D01*
X1660871Y508300D01*
X1645931D01*
X1625981Y516719D01*
X1616980Y513689D01*
X1614201Y514489D01*
X1609834Y513616D01*
X1609833D01*
X1605465Y512742D01*
X1566699Y528794D01*
X1559038Y526855D01*
X1552582Y528218D01*
X1546255Y526782D01*
X1537667Y528512D01*
X1504322Y521565D01*
X1499898Y523110D01*
X1497027Y525291D01*
X1494726Y526003D01*
X1491179Y524978D01*
X1484318Y519971D01*
X1481650Y519455D01*
X1474246Y521177D01*
X1465668Y518230D01*
X1460738Y519328D01*
X1457634Y518641D01*
X1424857Y505646D01*
X1410034Y496287D01*
X1407783Y490246D01*
X1409593Y482423D01*
X1408647Y478114D01*
X1418423Y459258D01*
Y449652D01*
X1416152Y447381D01*
Y437828D01*
X1414568Y436244D01*
Y433794D01*
X1413624Y432850D01*
X1409750D01*
X1409300Y433300D01*
Y434775D01*
G01X1415146Y421946D02*
X1415143Y420431D01*
X1415597Y419977D01*
X1416677D01*
X1417118Y420418D01*
Y435256D01*
X1418655Y436793D01*
Y446347D01*
X1421057Y448749D01*
Y469841D01*
X1421542Y472294D01*
X1421154Y474256D01*
X1421542Y476218D01*
X1421154Y478180D01*
X1421542Y480142D01*
X1421154Y482104D01*
X1421542Y484066D01*
X1421154Y486028D01*
X1421542Y487990D01*
X1421154Y489952D01*
X1421542Y491914D01*
X1421154Y493876D01*
X1421813Y497208D01*
X1425939Y503331D01*
X1431498Y505535D01*
X1447044Y508700D01*
X1447551Y509467D01*
X1448874Y509736D01*
X1449641Y509229D01*
X1450963Y509498D01*
X1451471Y510265D01*
X1452794Y510534D01*
X1453560Y510027D01*
X1454883Y510296D01*
X1458419Y509507D01*
X1466994Y513144D01*
X1474218Y514366D01*
X1481113Y512339D01*
X1488276Y513838D01*
X1498614Y511370D01*
X1502413D01*
X1507809Y514747D01*
X1516524Y517073D01*
X1517687Y517759D01*
X1517916Y518649D01*
X1519079Y519335D01*
X1519969Y519106D01*
X1521131Y519792D01*
X1521361Y520682D01*
X1522523Y521369D01*
X1523413Y521139D01*
X1528122Y523918D01*
X1537676Y525909D01*
X1546287Y524173D01*
X1552602Y525609D01*
X1559091Y524240D01*
X1565192Y525783D01*
X1565961Y525977D01*
X1609905Y507771D01*
X1612187Y507320D01*
X1614375Y507753D01*
X1616309Y507370D01*
X1618274Y507759D01*
X1625541Y506318D01*
X1630077Y504478D01*
X1632280Y504914D01*
X1634201Y504534D01*
X1638158Y505362D01*
X1648622Y502537D01*
X1659927Y505158D01*
X1671397Y508584D01*
X1677639Y507090D01*
X1683473Y497496D01*
X1685732Y496009D01*
X1691341Y494531D01*
X1695395Y495419D01*
X1702411Y493625D01*
X1722206Y481888D01*
X1746782Y477000D01*
X1757800D01*
X1759541Y478741D01*
X1764044Y480605D01*
X1780623Y482235D01*
X1783739Y482855D01*
X1785542Y483603D01*
X1787970Y486030D01*
X1795489D01*
X1797389Y486818D01*
X1797950Y487379D01*
Y488580D01*
X1797600Y488930D01*
X1796125D01*
G01X1806975Y488730D02*
X1808450D01*
X1808900Y488280D01*
Y487428D01*
X1806451Y484980D01*
X1798209Y483340D01*
X1788817D01*
X1786300Y480823D01*
Y478883D01*
X1783727Y472675D01*
X1781352Y470300D01*
X1763612D01*
X1739268Y475142D01*
X1738758Y475906D01*
X1737434Y476169D01*
X1736669Y475658D01*
X1735345Y475922D01*
X1734834Y476686D01*
X1733510Y476949D01*
X1732746Y476439D01*
X1731422Y476702D01*
X1730911Y477466D01*
X1729587Y477729D01*
X1728823Y477219D01*
X1723186Y478340D01*
Y478339D01*
X1701405Y491252D01*
X1695361Y492799D01*
X1691366Y491924D01*
X1684512Y493728D01*
X1681625Y495630D01*
X1676014Y504857D01*
X1671470Y505943D01*
X1656067Y501342D01*
X1648621Y499855D01*
X1637998Y502722D01*
X1634216Y501932D01*
X1632235Y502324D01*
X1629797Y501840D01*
X1624759Y503883D01*
X1618297Y505165D01*
X1616311Y504771D01*
X1614344Y505160D01*
X1612157Y504727D01*
X1609135Y505324D01*
X1565752Y523293D01*
X1559144Y521622D01*
X1552572Y523010D01*
X1546267Y521576D01*
X1537683Y523306D01*
X1529277Y521554D01*
X1524396Y518673D01*
X1519456Y509925D01*
X1512924Y506024D01*
X1507919D01*
X1502053Y502896D01*
X1499091Y502066D01*
X1484918Y505636D01*
X1480874Y504774D01*
X1477945Y505423D01*
X1465997Y503175D01*
X1454265Y507567D01*
X1432228Y503081D01*
X1427574Y501236D01*
X1424226Y496269D01*
X1423754Y493876D01*
X1424142Y491914D01*
X1423754Y489952D01*
X1424122Y488090D01*
X1423734Y486128D01*
X1424142Y484066D01*
X1423754Y482104D01*
X1424160Y480053D01*
X1423772Y478089D01*
X1424142Y476218D01*
X1423754Y474256D01*
X1424160Y472205D01*
X1423557Y469151D01*
Y447712D01*
X1421155Y445310D01*
Y435756D01*
X1419618Y434219D01*
Y417546D01*
X1415672Y413600D01*
X1411737D01*
X1410773Y414564D01*
Y418474D01*
X1409650Y419597D01*
X1407608D01*
X1407158Y420047D01*
Y421575D01*
G01X1405423Y413281D02*
X1408004Y410700D01*
X1417300D01*
X1422118Y415518D01*
Y433182D01*
X1423775Y434839D01*
Y444393D01*
X1426081Y446699D01*
Y468539D01*
X1426782Y472089D01*
X1426353Y474256D01*
X1426741Y476218D01*
X1426389Y478000D01*
X1426777Y479964D01*
X1426353Y482104D01*
X1426741Y484066D01*
X1426354Y486023D01*
X1426742Y487985D01*
X1426353Y489952D01*
X1426742Y491914D01*
X1426363Y493829D01*
X1426670Y495382D01*
X1429203Y499139D01*
X1432427Y500415D01*
X1454237Y504855D01*
X1465769Y500537D01*
X1477903Y502820D01*
X1480863Y502164D01*
X1484869Y503018D01*
X1511840Y496225D01*
X1515208Y496910D01*
X1518176Y498874D01*
X1522081Y504774D01*
X1523494Y511719D01*
X1526425Y516909D01*
X1530210Y519144D01*
X1537692Y520703D01*
X1546351Y518957D01*
X1552642Y520388D01*
X1559196Y519005D01*
X1565453Y520588D01*
X1608375Y502812D01*
X1611998Y502095D01*
X1614347Y502560D01*
X1616309Y502172D01*
X1618365Y502580D01*
X1623877Y501489D01*
X1629545Y499191D01*
X1632239Y499724D01*
X1634231Y499330D01*
X1637998Y500117D01*
X1648660Y497239D01*
X1656451Y498796D01*
X1671543Y503304D01*
X1674385Y502624D01*
X1681098Y491586D01*
X1684382Y483183D01*
X1688439Y480881D01*
X1694102Y482011D01*
X1701172Y479841D01*
X1703139Y480325D01*
X1706641Y479679D01*
X1710120Y480453D01*
X1714033Y479342D01*
X1719437Y476139D01*
X1750050Y470050D01*
X1754900Y465200D01*
X1785077D01*
X1788684Y466695D01*
X1789664Y467675D01*
Y468595D01*
X1790619Y469549D01*
X1791538D01*
X1792493Y470504D01*
Y471423D01*
X1793447Y472378D01*
X1794367D01*
X1799661Y477672D01*
Y478591D01*
X1800615Y479545D01*
X1801534D01*
X1802489Y480500D01*
X1812386Y484600D01*
X1816077D01*
X1820212Y486314D01*
X1821050Y487150D01*
Y488480D01*
X1820600Y488930D01*
X1819125D01*
G01X1770325Y487355D02*
X1768850D01*
X1768400Y486905D01*
Y485400D01*
X1767367Y484366D01*
X1759387Y481059D01*
X1756828Y478500D01*
X1747117D01*
X1722586Y483380D01*
X1703318Y494804D01*
X1695127Y496897D01*
X1691138Y496025D01*
X1686424Y497267D01*
X1684466Y498556D01*
X1678531Y508316D01*
X1670986Y510120D01*
X1661040Y507150D01*
X1645698D01*
X1625935Y515490D01*
X1617007Y512484D01*
X1614152Y513306D01*
X1605348Y511545D01*
X1566611Y527585D01*
X1559062Y525674D01*
X1552591Y527040D01*
X1546269Y525605D01*
X1537671Y527338D01*
X1504244Y520374D01*
X1499347Y522084D01*
X1496493Y524252D01*
X1494715Y524802D01*
X1491694Y523929D01*
X1484789Y518890D01*
X1481628Y518279D01*
X1474307Y519981D01*
X1465735Y517036D01*
X1460737Y518149D01*
X1457973Y517537D01*
X1425380Y504616D01*
X1410977Y495521D01*
X1408982Y490168D01*
X1410772Y482429D01*
X1409860Y478274D01*
X1419573Y459539D01*
Y449175D01*
X1417302Y446904D01*
Y437351D01*
X1415718Y435767D01*
Y433317D01*
X1414101Y431700D01*
X1409750D01*
X1409300Y431250D01*
Y429775D01*
G01X1414982Y417040D02*
Y418309D01*
X1415500Y418827D01*
X1417154D01*
X1418268Y419941D01*
Y434779D01*
X1419805Y436316D01*
Y445870D01*
X1422207Y448272D01*
Y469728D01*
X1422715Y472294D01*
X1422327Y474256D01*
X1422715Y476218D01*
X1422327Y478180D01*
X1422715Y480142D01*
X1422327Y482104D01*
X1422715Y484066D01*
X1422327Y486028D01*
X1422715Y487990D01*
X1422327Y489952D01*
X1422715Y491914D01*
X1422327Y493876D01*
X1422897Y496757D01*
X1426694Y502393D01*
X1431827Y504428D01*
X1454872Y509120D01*
X1458528Y508304D01*
X1467319Y512032D01*
X1474148Y513187D01*
X1481066Y511154D01*
X1488260Y512659D01*
X1498478Y510220D01*
X1502744D01*
X1508273Y513680D01*
X1516973Y516002D01*
X1518683Y517010D01*
X1518684Y517012D01*
X1528543Y522831D01*
X1537680Y524735D01*
X1546301Y522996D01*
X1552611Y524431D01*
X1559115Y523059D01*
X1565873Y524768D01*
X1609570Y506664D01*
X1612187Y506147D01*
X1614375Y506580D01*
X1616309Y506197D01*
X1618274Y506586D01*
X1625210Y505211D01*
X1629963Y503283D01*
X1632280Y503741D01*
X1634207Y503360D01*
X1638124Y504179D01*
X1648601Y501351D01*
X1660222Y504045D01*
X1671430Y507393D01*
X1676905Y506083D01*
X1682624Y496677D01*
X1685257Y494944D01*
X1691316Y493348D01*
X1695374Y494237D01*
X1701966Y492551D01*
X1721789Y480798D01*
X1721790Y480797D01*
Y480798D01*
X1746668Y475850D01*
X1758277D01*
X1760193Y477765D01*
X1764326Y479477D01*
X1780792Y481096D01*
X1784075Y481749D01*
X1786195Y482628D01*
X1788447Y484880D01*
X1795719D01*
X1798041Y485843D01*
X1799100Y486902D01*
Y488380D01*
X1799650Y488930D01*
X1801125D01*
G01X1811975Y488730D02*
X1810500D01*
X1810050Y488280D01*
Y486951D01*
X1807018Y483919D01*
X1798323Y482190D01*
X1789294D01*
X1787450Y480346D01*
Y478654D01*
X1784703Y472023D01*
X1784540Y471860D01*
Y471861D01*
X1781829Y469150D01*
X1763498D01*
X1722767Y477250D01*
X1700960Y490178D01*
X1695340Y491617D01*
X1691341Y490741D01*
X1684036Y492663D01*
X1680776Y494811D01*
X1675280Y503850D01*
X1671503Y504752D01*
X1656345Y500224D01*
X1648582Y498674D01*
X1637964Y501540D01*
X1634222Y500758D01*
X1632235Y501151D01*
X1629683Y500645D01*
X1624428Y502776D01*
X1618297Y503992D01*
X1616309Y503598D01*
X1614344Y503987D01*
X1612157Y503554D01*
X1608800Y504217D01*
X1565664Y522084D01*
X1559167Y520441D01*
X1552581Y521832D01*
X1546282Y520399D01*
X1537687Y522132D01*
X1529698Y520467D01*
X1525246Y517839D01*
X1520308Y509093D01*
X1513242Y504874D01*
X1508207D01*
X1502481Y501820D01*
X1499107Y500876D01*
X1484897Y504455D01*
X1480869Y503597D01*
X1477926Y504249D01*
X1465894Y501985D01*
X1454171Y506374D01*
X1432557Y501974D01*
X1428329Y500298D01*
X1425310Y495818D01*
X1424927Y493876D01*
X1425315Y491914D01*
X1424927Y489952D01*
X1425295Y488090D01*
X1424907Y486128D01*
X1425315Y484066D01*
X1424927Y482104D01*
X1425333Y480053D01*
X1424945Y478090D01*
X1425315Y476218D01*
X1424927Y474256D01*
X1425333Y472205D01*
X1424707Y469038D01*
Y447235D01*
X1422305Y444833D01*
Y435279D01*
X1420768Y433742D01*
Y417069D01*
X1416149Y412450D01*
X1411260D01*
X1409623Y414087D01*
Y417997D01*
X1409173Y418447D01*
X1407608D01*
X1407158Y417997D01*
Y416575D01*
G01X1405423Y408281D02*
X1406692Y409550D01*
X1417777D01*
X1423268Y415041D01*
Y432705D01*
X1424925Y434362D01*
Y443916D01*
X1427231Y446222D01*
Y468426D01*
X1427955Y472089D01*
X1427526Y474256D01*
X1427914Y476218D01*
X1427562Y478000D01*
X1427950Y479964D01*
X1427526Y482104D01*
X1427914Y484066D01*
X1427527Y486023D01*
X1427915Y487985D01*
X1427526Y489952D01*
X1427915Y491914D01*
X1427536Y493829D01*
X1427754Y494931D01*
X1429958Y498200D01*
X1432756Y499308D01*
X1454143Y503662D01*
X1465666Y499347D01*
X1477884Y501646D01*
X1480858Y500986D01*
X1484847Y501837D01*
X1511813Y495045D01*
Y495046D01*
X1515656Y495827D01*
X1519006Y498044D01*
X1523164Y504325D01*
X1524585Y511312D01*
X1527277Y516075D01*
X1530631Y518057D01*
X1537696Y519529D01*
X1546365Y517780D01*
X1552651Y519210D01*
X1559219Y517824D01*
X1565365Y519379D01*
X1608040Y501705D01*
X1611998Y500922D01*
X1614347Y501387D01*
X1616309Y500999D01*
X1618365Y501407D01*
X1623546Y500382D01*
X1629431Y497996D01*
X1632239Y498551D01*
X1634237Y498156D01*
X1637964Y498935D01*
X1648621Y496058D01*
X1656729Y497678D01*
X1671576Y502113D01*
X1673652Y501616D01*
X1680063Y491074D01*
X1683459Y482384D01*
X1688244Y479669D01*
X1694042Y480826D01*
X1701138Y478648D01*
X1703174Y479149D01*
X1706662Y478505D01*
X1710086Y479267D01*
X1713575Y478276D01*
X1719022Y475048D01*
X1749483Y468989D01*
X1754422Y464050D01*
X1785306D01*
X1789336Y465719D01*
X1803141Y479524D01*
X1812615Y483450D01*
X1816306D01*
X1820864Y485338D01*
X1822200Y486673D01*
Y488300D01*
X1822830Y488930D01*
X1824125D01*
G01X1657498Y284900D02*
Y283185D01*
X1657048Y282735D01*
X1653521D01*
X1647672Y288584D01*
Y322178D01*
X1640535Y329315D01*
X1634333D01*
X1631024Y326006D01*
X1624498D01*
X1622672Y327832D01*
X1597582D01*
X1596967Y327217D01*
X1557371D01*
X1552752Y331836D01*
Y333956D01*
X1549158Y337550D01*
X1531840D01*
X1530465Y338925D01*
X1519598D01*
X1509796Y348726D01*
X1509459Y349063D01*
X1508847D01*
X1501700Y356210D01*
Y367300D01*
X1496300Y372700D01*
X1486750D01*
X1483650Y375800D01*
Y377600D01*
X1479150Y382100D01*
Y388677D01*
X1477577Y390250D01*
X1469377D01*
X1468050Y391577D01*
Y394023D01*
X1468948Y394921D01*
Y396723D01*
X1469873Y397648D01*
G01X1657498Y279900D02*
Y281135D01*
X1657048Y281585D01*
X1653044D01*
X1646522Y288107D01*
Y321701D01*
X1640058Y328165D01*
X1634810D01*
X1631501Y324856D01*
X1624021D01*
X1622195Y326682D01*
X1598059D01*
X1597444Y326067D01*
X1556894D01*
X1551602Y331359D01*
Y333479D01*
X1548681Y336400D01*
X1531363D01*
X1529988Y337775D01*
X1519121D01*
X1508983Y347913D01*
Y347912D01*
X1508982Y347913D01*
X1508370D01*
X1500550Y355733D01*
Y366823D01*
X1495823Y371550D01*
X1486273D01*
X1482500Y375323D01*
Y377123D01*
X1478000Y381623D01*
Y388200D01*
X1477100Y389100D01*
X1468900D01*
X1466900Y391100D01*
Y394500D01*
X1467798Y395398D01*
Y396723D01*
X1466873Y397648D01*
G01X1466382Y406773D02*
X1467307Y407698D01*
Y408812D01*
X1468645Y410150D01*
X1474477D01*
X1479727Y404900D01*
X1484677D01*
X1487050Y402527D01*
Y399949D01*
X1485906Y398805D01*
Y397123D01*
X1487856Y395173D01*
Y388729D01*
X1485850Y386723D01*
Y376801D01*
X1487301Y375350D01*
X1505050D01*
X1506678Y373722D01*
Y372803D01*
X1506959Y372522D01*
X1507878D01*
X1509506Y370894D01*
Y369975D01*
X1509787Y369694D01*
X1510706D01*
X1512020Y368380D01*
Y354780D01*
X1514913Y351887D01*
Y349386D01*
X1520149Y344150D01*
X1531377D01*
X1535377Y340150D01*
X1550963D01*
X1554280Y336833D01*
X1559094D01*
X1566210Y329717D01*
X1575871D01*
X1578482Y332328D01*
X1583340D01*
X1585715Y329953D01*
X1595442D01*
X1599568Y334079D01*
X1604468D01*
X1608168Y330379D01*
X1620979D01*
X1622415Y331815D01*
X1641884D01*
X1650350Y323349D01*
Y295442D01*
X1654955Y290837D01*
X1658659D01*
X1660721Y288775D01*
Y262393D01*
X1659528Y261200D01*
X1658011D01*
X1657492Y260679D01*
X1657500Y259700D01*
G01X1469382Y406773D02*
X1468457Y407698D01*
Y408335D01*
X1469122Y409000D01*
X1474000D01*
X1474955Y408045D01*
Y407126D01*
X1475909Y406172D01*
X1476828D01*
X1479250Y403750D01*
X1484200D01*
X1485900Y402050D01*
Y400426D01*
X1484756Y399282D01*
Y396646D01*
X1486706Y394696D01*
Y389206D01*
X1484700Y387200D01*
Y376324D01*
X1486824Y374200D01*
X1500417D01*
X1501067Y373550D01*
X1502417D01*
X1503067Y374200D01*
X1504573D01*
X1505528Y373245D01*
Y372326D01*
X1506482Y371372D01*
X1507401D01*
X1508356Y370417D01*
Y369498D01*
X1509310Y368544D01*
X1510229D01*
X1510860Y367913D01*
Y365993D01*
X1510210Y365343D01*
Y363993D01*
X1510860Y363343D01*
Y361993D01*
X1510210Y361343D01*
Y359993D01*
X1510860Y359343D01*
Y357993D01*
X1510210Y357343D01*
Y355993D01*
X1510860Y355343D01*
Y354313D01*
X1513763Y351410D01*
Y348909D01*
X1514909Y347763D01*
Y346843D01*
X1515864Y345889D01*
X1516783D01*
X1519672Y343000D01*
X1530900D01*
X1534900Y339000D01*
X1550486D01*
X1553803Y335683D01*
X1558617D01*
X1565733Y328567D01*
X1576348D01*
X1578959Y331178D01*
X1582863D01*
X1585238Y328803D01*
X1595919D01*
X1600045Y332929D01*
X1603991D01*
X1607691Y329229D01*
X1621456D01*
X1622892Y330665D01*
X1641407D01*
X1649200Y322872D01*
Y294965D01*
X1654478Y289687D01*
X1658182D01*
X1659571Y288298D01*
Y262870D01*
X1659051Y262350D01*
X1658032D01*
X1657579Y262799D01*
X1657567Y264600D01*
G01X1909421Y208805D02*
X1909426Y207649D01*
X1909878Y207200D01*
X1911400D01*
X1913230Y209030D01*
Y226362D01*
X1918385Y231517D01*
Y233721D01*
X1911855Y240251D01*
X1891134D01*
X1882701Y248684D01*
X1881782D01*
X1880827Y249639D01*
Y250558D01*
X1879872Y251513D01*
X1878953D01*
X1877999Y252467D01*
Y253386D01*
X1877044Y254341D01*
X1876125D01*
X1875170Y255295D01*
Y256215D01*
X1874216Y257169D01*
X1873296D01*
X1872342Y258124D01*
Y259043D01*
X1867367Y264018D01*
X1676726D01*
X1667901Y272843D01*
Y407173D01*
X1666760Y408314D01*
X1666759D01*
X1647598Y427475D01*
X1645966D01*
X1643006Y430435D01*
Y461434D01*
X1645000Y463428D01*
Y477673D01*
X1639900Y482773D01*
X1639182D01*
X1635605Y486350D01*
X1613767D01*
X1612679Y487438D01*
X1611060Y490672D01*
X1605009Y496723D01*
X1600681Y498632D01*
X1581681D01*
X1579280Y496231D01*
X1560641D01*
X1559991Y495581D01*
X1558641D01*
X1557991Y496231D01*
X1556641D01*
X1555991Y495581D01*
X1554641D01*
X1553991Y496231D01*
X1552641D01*
X1551991Y495581D01*
X1550641D01*
X1549991Y496231D01*
X1548641D01*
X1547991Y495581D01*
X1546641D01*
X1545991Y496231D01*
X1539551D01*
X1536878Y498904D01*
Y505830D01*
X1536097Y506611D01*
X1534676D01*
X1533595Y505530D01*
G01X1909438Y204307D02*
X1909432Y205520D01*
Y205532D01*
X1909948Y206050D01*
X1911877D01*
X1914380Y208553D01*
Y225885D01*
X1919535Y231040D01*
Y234198D01*
X1912332Y241401D01*
X1891611D01*
X1867844Y265168D01*
X1677203D01*
X1669051Y273320D01*
Y407650D01*
X1667237Y409464D01*
X1667236D01*
X1648074Y428626D01*
X1647958D01*
X1647957Y428625D01*
X1646443D01*
X1644156Y430912D01*
Y460957D01*
X1646150Y462951D01*
Y478150D01*
X1640377Y483923D01*
X1639659D01*
X1636082Y487500D01*
X1614244D01*
X1613625Y488120D01*
X1612006Y491354D01*
X1605671Y497689D01*
X1600924Y499782D01*
X1581204D01*
X1578803Y497381D01*
X1540028D01*
X1538028Y499381D01*
Y506307D01*
X1536574Y507761D01*
X1534864D01*
X1533595Y509030D01*
G01X1904042Y204895D02*
X1905116Y203821D01*
X1905788D01*
X1906238Y204271D01*
Y231865D01*
X1900952Y237151D01*
X1888861D01*
X1882508Y243504D01*
X1881589D01*
X1880634Y244458D01*
Y245378D01*
X1879680Y246332D01*
X1878761D01*
X1877806Y247287D01*
Y248206D01*
X1876851Y249161D01*
X1875932D01*
X1874978Y250115D01*
Y251034D01*
X1874023Y251989D01*
X1873104D01*
X1872149Y252944D01*
Y253863D01*
X1865094Y260918D01*
X1674395D01*
X1663923Y271390D01*
Y302650D01*
X1660204Y306369D01*
Y379696D01*
X1664801Y384293D01*
Y405887D01*
X1646313Y424375D01*
X1641070D01*
X1635701Y429744D01*
Y461028D01*
X1640850Y466177D01*
Y477393D01*
X1639159Y479084D01*
X1636738D01*
X1632572Y483250D01*
X1611423D01*
X1608867Y485806D01*
Y487726D01*
X1605736Y490857D01*
X1600039D01*
X1598477Y492419D01*
Y494319D01*
X1597380Y495416D01*
G01X1903917Y201472D02*
X1904815Y202370D01*
X1905088D01*
X1905389Y202671D01*
X1906265D01*
X1907388Y203794D01*
Y232342D01*
X1901429Y238301D01*
X1889338D01*
X1865571Y262068D01*
X1674872D01*
X1665073Y271867D01*
Y303127D01*
X1661354Y306846D01*
Y379219D01*
X1665951Y383816D01*
Y406364D01*
X1646790Y425525D01*
X1641547D01*
X1636851Y430221D01*
Y460551D01*
X1642000Y465700D01*
Y477870D01*
X1639636Y480234D01*
X1637215D01*
X1633049Y484400D01*
X1611900D01*
X1610017Y486283D01*
Y488203D01*
X1606213Y492007D01*
X1600516D01*
X1599627Y492896D01*
Y494263D01*
X1600780Y495416D01*
G54D28*
G01X1258162Y173416D02*
X1277916D01*
X1288644Y162688D01*
X1289349D01*
G54D19*
X102328Y105000D03*
X97406D03*
X92485D03*
G54D38*
G01D02*
X89785Y102300D01*
X82940D01*
X77978Y97338D01*
Y88582D01*
X75339Y85943D01*
X59900D01*
X57143Y88700D01*
X46400D01*
X40700Y94400D01*
Y116000D01*
X35218Y121482D01*
X-13018D01*
X-15748Y118752D01*
Y116969D01*
G01X-19210Y162529D02*
Y161160D01*
X-20940Y159430D01*
Y133638D01*
X-16290Y128988D01*
X-8453D01*
X-4725Y132716D01*
Y132717D01*
G01X-12861Y163165D02*
X-14044D01*
X-14932Y164053D01*
X-16320D01*
X-17344Y163029D01*
Y161285D01*
X-19772Y158857D01*
Y136741D01*
X-15748Y132717D01*
G01X49091Y351509D02*
X41609D01*
X37752Y347652D01*
X5922D01*
X1922Y343652D01*
X-14278D01*
X-21548Y336382D01*
Y174718D01*
X-19210Y172380D01*
Y162529D01*
G01X-15768Y161922D02*
X-13847D01*
X-13514Y161589D01*
X-12208D01*
X-11384Y162413D01*
X50716D01*
X53469Y165166D01*
Y187015D01*
X45083Y195401D01*
Y266311D01*
X47528Y268756D01*
Y280013D01*
X45753Y281788D01*
Y311220D01*
X45248Y311725D01*
Y342740D01*
X49017Y346509D01*
G01X49117Y349009D02*
X41109D01*
X38600Y346500D01*
X6400D01*
X2400Y342500D01*
X-13800D01*
X-20396Y335904D01*
Y175196D01*
X-16135Y170935D01*
Y168687D01*
X-12861Y165413D01*
Y163165D01*
G01X-17200Y510800D02*
X-11415Y505015D01*
Y500024D01*
X-7515Y496124D01*
X-3456D01*
X230Y492438D01*
X13430D01*
X15219Y490649D01*
X28898D01*
X31947Y487600D01*
X47800D01*
G01X-16766Y500106D02*
X-14864Y498204D01*
Y496520D01*
X-16504Y494880D01*
Y486088D01*
X-6763Y476347D01*
X5520D01*
X10338Y481165D01*
Y481166D01*
X11334Y482162D01*
X11335D01*
X11336Y482163D01*
X12744D01*
X12745Y482162D01*
X19145D01*
X24203Y477104D01*
X61558D01*
X64654Y474008D01*
X69729D01*
X71400Y472337D01*
X98963D01*
X134630Y436670D01*
X137600D01*
X148409Y425861D01*
Y422239D01*
G01X-17302Y506798D02*
X-19908Y504192D01*
Y484678D01*
X-9170Y473940D01*
Y473939D01*
X-8174Y472943D01*
X6930D01*
X12745Y478758D01*
X17735D01*
X22794Y473699D01*
X25226D01*
X25227Y473700D01*
X60148D01*
X63244Y470604D01*
X68318D01*
X69989Y468933D01*
X97553D01*
X133926Y432560D01*
X136896D01*
X144545Y424911D01*
Y418355D01*
X148300Y414600D01*
G01X-16700Y497400D02*
X-18206Y495894D01*
Y485383D01*
X-7468Y474645D01*
X6225D01*
X12040Y480460D01*
X18440D01*
X23499Y475401D01*
X24520D01*
X24521Y475402D01*
X60853D01*
X63949Y472306D01*
X69024D01*
X70020Y471310D01*
Y471309D01*
X70694Y470635D01*
X98258D01*
X134213Y434680D01*
X137183D01*
X146406Y425457D01*
Y419127D01*
X148136Y417397D01*
X148666D01*
G01X34719Y19455D02*
Y17551D01*
X35624Y16646D01*
X39559D01*
X45012Y11193D01*
X52596D01*
X57252Y6537D01*
Y-1425D01*
X66935Y-11108D01*
X76508D01*
X81800Y-16400D01*
X82100D01*
X82300Y-16600D01*
G01X102328Y105000D02*
Y104928D01*
X97200Y99800D01*
X83700D01*
X80083Y96183D01*
Y87943D01*
X80082Y87942D01*
Y87709D01*
X76212Y83839D01*
X59027D01*
X56270Y86596D01*
X45527D01*
X45523Y86600D01*
X45100D01*
X38300Y93400D01*
Y107900D01*
X33168Y113032D01*
X-788D01*
X-4725Y116969D01*
G01X97406Y105000D02*
Y102406D01*
X95952Y100952D01*
X83222D01*
X79130Y96860D01*
Y88104D01*
X75817Y84791D01*
X59422D01*
X56665Y87548D01*
X45922D01*
X45870Y87600D01*
X45800D01*
X39500Y93900D01*
Y108521D01*
X34021Y114000D01*
X0D01*
X-2000Y116000D01*
Y118000D01*
X-4000Y120000D01*
X-7205D01*
X-10236Y116969D01*
G01X51923Y346164D02*
Y344285D01*
X49864Y342226D01*
X48547D01*
X47624Y341303D01*
Y332336D01*
X50900Y329060D01*
Y322670D01*
X47649Y319419D01*
Y312584D01*
X51400Y308833D01*
Y269368D01*
X47387Y265355D01*
Y196427D01*
X55773Y188041D01*
Y164942D01*
X56139Y164576D01*
Y162530D01*
X52367Y158758D01*
X47029D01*
X40830Y152559D01*
Y147930D01*
X36383Y143483D01*
Y139079D01*
X37037Y138425D01*
G01X49017Y344009D02*
X48609D01*
X46400Y341800D01*
Y331930D01*
X49748Y328582D01*
Y323148D01*
X46497Y319897D01*
Y312106D01*
X46905Y311698D01*
Y282266D01*
X48680Y280491D01*
Y268278D01*
X46235Y265833D01*
Y195949D01*
X54621Y187563D01*
Y164209D01*
X51626Y161214D01*
X47855D01*
X41542Y154901D01*
X39109D01*
G01X-14488Y434094D02*
Y435095D01*
X-4806Y444777D01*
Y453744D01*
X-413Y458137D01*
X2712D01*
X11589Y449260D01*
X64123D01*
X86200Y427183D01*
Y395700D01*
X83130Y392630D01*
Y374920D01*
X81143Y372933D01*
X69467D01*
X64200Y378200D01*
X56500D01*
X54995Y376695D01*
X53800Y373812D01*
Y365690D01*
X57876Y361614D01*
Y322536D01*
X51500Y316160D01*
Y314200D01*
X54300Y311400D01*
X56529D01*
X62429Y305500D01*
X80641D01*
X86476Y299665D01*
Y285979D01*
X85300Y284803D01*
Y274671D01*
X97671Y262300D01*
X100400D01*
X101600Y261100D01*
Y220500D01*
X86900Y205800D01*
Y199700D01*
X80526Y193326D01*
Y152157D01*
X79219Y150850D01*
X78462D01*
X75272Y147660D01*
Y143540D01*
X95775Y123037D01*
X100783D01*
X111552Y112268D01*
Y99330D01*
X104229Y92007D01*
Y4251D01*
X108597Y-117D01*
Y-12337D01*
X113512Y-17252D01*
X403544D01*
X405735Y-15061D01*
X457957D01*
X460588Y-17692D01*
X646897D01*
X651658Y-12931D01*
Y-1999D01*
X658436Y4779D01*
Y8995D01*
X662169Y12728D01*
X677328D01*
X679380Y14780D01*
X688291D01*
X689663Y13408D01*
X715116D01*
X721805Y6719D01*
Y3345D01*
X723600Y1550D01*
Y-5000D01*
X735992Y-17392D01*
X1268490D01*
X1273961Y-11921D01*
X1277149D01*
X1278000Y-11070D01*
Y-2070D01*
X1280551Y481D01*
Y58751D01*
X1284500Y62700D01*
X1290000D01*
X1294200Y66900D01*
Y76000D01*
X1302207Y84007D01*
X1307607D01*
X1309400Y85800D01*
X1316100D01*
X1317300Y84600D01*
G01X148901Y-50496D02*
X445509D01*
G02Y-53848I0J-1676D01*
G01X147382D01*
X145030Y-56200D01*
X84450D01*
X80500Y-52250D01*
G01X104424Y110833D02*
X105777Y109480D01*
X106720D01*
X110400Y105800D01*
Y99930D01*
X102661Y92191D01*
Y78475D01*
X100300Y76114D01*
Y73371D01*
X102000Y71671D01*
Y4900D01*
X103077Y3823D01*
Y3773D01*
X107445Y-595D01*
Y-12815D01*
X113034Y-18404D01*
X404022D01*
X406213Y-16213D01*
X457479D01*
X460110Y-18844D01*
X647375D01*
X653039Y-13180D01*
Y-2248D01*
X659588Y4301D01*
Y8517D01*
X662647Y11576D01*
X679495D01*
X679801Y11270D01*
X681136D01*
X682122Y12256D01*
X714638D01*
X720653Y6241D01*
Y2867D01*
X722448Y1072D01*
Y-5478D01*
X723489Y-6519D01*
Y-12767D01*
X722251Y-14005D01*
Y-15345D01*
X725450Y-18544D01*
X1268968D01*
X1274439Y-13073D01*
X1277627D01*
X1279152Y-11548D01*
Y-7594D01*
X1279200Y-7546D01*
Y-2570D01*
X1284222Y2452D01*
X1288352D01*
X1294348Y8448D01*
Y15646D01*
X1292900Y17094D01*
Y24770D01*
X1294150Y26020D01*
Y62850D01*
X1295450Y64150D01*
Y74650D01*
X1302100Y81300D01*
X1316400D01*
X1318885Y83785D01*
Y84385D01*
X1320000Y85500D01*
G01X712796Y-16011D02*
X712793D01*
X712441Y-15659D01*
Y-6277D01*
X706902Y-738D01*
Y662D01*
X706382Y1182D01*
Y5247D01*
X705103Y6526D01*
X704812D01*
X703428Y7910D01*
Y9065D01*
X703402Y9091D01*
Y9162D01*
X701460Y11104D01*
X682600D01*
X679592Y8098D01*
X663634D01*
X660740Y5204D01*
Y3823D01*
X654225Y-2692D01*
Y-15197D01*
X649426Y-19996D01*
X459632D01*
X457001Y-17365D01*
X406691D01*
X404500Y-19556D01*
X112556D01*
X106293Y-13293D01*
Y-1073D01*
X102599Y2621D01*
X90522D01*
X87900Y5243D01*
Y84189D01*
X82046Y90043D01*
G01X701100Y8100D02*
X699600Y9600D01*
X683253D01*
X679653Y6000D01*
X671514D01*
X662700Y-2814D01*
Y-3600D01*
X661500Y-4800D01*
X659100D01*
X656659Y-7241D01*
Y-16340D01*
X651499Y-21500D01*
X458600D01*
X455969Y-18869D01*
X407315D01*
X405124Y-21060D01*
X70500D01*
X66153Y-16713D01*
X61281D01*
X54307Y-9739D01*
Y-8051D01*
G01X704450Y4950D02*
X702650Y6750D01*
Y7421D01*
X702676Y7447D01*
Y8753D01*
X702650Y8779D01*
Y8850D01*
X701148Y10352D01*
X682941D01*
X679389Y6800D01*
X670300D01*
X663961Y461D01*
X660838D01*
X659100Y-1277D01*
Y-2900D01*
X655770Y-6230D01*
Y-15757D01*
X650779Y-20748D01*
X458912D01*
X456281Y-18117D01*
X407003D01*
X404812Y-20308D01*
X111858D01*
X104500Y-12950D01*
Y-1850D01*
G01X62900Y339000D02*
Y321700D01*
X61400Y320200D01*
Y309380D01*
X64127Y306653D01*
X81118D01*
X87628Y300143D01*
Y285501D01*
X86700Y284573D01*
Y277800D01*
X102752Y261748D01*
Y220022D01*
X88300Y205570D01*
Y199470D01*
X81708Y192878D01*
Y156252D01*
X81678Y156222D01*
Y151679D01*
X79519Y149520D01*
X78762D01*
X76424Y147182D01*
Y144018D01*
X96248Y124194D01*
X102835D01*
X113744Y113285D01*
Y87155D01*
X105820Y79231D01*
Y63181D01*
X108000Y61001D01*
Y2110D01*
X109749Y361D01*
Y-11859D01*
X113990Y-16100D01*
X403066D01*
X405257Y-13909D01*
X458435D01*
X461066Y-16540D01*
X646419D01*
X650339Y-12620D01*
Y-1688D01*
X657284Y5257D01*
Y9473D01*
X661691Y13880D01*
X676680D01*
X678710Y15910D01*
X678880D01*
X678902Y15932D01*
X684162D01*
X685106Y16876D01*
X693153D01*
X695469Y14560D01*
X715594D01*
X722957Y7197D01*
Y3823D01*
X724752Y2028D01*
Y-4522D01*
X735782Y-15552D01*
X736095D01*
X736783Y-16240D01*
X1267860D01*
X1276600Y-7500D01*
Y-1701D01*
X1279399Y1098D01*
Y73245D01*
X1283628Y77474D01*
X1292995D01*
X1298754Y83233D01*
G01X1317195Y87098D02*
X1308898D01*
X1306959Y85159D01*
X1298381D01*
X1291848Y78626D01*
X1283150D01*
X1278247Y73723D01*
Y1576D01*
X1275100Y-1571D01*
Y-7300D01*
X1267465Y-14935D01*
X737108D01*
X725904Y-3731D01*
Y2506D01*
X724109Y4301D01*
Y7775D01*
X721650Y10234D01*
Y14279D01*
X720053Y15876D01*
X718747D01*
X718583Y15712D01*
X695947D01*
X693631Y18028D01*
X685405D01*
X682843Y20590D01*
X679004D01*
X673446Y15032D01*
X661213D01*
X656132Y9951D01*
Y5735D01*
X649142Y-1255D01*
Y-12187D01*
X645941Y-15388D01*
X461544D01*
X458913Y-12757D01*
X404779D01*
X402588Y-14948D01*
X114468D01*
X110901Y-11381D01*
Y839D01*
X109152Y2588D01*
Y62219D01*
X106972Y64399D01*
Y78753D01*
X114896Y86677D01*
Y114164D01*
X103687Y125373D01*
X97657D01*
X82905Y140125D01*
Y153403D01*
X84957Y155455D01*
X92344D01*
X93488Y156599D01*
Y175185D01*
X86952Y181721D01*
G01X87200Y152374D02*
X85638Y150812D01*
Y141162D01*
X95500Y131300D01*
X101734D01*
X117200Y115834D01*
Y85721D01*
X109276Y77797D01*
Y66324D01*
X111456Y64144D01*
Y6044D01*
X114000Y3500D01*
G01X1311559Y91431D02*
X1306439Y86311D01*
X1297903D01*
X1291376Y79784D01*
X1282678D01*
X1277095Y74201D01*
Y2054D01*
X1273948Y-1093D01*
Y-6822D01*
X1266987Y-13783D01*
X737586D01*
X727056Y-3253D01*
Y2984D01*
X725296Y4744D01*
Y4974D01*
X725261Y5009D01*
Y8253D01*
X722802Y10712D01*
Y13801D01*
X722803Y13802D01*
Y14756D01*
X720531Y17028D01*
X718269D01*
X718105Y16864D01*
X696425D01*
X694109Y19180D01*
X686820D01*
X684190Y21810D01*
X678384D01*
X672758Y16184D01*
X660735D01*
X654980Y10429D01*
Y6213D01*
X650067Y1300D01*
X632600D01*
X617064Y-14236D01*
X462416D01*
X459780Y-11600D01*
X409900D01*
X409895Y-11605D01*
X404301D01*
X402110Y-13796D01*
X114946D01*
X112053Y-10903D01*
Y1317D01*
X110304Y3066D01*
Y62697D01*
X108124Y64877D01*
Y78275D01*
X116048Y86199D01*
Y114834D01*
X100832Y130050D01*
X94610D01*
X84250Y140410D01*
Y152830D01*
X85487Y154067D01*
X93550D01*
X94640Y155157D01*
Y177383D01*
X87151Y184872D01*
G01X75660Y152380D02*
X73576Y150296D01*
Y121924D01*
X79700Y115800D01*
X91710D01*
X102328Y105182D01*
Y105000D01*
G01X97406D02*
Y108594D01*
X91152Y114848D01*
X80095D01*
X80094Y114847D01*
X79306D01*
X72624Y121529D01*
Y151700D01*
X74973Y154049D01*
X77711D01*
X78950Y152810D01*
G01X89980Y145531D02*
X94676Y140835D01*
X103565D01*
X118352Y126048D01*
Y85243D01*
X110428Y77319D01*
Y66942D01*
X117800Y59570D01*
Y9820D01*
X114100Y6120D01*
G01X75626Y310418D02*
X77744Y308300D01*
X89296D01*
X93373Y304223D01*
Y300354D01*
X91285Y298266D01*
Y287528D01*
X87852Y284095D01*
Y278278D01*
X103504Y262626D01*
Y218804D01*
X89515Y204815D01*
Y195815D01*
X84824Y191124D01*
Y163676D01*
X91306Y157194D01*
G01X453250Y623320D02*
X454320Y622250D01*
Y621510D01*
X449969Y617159D01*
X345095D01*
X342305Y619949D01*
X114929D01*
X102441Y607461D01*
Y495451D01*
X91259Y484269D01*
X66369D01*
X63751Y481651D01*
Y478949D01*
X65450Y477250D01*
Y475610D01*
G01X67477Y477940D02*
X66230D01*
X64790Y479380D01*
Y481220D01*
X66800Y483230D01*
X91690D01*
X103480Y495020D01*
Y607030D01*
X115360Y618910D01*
X342280D01*
X344783Y616407D01*
X450687D01*
X455180Y620900D01*
Y621590D01*
X456910Y623320D01*
G01X122242Y419199D02*
X123308Y418133D01*
Y412428D01*
X126368Y409368D01*
X142243D01*
X150956Y400655D01*
X163233D01*
X170407Y393481D01*
X172948D01*
X178248Y388181D01*
Y387027D01*
X193300Y371975D01*
Y366434D01*
X198804Y360930D01*
Y359167D01*
X245991Y311980D01*
X257793Y308818D01*
G01X123441Y421795D02*
X124082Y421154D01*
Y412718D01*
X126680Y410120D01*
X143121D01*
X151434Y401807D01*
X163261D01*
X170713Y394355D01*
X173898D01*
X179220Y389033D01*
Y387533D01*
X194498Y372255D01*
Y367130D01*
X200168Y361460D01*
Y359852D01*
X246969Y312961D01*
X258103Y309978D01*
G01X338838Y230560D02*
Y225446D01*
X336392Y223000D01*
X335392D01*
X333792Y221400D01*
Y216300D01*
X335892Y214200D01*
Y200700D01*
X336242Y200350D01*
Y197950D01*
X335892Y197600D01*
Y182701D01*
X337092Y181501D01*
Y134228D01*
X311892Y109028D01*
Y99973D01*
X307675Y95756D01*
Y92657D01*
G01X411431Y359351D02*
X417451D01*
X422200Y364100D01*
X424599D01*
G01X490819Y372227D02*
X492041D01*
X493072Y373258D01*
Y396205D01*
X494039Y397172D01*
X495373D01*
X497901Y399700D01*
X500600D01*
X506600Y405700D01*
X511499D01*
X525299Y419500D01*
X536291D01*
X588372Y471581D01*
X606906D01*
X608800Y473475D01*
G01X411086Y355360D02*
X420688D01*
X422300Y356972D01*
X424659D01*
X425594Y357907D01*
G01X490148Y364341D02*
X492148D01*
X494307Y366500D01*
X495892D01*
X497892Y368500D01*
X498553D01*
X499877Y369824D01*
Y392349D01*
X500799Y393271D01*
X501880D01*
X504580Y395971D01*
X505881D01*
X509330Y399420D01*
X512240D01*
X514130Y401310D01*
X515610D01*
X517830Y403530D01*
X518839D01*
X530309Y415000D01*
X537392D01*
X588977Y466585D01*
X603906D01*
X607016Y463475D01*
X608800D01*
G01X403056Y353409D02*
X405395D01*
X408958Y356972D01*
X418773D01*
X422462Y360661D01*
X424678D01*
G01X425008Y360991D02*
X425508Y361491D01*
G01X493734Y370000D02*
X494723D01*
X496497Y371774D01*
Y394300D01*
X497419Y395222D01*
X498856D01*
X503134Y399500D01*
X505099D01*
X508899Y403300D01*
X512301D01*
X514401Y405400D01*
X515792D01*
X527392Y417000D01*
X536590D01*
X588371Y468781D01*
X608494D01*
X608800Y468475D01*
G01X459773Y264947D02*
X463883D01*
X465630Y263200D01*
X466990D01*
X468900Y261290D01*
X470930D01*
X472320Y262680D01*
X474050D01*
X475470Y261260D01*
X477040D01*
X478840Y259460D01*
X481060D01*
X482300Y260700D01*
X483500D01*
X485800Y263000D01*
X492000D01*
X493600Y264600D01*
X495600D01*
X497400Y262800D01*
X498900D01*
X499800Y261900D01*
Y258200D01*
X500900Y257100D01*
X502300D01*
X504100Y255300D01*
X512200D01*
X513781Y256881D01*
X515719D01*
X517400Y255200D01*
X519000D01*
X521100Y253100D01*
X522500D01*
X524000Y251600D01*
X525900D01*
X527400Y253100D01*
X529100D01*
X530800Y251400D01*
X532800D01*
X534300Y252900D01*
X536300D01*
X537700Y251500D01*
X539800D01*
X541400Y253100D01*
X542800D01*
X544400Y251500D01*
X546100D01*
X547600Y253000D01*
X549500D01*
X551050Y251450D01*
X553350D01*
X554900Y253000D01*
X556500D01*
X558150Y251350D01*
X560250D01*
X562526Y253626D01*
X563242D01*
X565230Y255614D01*
X576109D01*
X576111Y255612D01*
X577065D01*
X587652Y266199D01*
X612580D01*
X625142Y278761D01*
X629151D01*
X631529Y281139D01*
X641607D01*
G01X636100Y329800D02*
X628143D01*
X622048Y335895D01*
Y374764D01*
X619399Y377413D01*
X587007D01*
X583401Y373807D01*
Y363982D01*
X577191Y357772D01*
Y349802D01*
X570716Y343327D01*
X568986D01*
G01X474267Y339421D02*
X471546Y336700D01*
X468400D01*
X445100Y313400D01*
Y300100D01*
X451514Y293686D01*
X453400D01*
G01X595070Y447970D02*
X592772Y450268D01*
X587139D01*
X565076Y428205D01*
X554400Y402431D01*
X554378Y402378D01*
X553800Y400982D01*
Y361875D01*
X552435Y360510D01*
X551013D01*
X549429Y358926D01*
X547374D01*
X546183Y360117D01*
X543917D01*
X542726Y358926D01*
X540674D01*
X539483Y360117D01*
X537417D01*
X536226Y358926D01*
X533874D01*
X532683Y360117D01*
X530617D01*
X529426Y358926D01*
X527174D01*
X525983Y360117D01*
X523817D01*
X522626Y358926D01*
X520374D01*
X519183Y360117D01*
X517017D01*
X515826Y358926D01*
X513774D01*
X512583Y360117D01*
X510117D01*
X508926Y358926D01*
X506974D01*
X505783Y360117D01*
X503617D01*
X502426Y358926D01*
X500174D01*
X498983Y360117D01*
X497017D01*
X495826Y358926D01*
X493274D01*
X492083Y360117D01*
X490117D01*
X488500Y358500D01*
X487100D01*
X485577Y356977D01*
X483123D01*
X481934Y358166D01*
X480166D01*
X478700Y356700D01*
X477000D01*
X474900Y354600D01*
X474096D01*
X472700Y353204D01*
Y348514D01*
X471033Y346847D01*
G01X483432Y239596D02*
X487804D01*
X489300Y238100D01*
Y218700D01*
X493600Y214400D01*
X495200D01*
X497500Y212100D01*
X498900D01*
X508600Y202400D01*
X519900D01*
X595944Y126356D01*
X607694D01*
X609482Y124568D01*
G01X518352Y261047D02*
X518733Y260666D01*
X522066D01*
X524100Y262700D01*
X525600D01*
X527600Y264700D01*
X529500D01*
X531000Y263200D01*
X532352D01*
X534000Y264848D01*
X535627D01*
X537600Y262875D01*
X538875D01*
X540600Y264600D01*
X542700D01*
X544400Y262900D01*
X545700D01*
X547500Y264700D01*
X549700D01*
X551500Y262900D01*
X552600D01*
X554600Y264900D01*
X555900D01*
X557600Y263200D01*
X567315D01*
X574874Y270759D01*
X610650D01*
X627723Y287832D01*
X628525D01*
G01X634407Y287915D02*
X632748Y286256D01*
X627211D01*
X610962Y270007D01*
X575186D01*
X567273Y262094D01*
X557014D01*
X556341Y261421D01*
G01X484552Y284447D02*
X482826Y282721D01*
Y272214D01*
X483863Y271177D01*
X484500D01*
G01X561213Y275351D02*
X562749Y273815D01*
X609382D01*
X626680Y291113D01*
X629667D01*
X630698Y292144D01*
X633865D01*
X635821Y294100D01*
X640489D01*
X644271Y297882D01*
Y329398D01*
X661045Y346172D01*
X664501D01*
X666197Y347868D01*
Y356697D01*
X673988Y364488D01*
Y370618D01*
X678476Y375106D01*
Y382453D01*
X677947Y382982D01*
Y387267D01*
X679385Y388705D01*
G01X560900Y274600D02*
X562437Y273063D01*
X609694D01*
X626869Y290238D01*
X630662D01*
X631250Y289650D01*
G01X636799Y285670D02*
X635881Y284752D01*
X627873D01*
X611624Y268503D01*
X575922D01*
X566368Y258949D01*
G01X636985Y288264D02*
X634225Y285504D01*
X627523D01*
X611274Y269255D01*
X575610D01*
X567026Y260671D01*
X566999D01*
X566212Y259884D01*
X557016D01*
X556256Y260644D01*
G01X695700Y346300D02*
X694312Y347688D01*
X693525D01*
X693470Y347633D01*
X691905D01*
X689687Y345415D01*
X668741D01*
X659948Y336622D01*
X657027D01*
X650605Y330200D01*
Y294203D01*
X639734Y283332D01*
X628083D01*
X612102Y267351D01*
X587174D01*
X576197Y256374D01*
X574095D01*
X574079Y256390D01*
X564311D01*
X563936Y256765D01*
G01X521593Y256771D02*
X520200Y258164D01*
Y258300D01*
X519200Y259300D01*
X517000D01*
X516200Y260100D01*
Y261400D01*
X514900Y262700D01*
X509200D01*
X505862Y259362D01*
X504188D01*
X501452Y262098D01*
Y262996D01*
G01X695790Y351300D02*
X693075Y348585D01*
X691510D01*
X689292Y346367D01*
X668346D01*
X659553Y337574D01*
X656632D01*
X649653Y330595D01*
Y295507D01*
X648183Y294037D01*
X644437D01*
X642300Y291900D01*
X637100D01*
X635040Y289840D01*
X633775D01*
X631982Y288047D01*
X630549D01*
X629188Y289408D01*
X627669D01*
X610172Y271911D01*
X574396D01*
X574390Y271905D01*
X564605D01*
X559400Y266700D01*
X557900D01*
Y266755D01*
X556184Y268471D01*
X555229D01*
X553000Y270700D01*
X551300D01*
X549428Y268828D01*
X547600D01*
X546044Y267272D01*
X544528D01*
X543100Y268700D01*
X540800D01*
X538875Y266775D01*
X537600D01*
X535575Y268800D01*
X534500D01*
X532700Y267000D01*
X530900D01*
X529100Y268800D01*
X528167D01*
X526639Y267272D01*
X525000D01*
X522328Y264600D01*
X520800D01*
X519200Y263000D01*
X516700D01*
X515600Y264100D01*
X507885D01*
X504832Y261047D01*
G01X595070Y447970D02*
X592068D01*
X590251Y446153D01*
Y444264D01*
X592410Y442105D01*
X616595D01*
X676900Y381800D01*
G01X1298422Y74000D02*
X1298324D01*
X1296602Y72278D01*
Y63302D01*
X1295302Y62002D01*
Y25542D01*
X1294052Y24292D01*
Y17572D01*
X1295500Y16124D01*
Y7700D01*
X1289100Y1300D01*
X1284700D01*
X1280352Y-3048D01*
Y-13740D01*
X1280676Y-14064D01*
Y-16824D01*
X1275854Y-21646D01*
X714603D01*
X707600Y-14643D01*
Y-2500D01*
X706150Y-1050D01*
Y350D01*
X697736Y8764D01*
X684064D01*
X680100Y4800D01*
X671378D01*
X663452Y-3126D01*
Y-3912D01*
X661812Y-5552D01*
X660448D01*
X657825Y-8175D01*
Y-19634D01*
X656807Y-20652D01*
G01X1311551Y93952D02*
X1305062Y87463D01*
X1297425D01*
X1290898Y80936D01*
X1282200D01*
X1275943Y74679D01*
Y2543D01*
X1272600Y-800D01*
Y-6540D01*
X1266564Y-12576D01*
X1031566D01*
X1028419Y-9429D01*
X1021147D01*
X1018477Y-12099D01*
X1003781D01*
X1003249Y-12631D01*
X759702D01*
X750919Y-3848D01*
Y-2478D01*
X747637Y804D01*
X741547D01*
X740843Y100D01*
X731570D01*
X726448Y5222D01*
Y5452D01*
X726413Y5487D01*
Y14805D01*
X723038Y18180D01*
X717791D01*
X717627Y18016D01*
X696903D01*
X694587Y20332D01*
X694567D01*
X693976Y20923D01*
Y21453D01*
X692339Y23090D01*
X677944D01*
X672854Y18000D01*
X660602D01*
X653828Y11226D01*
Y6691D01*
X650037Y2900D01*
X631400D01*
X625500Y-3000D01*
X623000D01*
G01X624770Y-640D02*
X629510Y4100D01*
X649607D01*
X652676Y7169D01*
Y12094D01*
X659982Y19400D01*
X672499D01*
X679641Y26542D01*
X691129D01*
X694923Y22748D01*
X703502D01*
X706918Y19332D01*
X723516D01*
X727600Y15248D01*
Y5700D01*
X732048Y1252D01*
X739500D01*
X740348Y2100D01*
X747971D01*
X751535Y-1464D01*
X752236D01*
X753200Y-2428D01*
X756828D01*
X759500Y-5100D01*
X770750D01*
X777129Y-11479D01*
X1002771D01*
X1006050Y-8200D01*
X1019849D01*
X1020478Y-7571D01*
X1020562D01*
X1021518Y-6615D01*
X1028639D01*
G01X711791Y23716D02*
Y27209D01*
X705200Y33800D01*
X673700D01*
X668100Y39400D01*
X650800D01*
X646000Y44200D01*
X634400D01*
X629800Y48800D01*
Y91900D01*
X633365Y95465D01*
X670915D01*
X688864Y113414D01*
Y134236D01*
X680696Y142404D01*
Y187776D01*
X674420Y194052D01*
Y200083D01*
X680973Y206636D01*
Y238921D01*
X685152Y243100D01*
Y248458D01*
X682338Y251272D01*
X671228D01*
X662348Y260152D01*
X654152D01*
X653200Y259200D01*
X633800D01*
X628900Y264100D01*
Y275768D01*
X629843Y276711D01*
Y276723D01*
X631117Y277997D01*
X631129D01*
X631367Y278235D01*
X642620D01*
X645081Y280696D01*
Y281793D01*
X645080Y281794D01*
Y283509D01*
X656300Y294729D01*
Y300900D01*
X664800Y309400D01*
X682500D01*
X683000Y309900D01*
Y328040D01*
X699925Y344965D01*
Y360545D01*
X696600Y363870D01*
Y369000D01*
X695000Y370600D01*
Y488340D01*
X698728Y492068D01*
Y501491D01*
X691895Y508324D01*
X666220D01*
X663494Y505598D01*
X634156D01*
X628956Y510798D01*
Y554542D01*
X634568Y560154D01*
X656738D01*
X666457Y569873D01*
X677000D01*
X678418Y571291D01*
X694776D01*
X698465Y574980D01*
X728549D01*
X729579Y573950D01*
X732600D01*
G01X670400Y26100D02*
X671500D01*
X672821Y27421D01*
Y29667D01*
X670466Y32022D01*
X667978D01*
X661800Y38200D01*
X650302D01*
X645454Y43048D01*
X634878D01*
X634877Y43047D01*
X633923D01*
X628648Y48322D01*
Y92748D01*
X632121Y96221D01*
X670041D01*
X687658Y113838D01*
Y132691D01*
X679944Y140405D01*
Y187464D01*
X673668Y193740D01*
Y200395D01*
X680221Y206948D01*
Y240051D01*
X684000Y243830D01*
Y247980D01*
X681860Y250120D01*
X670750D01*
X661870Y259000D01*
X654630D01*
X653678Y258048D01*
X633152D01*
X627700Y263500D01*
Y276198D01*
X628691Y277189D01*
Y277201D01*
X630639Y279149D01*
X630651D01*
X630937Y279435D01*
X642189D01*
X642317Y279563D01*
X642318D01*
X643241Y280486D01*
Y280487D01*
X643928Y281174D01*
Y283421D01*
X652800Y292293D01*
Y302200D01*
X661300Y310700D01*
X680800D01*
X681300Y311200D01*
Y327970D01*
X698773Y345443D01*
Y359445D01*
X695385Y362833D01*
Y368585D01*
X693848Y370122D01*
Y414652D01*
X692176Y416324D01*
Y487146D01*
X697576Y492546D01*
Y501470D01*
X691474Y507572D01*
X666532D01*
X663806Y504846D01*
X633760D01*
X628203Y510403D01*
Y554853D01*
X634257Y560907D01*
X656427D01*
X666145Y570625D01*
X676625D01*
X678255Y572255D01*
X683785D01*
X689006Y577476D01*
X691624D01*
X693200Y575900D01*
G01X670503Y115884D02*
Y114908D01*
X653140Y97545D01*
X634271D01*
X633535Y98281D01*
X626040D01*
G01X631250Y289650D02*
X632592Y290992D01*
X634445D01*
X636505Y293052D01*
X641222D01*
X642959Y294789D01*
X646980D01*
X648501Y296310D01*
Y331445D01*
X662075Y345019D01*
X665049D01*
X667200Y347170D01*
Y355400D01*
X675140Y363340D01*
Y370140D01*
X680638Y375638D01*
Y384693D01*
X679523Y385808D01*
G01X687427Y384926D02*
Y371763D01*
X693595Y365595D01*
Y361983D01*
X697621Y357957D01*
Y345667D01*
X696217Y344263D01*
X669219D01*
X656578Y331622D01*
X654892D01*
X651802Y328532D01*
Y292359D01*
X641607Y282164D01*
Y281139D01*
G01D02*
X641665D01*
G01X711339Y499478D02*
X708978Y501839D01*
X700508D01*
X692377Y509970D01*
X678881D01*
X676171Y512680D01*
X668448D01*
X662871Y507103D01*
X635104D01*
X630721Y511486D01*
Y554179D01*
X635192Y558650D01*
X657362D01*
X667081Y568369D01*
X677624D01*
X678969Y569714D01*
X695327D01*
X699089Y573476D01*
X727925D01*
X730342Y571059D01*
X733596D01*
X743937Y581400D01*
X745879D01*
X758559Y594080D01*
Y605501D01*
X768158Y615100D01*
X1029067D01*
X1029124Y615157D01*
X1030430D01*
X1030487Y615100D01*
X1035985D01*
X1036066Y615181D01*
X1039528D01*
X1039609Y615100D01*
X1039620D01*
X1043638Y611082D01*
X1045501D01*
X1045859Y611440D01*
X1048560D01*
X1048918Y611082D01*
X1052546D01*
X1052904Y611440D01*
X1056036D01*
X1056395Y611081D01*
X1059177D01*
X1059536Y611440D01*
X1062491D01*
X1062850Y611081D01*
X1065852D01*
X1066211Y611440D01*
X1069223D01*
X1069679Y610984D01*
X1072164D01*
X1072620Y611440D01*
X1076064D01*
X1076423Y611081D01*
X1078813D01*
X1079172Y611440D01*
X1082938D01*
X1083297Y611081D01*
X1086119D01*
X1086478Y611440D01*
X1089169D01*
X1089628Y610981D01*
X1092281D01*
X1092740Y611440D01*
X1095984D01*
X1096401Y611023D01*
X1102367D01*
X1103220Y611876D01*
X1105600D01*
X1106403Y611073D01*
X1108527D01*
X1112839Y615385D01*
X1266288D01*
X1275528Y606145D01*
Y580318D01*
X1274409Y579199D01*
Y545764D01*
X1276700Y543473D01*
Y541500D01*
X1275478Y540278D01*
Y536822D01*
X1277244Y535056D01*
Y528715D01*
X1281853Y524106D01*
Y517901D01*
X1280777Y516825D01*
Y507410D01*
X1282818Y505369D01*
Y503526D01*
X1287046Y499298D01*
Y489943D01*
X1281731Y484628D01*
Y466980D01*
X1280382Y465631D01*
Y457682D01*
X1276635Y453935D01*
Y361671D01*
X1304396Y333910D01*
Y323935D01*
X1314064Y314267D01*
Y292736D01*
X1319348Y287452D01*
X1326876D01*
X1333572Y280756D01*
X1335299D01*
X1338419Y277636D01*
X1359023D01*
X1361915Y274744D01*
X1388146D01*
X1388914Y275512D01*
X1392416D01*
X1394686Y273242D01*
X1394687D01*
X1394691Y273238D01*
X1408014D01*
X1412825Y278049D01*
X1427475D01*
X1430918Y274606D01*
Y273417D01*
X1443035Y261300D01*
X1448300D01*
X1451476Y258124D01*
X1454653D01*
X1455576Y259047D01*
Y260974D01*
X1454350Y262200D01*
G01X623600Y521700D02*
X624943Y523043D01*
Y552657D01*
X633965Y561679D01*
X656071D01*
X665770Y571378D01*
X676213D01*
X678107Y573272D01*
X683162D01*
X688930Y579040D01*
Y580471D01*
X700759Y592300D01*
X713587D01*
X719188Y597901D01*
Y609861D01*
X722827Y613500D01*
X736582D01*
X743719Y620637D01*
X1042472D01*
X1043754Y619355D01*
X1105325D01*
X1107115Y621145D01*
X1285814D01*
X1295181Y611778D01*
Y586456D01*
X1286525Y577800D01*
X1283630D01*
X1279552Y573722D01*
Y562753D01*
X1283800Y558505D01*
X1290148D01*
X1294029Y554624D01*
Y549506D01*
X1294028Y549505D01*
Y548883D01*
X1294029Y548882D01*
Y548501D01*
X1303100Y539430D01*
Y533672D01*
X1306136Y530636D01*
Y509850D01*
X1292450Y496164D01*
Y490000D01*
X1292800Y489650D01*
Y444225D01*
X1289185Y440610D01*
Y360458D01*
X1311389Y338254D01*
Y325678D01*
X1323142Y313925D01*
Y309608D01*
X1325731Y307019D01*
Y294040D01*
X1331671Y288100D01*
X1335201D01*
X1336976Y286325D01*
Y284195D01*
X1340327Y280844D01*
X1360071D01*
X1363163Y277752D01*
X1386898D01*
X1387666Y278520D01*
X1393664D01*
X1395934Y276250D01*
X1395935D01*
X1395939Y276246D01*
X1406766D01*
X1411606Y281086D01*
X1430186D01*
X1436298Y287198D01*
X1443301D01*
X1445454Y289351D01*
G01X1451850Y262200D02*
X1450314Y263736D01*
X1443351D01*
X1443350Y263735D01*
X1442728D01*
X1432422Y274041D01*
Y275230D01*
X1428070Y279582D01*
X1412230D01*
X1407390Y274742D01*
X1395315D01*
X1395311Y274746D01*
X1395310D01*
X1393040Y277016D01*
X1388290D01*
X1387522Y276248D01*
X1362539D01*
X1359447Y279340D01*
X1338843D01*
X1335923Y282260D01*
X1334240D01*
X1323475Y293025D01*
Y306083D01*
X1320358Y309200D01*
Y313328D01*
X1308404Y325282D01*
Y336349D01*
X1280643Y364110D01*
Y453554D01*
X1283390Y456301D01*
Y463660D01*
X1285138Y465408D01*
Y482302D01*
X1290187Y487351D01*
Y497093D01*
X1303880Y510786D01*
Y529700D01*
X1300444Y533136D01*
Y536945D01*
X1295192Y542197D01*
X1285586D01*
X1277032Y550751D01*
Y607901D01*
X1267244Y617689D01*
X1109089D01*
X1107299Y615899D01*
X1042320D01*
X1041199Y617020D01*
X752520D01*
X750919Y615419D01*
Y605810D01*
X737352Y592243D01*
Y581592D01*
X734400Y578640D01*
Y573489D01*
X733285Y572374D01*
X730091D01*
X728237Y574228D01*
X698777D01*
X695088Y570539D01*
X678730D01*
X677312Y569121D01*
X666769D01*
X657050Y559402D01*
X634880D01*
X629968Y554490D01*
Y511067D01*
X634685Y506350D01*
X663182D01*
X668535Y511703D01*
X676084D01*
X678637Y509150D01*
X692133D01*
X699800Y501483D01*
Y489100D01*
X698300Y487600D01*
Y397800D01*
X696500Y396000D01*
Y387500D01*
X695960Y386960D01*
Y372189D01*
X701077Y367072D01*
Y344277D01*
X697000Y340200D01*
Y337500D01*
X693500Y334000D01*
Y331400D01*
X687300Y325200D01*
G01X670227Y34277D02*
X672204Y32300D01*
X688579D01*
X695879Y25000D01*
X703099D01*
X706899Y21200D01*
X723749D01*
X727543Y17406D01*
Y17380D01*
X728752Y16171D01*
Y14701D01*
X740201Y3252D01*
X748449D01*
X749402Y2299D01*
X763550D01*
X763970Y1879D01*
X778345D01*
X778404Y1938D01*
X1007200D01*
X1009200Y-62D01*
Y-3600D01*
X1009900Y-4300D01*
X1019600D01*
X1020369Y-3531D01*
X1028844D01*
X1034683Y2308D01*
X1040152D01*
X1041056Y1404D01*
X1267757D01*
X1273287Y6934D01*
Y89587D01*
X1285000Y101300D01*
X1301770D01*
G01X753675Y23239D02*
X755762Y25326D01*
Y27650D01*
X759056Y30944D01*
Y75168D01*
X753312Y80912D01*
X740488D01*
X736852Y84548D01*
X730252D01*
X727322Y87478D01*
Y102031D01*
X681848Y147505D01*
Y187688D01*
X675172Y194364D01*
Y199771D01*
X683447Y208046D01*
Y236794D01*
X696536Y249883D01*
Y262659D01*
X692616Y266579D01*
Y280967D01*
X691538Y282045D01*
X691040D01*
X690048Y281053D01*
G01Y284053D02*
X691001Y283100D01*
X691830D01*
X693568Y281362D01*
Y266691D01*
X697288Y262971D01*
Y249571D01*
X684200Y236483D01*
Y207735D01*
X675924Y199459D01*
Y194676D01*
X682800Y187800D01*
Y147900D01*
X728274Y102426D01*
Y87590D01*
X730564Y85300D01*
X737164D01*
X740800Y81664D01*
X753624D01*
X759979Y75309D01*
Y30520D01*
X756714Y27255D01*
Y23130D01*
G01X1249230Y402022D02*
Y402039D01*
X1245513Y405756D01*
Y439387D01*
X1270700Y464574D01*
Y467050D01*
X1274406Y470756D01*
Y490624D01*
X1274240Y490790D01*
Y493881D01*
X1276161Y495802D01*
Y502953D01*
X1266800Y512314D01*
Y548581D01*
X1260200Y555181D01*
Y575350D01*
X1253050Y582500D01*
X1198930D01*
X1195700Y585730D01*
Y593589D01*
X1190219Y599070D01*
X1131976D01*
X1126176Y593270D01*
Y589948D01*
X1119281Y583053D01*
X1036067D01*
X1031823Y587297D01*
Y594654D01*
X1027583Y598894D01*
X901953D01*
X898930Y595871D01*
Y585299D01*
X898597Y584966D01*
Y584962D01*
X897557Y583922D01*
X897553D01*
X897251Y583620D01*
X764631D01*
X757950Y576939D01*
Y460666D01*
X722727Y425443D01*
Y412493D01*
X720000Y409766D01*
Y324767D01*
X708906Y313673D01*
Y309414D01*
X707693Y308201D01*
X704333D01*
X700028Y303896D01*
Y298256D01*
X696780Y295008D01*
Y272705D01*
X705496Y263989D01*
Y256890D01*
X707896Y254490D01*
Y254466D01*
X716162Y246200D01*
X723389D01*
X726328Y249139D01*
Y249979D01*
G01X1243399Y398339D02*
X1241550Y400188D01*
Y440587D01*
X1248916Y447953D01*
Y451796D01*
X1250166Y453046D01*
Y453544D01*
X1248171Y455539D01*
Y456037D01*
X1248669Y456535D01*
X1249167D01*
X1251162Y454540D01*
X1251660D01*
X1252158Y455038D01*
Y455536D01*
X1250163Y457531D01*
Y458029D01*
X1250661Y458527D01*
X1251159D01*
X1253154Y456532D01*
X1253652D01*
X1254150Y457030D01*
Y457528D01*
X1252155Y459523D01*
Y460021D01*
X1252653Y460519D01*
X1253151D01*
X1255146Y458524D01*
X1255644D01*
X1256142Y459022D01*
Y459520D01*
X1254147Y461515D01*
Y462013D01*
X1254645Y462511D01*
X1255143D01*
X1257138Y460516D01*
X1257636D01*
X1258134Y461014D01*
Y461512D01*
X1256139Y463507D01*
Y464005D01*
X1265234Y473100D01*
Y489689D01*
X1272714Y497169D01*
Y501458D01*
X1267293Y506879D01*
X1262860D01*
X1260235Y509504D01*
Y548415D01*
X1259117Y549533D01*
X1258502D01*
X1253347Y554688D01*
Y575510D01*
X1250857Y578000D01*
X1193149D01*
X1185918Y585231D01*
Y592150D01*
X1182578Y595490D01*
X1136209D01*
X1132869Y592150D01*
Y586656D01*
X1133075Y586450D01*
Y584978D01*
X1127746Y579649D01*
X1034657D01*
X1028370Y585936D01*
Y593242D01*
X1026122Y595490D01*
X911996D01*
X908656Y592150D01*
Y587244D01*
X908862Y587038D01*
Y584978D01*
X904100Y580216D01*
X766446D01*
X761724Y575494D01*
Y459626D01*
X726131Y424033D01*
Y411083D01*
X723600Y408552D01*
Y323501D01*
X712310Y312211D01*
Y308004D01*
X708949Y304643D01*
X705589D01*
X703432Y302486D01*
Y296846D01*
X700324Y293738D01*
Y273975D01*
X708900Y265399D01*
Y258300D01*
X715130Y252070D01*
X718330D01*
X720450Y249950D01*
G01X723400Y250000D02*
X721460Y248060D01*
X716733D01*
X707198Y257595D01*
Y264694D01*
X698500Y273392D01*
Y294321D01*
X701730Y297551D01*
Y303191D01*
X704931Y306392D01*
X708291D01*
X710608Y308709D01*
Y312916D01*
X721800Y324108D01*
Y409159D01*
X724429Y411788D01*
Y424738D01*
X760022Y460331D01*
Y576199D01*
X765741Y581918D01*
X900627D01*
X903830Y585121D01*
Y592730D01*
X908292Y597192D01*
X1026878D01*
X1030120Y593950D01*
Y586593D01*
X1035362Y581351D01*
X1122818D01*
X1129728Y588261D01*
Y592150D01*
X1129700Y592178D01*
Y594387D01*
X1132505Y597192D01*
X1186808D01*
X1190500Y593500D01*
Y585727D01*
X1196027Y580200D01*
X1252800D01*
X1256888Y576112D01*
Y555109D01*
X1263581Y548416D01*
Y509504D01*
X1264504Y508581D01*
X1265248D01*
X1265249Y508582D01*
X1268033D01*
X1274437Y502178D01*
Y496485D01*
X1266936Y488984D01*
Y472964D01*
X1268998Y470902D01*
Y465279D01*
X1262380Y458661D01*
X1261882D01*
X1260292Y460251D01*
X1259794D01*
X1259296Y459753D01*
Y459255D01*
X1260886Y457665D01*
Y457167D01*
X1260388Y456669D01*
X1259890D01*
X1258300Y458259D01*
X1257802D01*
X1257304Y457761D01*
Y457263D01*
X1258894Y455673D01*
Y455175D01*
X1258396Y454677D01*
X1257898D01*
X1256308Y456267D01*
X1255810D01*
X1255312Y455769D01*
Y455271D01*
X1256902Y453681D01*
Y453183D01*
X1256404Y452685D01*
X1255906D01*
X1254316Y454275D01*
X1253818D01*
X1253320Y453777D01*
Y453279D01*
X1254910Y451689D01*
Y451191D01*
X1254412Y450693D01*
X1253914D01*
X1252324Y452283D01*
X1251826D01*
X1251328Y451785D01*
Y451287D01*
X1252918Y449697D01*
Y449199D01*
X1243755Y440036D01*
Y402365D01*
X1246010Y400110D01*
G01X695700Y357300D02*
X692400Y360600D01*
Y365160D01*
X685851Y371709D01*
Y389243D01*
X691616Y395008D01*
Y413084D01*
X689024Y415676D01*
Y485624D01*
X691401Y488001D01*
Y497799D01*
X691000Y498200D01*
G01X695644Y354644D02*
X691000Y359288D01*
Y364930D01*
X684699Y371231D01*
Y387599D01*
X677300Y394998D01*
Y479270D01*
X688202Y490172D01*
Y497736D01*
G01X712100Y512700D02*
X713800Y511000D01*
X717842D01*
X720142Y513300D01*
X726200D01*
X738173Y525273D01*
X747492D01*
X751085Y528866D01*
Y581506D01*
X759711Y590132D01*
Y605023D01*
X768913Y614225D01*
X1023675D01*
X1036448Y601452D01*
X1040826D01*
X1046497Y607123D01*
X1048223D01*
X1049968Y608868D01*
X1052300D01*
X1052880Y608288D01*
X1055771D01*
X1056351Y608868D01*
X1059076D01*
X1059656Y608288D01*
X1062468D01*
X1063048Y608868D01*
X1065756D01*
X1066336Y608288D01*
X1069133D01*
X1069713Y608868D01*
X1072468D01*
X1073048Y608288D01*
X1075684D01*
X1076264Y608868D01*
X1079037D01*
X1079617Y608288D01*
X1082443D01*
X1083023Y608868D01*
X1085750D01*
X1086330Y608288D01*
X1089044D01*
X1089624Y608868D01*
X1092558D01*
X1093138Y608288D01*
X1095612D01*
X1096120Y608796D01*
X1099069D01*
X1099141Y608724D01*
X1111173D01*
X1112300Y609851D01*
Y612788D01*
X1113745Y614233D01*
X1265810D01*
X1274776Y605267D01*
Y581196D01*
X1273657Y580077D01*
Y545452D01*
X1275948Y543161D01*
Y541812D01*
X1274726Y540590D01*
Y536510D01*
X1276492Y534744D01*
Y528403D01*
X1281101Y523794D01*
Y518213D01*
X1280025Y517137D01*
Y507098D01*
X1282066Y505057D01*
Y503156D01*
X1286294Y498928D01*
Y490255D01*
X1280979Y484940D01*
Y467388D01*
X1279419Y465828D01*
Y457816D01*
X1274349Y452746D01*
Y362893D01*
X1303644Y333598D01*
Y323623D01*
X1313312Y313955D01*
Y292424D01*
X1319036Y286700D01*
X1326564D01*
X1333260Y280004D01*
X1334987D01*
X1338956Y276035D01*
X1359560D01*
X1361728Y273867D01*
X1388333D01*
X1389226Y274760D01*
X1392104D01*
X1394374Y272490D01*
X1394375D01*
X1394379Y272486D01*
X1408326D01*
X1413079Y277239D01*
X1427221D01*
X1430166Y274294D01*
Y273105D01*
X1442724Y260547D01*
X1447989D01*
X1451164Y257372D01*
X1459272D01*
X1460800Y255844D01*
Y253800D01*
X1465087Y249513D01*
X1479013D01*
X1483920Y254420D01*
X1485277D01*
X1485843Y254986D01*
X1487135D01*
X1490175Y251946D01*
X1490840D01*
X1490841Y251945D01*
X1491463D01*
X1491464Y251946D01*
X1500646D01*
X1503132Y254432D01*
X1505946D01*
G01X707850Y505700D02*
X710050Y507900D01*
X716600D01*
X717300Y507200D01*
X721900D01*
X739065Y524365D01*
X747985D01*
X752258Y528638D01*
Y581452D01*
X773599Y602793D01*
X1032607D01*
X1035100Y600300D01*
X1041304D01*
X1043497Y602493D01*
X1044063D01*
X1044424Y602854D01*
X1265503D01*
X1273480Y594877D01*
Y584709D01*
X1271224Y582453D01*
Y537884D01*
X1274988Y534120D01*
Y519212D01*
X1278521Y515679D01*
Y506474D01*
X1280562Y504433D01*
Y502192D01*
X1284790Y497964D01*
Y490879D01*
X1279475Y485564D01*
Y468364D01*
X1277257Y466146D01*
Y459041D01*
X1271352Y453136D01*
Y391834D01*
X1271480Y391706D01*
Y361240D01*
X1300304Y332416D01*
Y324835D01*
X1311808Y313331D01*
Y291800D01*
X1319008Y284600D01*
X1326101D01*
X1330039Y280662D01*
Y279618D01*
G01X1335400Y284900D02*
X1333728D01*
X1324979Y293649D01*
Y306707D01*
X1322364Y309322D01*
Y313540D01*
X1310308Y325596D01*
Y337705D01*
X1288433Y359580D01*
Y440922D01*
X1291994Y444483D01*
Y476205D01*
X1288100Y480099D01*
Y483136D01*
X1291691Y486727D01*
Y496469D01*
X1305384Y510162D01*
Y530324D01*
X1302300Y533408D01*
Y538349D01*
X1296148Y544501D01*
X1285410D01*
X1278536Y551375D01*
Y574336D01*
X1283152Y578952D01*
X1286047D01*
X1294029Y586934D01*
Y611300D01*
X1285336Y619993D01*
X1107593D01*
X1105803Y618203D01*
X1043276D01*
X1041994Y619485D01*
X744222D01*
X735021Y610284D01*
Y594120D01*
X729301Y588400D01*
X714100D01*
X701600Y575900D01*
X693200D01*
G01X1337200Y292012D02*
Y292000D01*
X1335250Y293950D01*
X1334077D01*
X1329951Y298076D01*
Y307055D01*
X1327417Y309589D01*
Y321469D01*
X1315197Y333722D01*
Y340703D01*
X1292263Y363637D01*
Y430404D01*
X1292264Y430405D01*
Y433173D01*
X1292263Y433174D01*
Y439432D01*
X1295858Y443027D01*
Y484651D01*
X1298485Y487278D01*
X1300804D01*
X1304355Y490829D01*
Y496021D01*
X1318000Y509666D01*
Y518678D01*
X1315040Y521638D01*
Y536700D01*
X1313785Y537955D01*
Y544186D01*
X1309192Y548779D01*
X1300256D01*
X1298079Y550956D01*
Y584449D01*
X1301300Y587670D01*
Y604300D01*
X1299652Y605948D01*
Y619898D01*
X1295847Y623703D01*
X1105703D01*
X1103659Y621659D01*
X1044983D01*
X1044252Y622390D01*
X1043413D01*
X1043262Y622541D01*
X742562D01*
X742411Y622390D01*
X741389D01*
X734425Y615426D01*
X716074D01*
X713500Y618000D01*
G01X711500Y616274D02*
X713500Y614274D01*
X735359D01*
X742874Y621789D01*
X1042950D01*
X1044232Y620507D01*
X1104137D01*
X1105927Y622297D01*
X1295304D01*
X1298500Y619101D01*
Y605470D01*
X1299676Y604294D01*
Y587676D01*
X1296927Y584927D01*
Y550475D01*
X1299775Y547627D01*
X1308714D01*
X1312570Y543771D01*
Y537630D01*
X1314200Y536000D01*
Y520652D01*
X1316848Y518004D01*
Y509578D01*
X1303603Y496333D01*
Y491141D01*
X1300492Y488030D01*
X1298797D01*
X1298796Y488031D01*
X1298174D01*
X1295106Y484963D01*
Y443339D01*
X1291511Y439744D01*
Y361890D01*
X1314045Y339356D01*
Y333177D01*
X1325798Y321391D01*
Y310144D01*
X1329199Y306743D01*
Y297251D01*
X1334400Y292050D01*
G01X754600Y300D02*
X755424Y-524D01*
X760039D01*
X761149Y586D01*
X999520D01*
X1003710Y-3604D01*
X1006504D01*
X1008367Y-5467D01*
X1019972D01*
X1021156Y-4283D01*
X1029538D01*
X1033021Y-800D01*
X1033036D01*
X1035392Y1556D01*
X1039840D01*
X1040744Y652D01*
X1268069D01*
X1274039Y6622D01*
Y88239D01*
X1285900Y100100D01*
X1296400D01*
X1300618Y95882D01*
X1308112D01*
X1308972Y96742D01*
G01X751900Y400D02*
X752100D01*
X753776Y-1276D01*
X760351D01*
X761461Y-166D01*
X999208D01*
X1003398Y-4356D01*
X1006192D01*
X1008055Y-6219D01*
X1020284D01*
X1021468Y-5035D01*
X1029865D01*
X1035704Y804D01*
X1039528D01*
X1040432Y-100D01*
X1268381D01*
X1274791Y6310D01*
Y87644D01*
X1286295Y99148D01*
X1296253D01*
X1300371Y95030D01*
X1307767D01*
X1308983Y93814D01*
G01X1144300Y274696D02*
X1145900Y273096D01*
Y225506D01*
X1147596Y223810D01*
X1148138D01*
X1149948Y222000D01*
X1151377D01*
X1153377Y220000D01*
X1155000D01*
X1157000Y218000D01*
X1158500D01*
X1160331Y216169D01*
X1161831D01*
X1163000Y215000D01*
Y211500D01*
X1164000Y210500D01*
X1165500D01*
X1167500Y208500D01*
X1169000D01*
X1173000Y204500D01*
X1175500D01*
X1233463Y146537D01*
X1240500D01*
X1247637Y139400D01*
X1250700D01*
X1259700Y130400D01*
Y120200D01*
X1258049Y118549D01*
X1256349D01*
X1255700Y117900D01*
Y110000D01*
X1258600Y107100D01*
X1262300D01*
X1263100Y106300D01*
X1272119D01*
X1273076Y105343D01*
Y101276D01*
X1271926Y100126D01*
Y97427D01*
X1270499Y96000D01*
X1262000D01*
X1260200Y94200D01*
Y15700D01*
X1256700Y12200D01*
Y8100D01*
X1256008Y7408D01*
X1050092D01*
X1049286Y8214D01*
Y18544D01*
X1048371Y19459D01*
X1044217D01*
X1042576Y21100D01*
X1034200D01*
X1020400Y7300D01*
X770500D01*
X770219Y7581D01*
X767819D01*
X760100Y15300D01*
X756955D01*
X755000Y17255D01*
G01X1174719Y268847D02*
X1170796D01*
X1170452Y269191D01*
G01X920364Y318549D02*
X919628D01*
X917379Y316300D01*
X908246D01*
X907878Y316668D01*
X897973D01*
X854701Y359940D01*
Y378149D01*
X854006Y379886D01*
X853837Y380056D01*
X848514Y385379D01*
X840235D01*
X825576Y400038D01*
Y403516D01*
X824653Y404439D01*
X821380D01*
X771930Y453889D01*
Y454164D01*
X766852Y459242D01*
Y515240D01*
X763794Y518298D01*
Y521986D01*
X763544Y522236D01*
G01X920226Y317730D02*
X919896D01*
X917682Y315516D01*
X897495D01*
X853549Y359462D01*
Y377673D01*
X853350Y378170D01*
X852853Y379409D01*
X848036Y384227D01*
X839757D01*
X770778Y453206D01*
Y453686D01*
X765700Y458764D01*
Y512256D01*
X763706Y514250D01*
G01X762989Y411728D02*
X763177Y411540D01*
X768211D01*
X769097Y412426D01*
X776905D01*
X778593Y410738D01*
X788432D01*
X795224Y417530D01*
X800913D01*
X813200Y405243D01*
Y400368D01*
X817246Y396322D01*
Y377870D01*
X818707Y376409D01*
Y366607D01*
X820476Y364838D01*
X834646D01*
X845107Y354377D01*
X851570D01*
X895650Y310297D01*
X914714D01*
X917613Y307398D01*
G01X763069Y414441D02*
X765176Y412334D01*
X767941D01*
X768785Y413178D01*
X777713D01*
X779401Y411490D01*
X788120D01*
X794930Y418300D01*
X801326D01*
X814500Y405126D01*
Y400606D01*
X818095Y397011D01*
Y378543D01*
X823353Y373285D01*
X837146D01*
X840300Y370131D01*
Y361700D01*
X846552Y355448D01*
X851563D01*
X895962Y311049D01*
X915026D01*
X918145Y307930D01*
G01X768080Y418780D02*
X778618Y429318D01*
X787652D01*
X796340Y420630D01*
X802204D01*
X834882Y387952D01*
Y381271D01*
X852112Y364041D01*
Y358624D01*
X896214Y314522D01*
X918234D01*
G01X922031Y309360D02*
X921155Y310236D01*
X919823D01*
X917577Y312482D01*
X895593D01*
X850258Y357817D01*
Y363615D01*
X832545Y381328D01*
Y388145D01*
X801564Y419126D01*
X795544D01*
X786890Y427780D01*
X779777D01*
X772146Y420149D01*
Y418170D01*
X768373Y414397D01*
X766394D01*
G01X766200Y417005D02*
X767605Y415600D01*
X768366D01*
X771336Y418570D01*
Y420710D01*
X779192Y428566D01*
X787236D01*
X795924Y419878D01*
X801892D01*
X833297Y388473D01*
Y381640D01*
X851010Y363927D01*
Y358129D01*
X895538Y313601D01*
G01X1479000Y254500D02*
X1478610Y254890D01*
X1468939D01*
X1465929Y257900D01*
X1461276D01*
X1455348Y263828D01*
X1451286D01*
X1450626Y264488D01*
X1443039D01*
X1433424Y274103D01*
Y275292D01*
X1428382Y280334D01*
X1411918D01*
X1407078Y275494D01*
X1395627D01*
X1395623Y275498D01*
X1395622D01*
X1393352Y277768D01*
X1387978D01*
X1387210Y277000D01*
X1362851D01*
X1359759Y280092D01*
X1339155D01*
X1336235Y283012D01*
X1334552D01*
X1324227Y293337D01*
Y306395D01*
X1321576Y309046D01*
Y313264D01*
X1309156Y325684D01*
Y337227D01*
X1283299Y363084D01*
Y455146D01*
X1284142Y455989D01*
Y463302D01*
X1285890Y465050D01*
Y481990D01*
X1290939Y487039D01*
Y496781D01*
X1304632Y510474D01*
Y530012D01*
X1301376Y533268D01*
Y537077D01*
X1295104Y543349D01*
X1285498D01*
X1277784Y551063D01*
Y608213D01*
X1267556Y618441D01*
X1107671D01*
X1106681Y617451D01*
X1042398D01*
X1042077Y617772D01*
X744139D01*
X736200Y609833D01*
Y582070D01*
X732600Y578470D01*
Y573950D01*
G01X763450Y585200D02*
X763974Y585724D01*
X766553D01*
X769302Y588473D01*
Y592060D01*
X778131Y600889D01*
X1030411D01*
X1032904Y598396D01*
X1042094D01*
X1045048Y601350D01*
X1264879D01*
X1271976Y594253D01*
Y585899D01*
X1269720Y583643D01*
Y573120D01*
X1266924Y570324D01*
Y552141D01*
X1269404Y549661D01*
Y537496D01*
X1273484Y533416D01*
Y517952D01*
X1276239Y515197D01*
Y506628D01*
X1279058Y503809D01*
Y501568D01*
X1283286Y497340D01*
Y491503D01*
X1277939Y486156D01*
Y469299D01*
X1275753Y467113D01*
Y459665D01*
X1269848Y453760D01*
Y391210D01*
X1269976Y391082D01*
Y359961D01*
X1298400Y331537D01*
Y324610D01*
X1310304Y312706D01*
Y290434D01*
X1312901Y287837D01*
Y285451D01*
X1314490Y283862D01*
G01X1314792Y286427D02*
Y287471D01*
X1311056Y291207D01*
Y313019D01*
X1299152Y324923D01*
Y331314D01*
X1299153Y331315D01*
Y331937D01*
X1270728Y360362D01*
Y391394D01*
X1270600Y391522D01*
Y453448D01*
X1276505Y459353D01*
Y466665D01*
X1278691Y468851D01*
Y485844D01*
X1284038Y491191D01*
Y497652D01*
X1279810Y501880D01*
Y504121D01*
X1276991Y506940D01*
Y515509D01*
X1274236Y518264D01*
Y533808D01*
X1270472Y537572D01*
Y583331D01*
X1272728Y585587D01*
Y594565D01*
X1265191Y602102D01*
X1044736D01*
X1041782Y599148D01*
X1034252D01*
X1031759Y601641D01*
X777819D01*
X768550Y592372D01*
Y589950D01*
X765900Y587300D01*
G01X755900Y593650D02*
X757650Y595400D01*
Y606222D01*
X767418Y615990D01*
X1040599D01*
X1041842Y614747D01*
X1107778D01*
X1109568Y616537D01*
X1266766D01*
X1276280Y607023D01*
Y579440D01*
X1275161Y578321D01*
Y546076D01*
X1280096Y541141D01*
Y538824D01*
X1278096Y536824D01*
Y529063D01*
X1283863Y523296D01*
X1298654D01*
X1301624Y520326D01*
Y511741D01*
X1287850Y497967D01*
Y489683D01*
X1282483Y484316D01*
Y466484D01*
X1281134Y465135D01*
Y457237D01*
X1277387Y453490D01*
Y361983D01*
X1305148Y334222D01*
Y324282D01*
X1314816Y314614D01*
Y293048D01*
X1319660Y288204D01*
X1327188D01*
X1333884Y281508D01*
X1335611D01*
X1338731Y278388D01*
X1359335D01*
X1362227Y275496D01*
X1387834D01*
X1388602Y276264D01*
X1392728D01*
X1394998Y273994D01*
X1394999D01*
X1395003Y273990D01*
X1407702D01*
X1412542Y278830D01*
X1427758D01*
X1431670Y274918D01*
Y273729D01*
X1442416Y262983D01*
X1443662D01*
X1443663Y262984D01*
X1448366D01*
X1451650Y259700D01*
X1454000D01*
G01X957283Y92657D02*
Y95100D01*
X961500Y99317D01*
Y109028D01*
X986700Y134228D01*
Y181501D01*
X985500Y182701D01*
Y197600D01*
X985850Y197950D01*
Y200350D01*
X985500Y200700D01*
Y214200D01*
X983400Y216300D01*
Y221400D01*
X985000Y223000D01*
X986000D01*
X988446Y225446D01*
Y230560D01*
G01X1026700Y1700D02*
X1032400Y7400D01*
Y17370D01*
X1034878Y19848D01*
X1039384D01*
X1042400Y16832D01*
Y11000D01*
X1047100Y6300D01*
X1049429D01*
X1049573Y6156D01*
X1260656D01*
X1263400Y8900D01*
Y93600D01*
X1264500Y94700D01*
X1271000D01*
X1273400Y97100D01*
Y99800D01*
X1274848Y101248D01*
Y107409D01*
X1275879Y109898D01*
X1277247Y111266D01*
X1281192Y112900D01*
X1291996D01*
X1297896Y118800D01*
Y121556D01*
X1300740Y124400D01*
X1301900D01*
G01X1060963Y370959D02*
X1065843D01*
X1068542Y368260D01*
X1073741D01*
X1075280Y366721D01*
X1078228D01*
X1079429Y367922D01*
X1080735D01*
X1081936Y366721D01*
X1084987D01*
X1086188Y367922D01*
X1087494D01*
X1088695Y366721D01*
X1091747D01*
X1092948Y367922D01*
X1094254D01*
X1095455Y366721D01*
X1097255D01*
X1099505Y364471D01*
X1101214D01*
X1102766Y366023D01*
X1104335D01*
X1106314Y364044D01*
X1107851D01*
X1109877Y366070D01*
X1111255D01*
X1112696Y364629D01*
X1115227D01*
X1116699Y366101D01*
X1118236D01*
X1120151Y364186D01*
X1121466D01*
X1123311Y366031D01*
X1124640D01*
X1126453Y364218D01*
X1127968D01*
G01X1139200Y371121D02*
X1140213Y372134D01*
X1141448D01*
X1142589Y373275D01*
Y396219D01*
X1144028Y397658D01*
X1144851D01*
X1155681Y408488D01*
X1163870D01*
X1174084Y418702D01*
X1180869D01*
X1243799Y481632D01*
X1250462D01*
X1253790Y484960D01*
Y494170D01*
X1255101Y495481D01*
Y495881D01*
X1255102Y495882D01*
Y497398D01*
X1261384Y503680D01*
X1267306D01*
X1269209Y501777D01*
G01X1271105Y498516D02*
X1270616Y498027D01*
X1266272D01*
X1264418Y499881D01*
X1262526D01*
X1261032Y498387D01*
Y495188D01*
X1261530Y494690D01*
Y482796D01*
X1256962Y478228D01*
X1245209D01*
X1182279Y415298D01*
X1175498D01*
X1165236Y405036D01*
X1158067D01*
X1152800Y399769D01*
Y391215D01*
X1151285Y389700D01*
X1150743D01*
X1149410Y388367D01*
Y370080D01*
G01X1095548Y359322D02*
X1094437Y360433D01*
G01X1092386D02*
X1090879Y358926D01*
X1088690D01*
X1087494Y360122D01*
G01X1085982D02*
X1084786Y358926D01*
X1081931D01*
X1080735Y360122D01*
G01X1078852D02*
X1077940Y359210D01*
G01X1075380D02*
X1073990Y360600D01*
X1067000D01*
X1064440Y363160D01*
X1061055D01*
G01X1267584Y499694D02*
X1267044Y500234D01*
X1266472D01*
X1264901Y501805D01*
X1261923D01*
X1259237Y499119D01*
Y494353D01*
X1259828Y493762D01*
Y483501D01*
X1256257Y479930D01*
X1244504D01*
X1181574Y417000D01*
X1174789D01*
X1164441Y406652D01*
X1156584D01*
X1150790Y400858D01*
Y398090D01*
X1149350Y396650D01*
Y392686D01*
X1148364Y391700D01*
X1147000D01*
X1146000Y390700D01*
Y370918D01*
X1144953Y369871D01*
X1143647D01*
X1142725Y368949D01*
Y365924D01*
X1141573Y364772D01*
X1140962D01*
X1138261Y362071D01*
X1136887D01*
X1135386Y360570D01*
X1133180D01*
G01X1130080Y358898D02*
X1128624Y360354D01*
X1126787D01*
X1125070Y362071D01*
X1122772D01*
X1121573Y360872D01*
X1119113D01*
X1117914Y362071D01*
X1115911D01*
X1114712Y360872D01*
X1113228D01*
X1112000Y362100D01*
X1109280D01*
X1108052Y360872D01*
X1106468D01*
X1105340Y362000D01*
G01X1103017D02*
X1101889Y360872D01*
X1099708D01*
X1098509Y362071D01*
X1097044D01*
X1095087Y364028D01*
X1092728D01*
X1090930Y362230D01*
X1089886D01*
X1088025Y364091D01*
G01X1085871D02*
X1084446Y362666D01*
X1082548D01*
X1080963Y364251D01*
G01X1079097D02*
X1077386Y362540D01*
X1075960D01*
X1074100Y364400D01*
X1067031D01*
X1064371Y367060D01*
G01X1249025Y130460D02*
X1248244D01*
X1245894Y132810D01*
X1239620D01*
X1175629Y196801D01*
X1171999D01*
X1168450Y200350D01*
X1160087D01*
X1152269Y208168D01*
X1150763D01*
X1150100Y208831D01*
Y210935D01*
X1148848Y212187D01*
X1146813D01*
X1144500Y214500D01*
X1141500D01*
X1138500Y217500D01*
Y238500D01*
X1137404Y239596D01*
X1133040D01*
G01X1255118Y16999D02*
Y27899D01*
G01D02*
X1256800Y29581D01*
Y48900D01*
X1255118Y50582D01*
Y54799D01*
G01Y9157D02*
X1253500Y10775D01*
Y32500D01*
X1255118Y34118D01*
Y36057D01*
G01Y92599D02*
Y93338D01*
X1259780Y98000D01*
X1267400D01*
X1271500Y102100D01*
G01X1255118Y54799D02*
Y65699D01*
G01D02*
X1256700Y67281D01*
Y89000D01*
X1255118Y90582D01*
Y92599D01*
G01Y73857D02*
Y84757D01*
G01D02*
X1253500Y86375D01*
Y93350D01*
X1259450Y99300D01*
X1265700D01*
X1268500Y102100D01*
G01X1255118Y46957D02*
X1253500Y48575D01*
Y67100D01*
X1255118Y68718D01*
Y73857D01*
G01Y36057D02*
Y46957D01*
G01X1372300Y86400D02*
X1370600Y84700D01*
X1354600D01*
X1353500Y83600D01*
Y80000D01*
X1347100Y73600D01*
X1335100D01*
X1333200Y75500D01*
Y80285D01*
X1332576Y80909D01*
Y84160D01*
X1312560Y104176D01*
X1308359D01*
X1304750Y107785D01*
Y119200D01*
X1302850Y121100D01*
X1300700D01*
X1300200Y120600D01*
Y115400D01*
X1293500Y108700D01*
X1287140D01*
X1284640Y106200D01*
X1277600D01*
G01X1275470Y99390D02*
X1276000Y99920D01*
Y107200D01*
X1276600Y107800D01*
X1283840D01*
X1286940Y110900D01*
X1293300D01*
X1299048Y116648D01*
Y121078D01*
X1300223Y122253D01*
X1303246D01*
X1305824Y119675D01*
Y108888D01*
X1309784Y104928D01*
X1312872D01*
X1333328Y84472D01*
Y82272D01*
X1334352Y81248D01*
Y75548D01*
X1335500Y74400D01*
X1344900D01*
X1349400Y78900D01*
Y84228D01*
X1351812Y86640D01*
X1357000D01*
G01X1305950Y306611D02*
X1307655Y308316D01*
Y313904D01*
X1297370Y324189D01*
Y331230D01*
X1269224Y359376D01*
Y359737D01*
X1269223Y359739D01*
Y360361D01*
X1269224Y360362D01*
Y390770D01*
X1268435Y391559D01*
Y453703D01*
X1274493Y459761D01*
Y467083D01*
X1277175Y469765D01*
Y490750D01*
X1277987Y491562D01*
Y491571D01*
X1277978D01*
G01X1270400Y593600D02*
X1263581Y586781D01*
Y554420D01*
X1268652Y549349D01*
Y537184D01*
X1272068Y533768D01*
Y512932D01*
X1273000Y512000D01*
Y508803D01*
X1278306Y503497D01*
Y501256D01*
X1282534Y497028D01*
Y495459D01*
X1281175Y494100D01*
X1277079D01*
X1276092Y493113D01*
Y491558D01*
X1276258Y491392D01*
Y469988D01*
X1273700Y467430D01*
Y460032D01*
X1266979Y453311D01*
Y391951D01*
X1268472Y390458D01*
Y360674D01*
X1268471Y360673D01*
Y359561D01*
X1268472Y359559D01*
Y358951D01*
X1295974Y331448D01*
Y323185D01*
X1305873Y313286D01*
Y309245D01*
G01X1599270Y246310D02*
Y249841D01*
X1596451Y252660D01*
X1592668D01*
X1588052Y248044D01*
X1573033D01*
X1568489Y243500D01*
X1551540D01*
X1549820Y241780D01*
X1547207D01*
X1546224Y242763D01*
Y244195D01*
X1544053Y246366D01*
Y246367D01*
X1542810Y247610D01*
X1538265D01*
X1535565Y244910D01*
X1530171D01*
X1529121Y245960D01*
X1522246D01*
X1521106Y247100D01*
X1521102D01*
X1516951Y251251D01*
X1512598D01*
X1511647Y250300D01*
Y243951D01*
X1510796Y243100D01*
X1507983D01*
X1507189Y243894D01*
X1502147D01*
X1500326Y245715D01*
X1495885D01*
X1494801Y246799D01*
X1491400D01*
X1488532Y249667D01*
X1486426D01*
X1482989Y246230D01*
X1479108D01*
X1477454Y244576D01*
X1468566D01*
X1467764Y243774D01*
X1465690D01*
X1459015Y250449D01*
X1451562D01*
X1429413Y272598D01*
Y273983D01*
X1426909Y276487D01*
X1413391D01*
X1408638Y271734D01*
X1394067D01*
X1394063Y271738D01*
X1394058D01*
X1392681Y273115D01*
X1361416D01*
X1359248Y275283D01*
X1338644D01*
X1334675Y279252D01*
X1332948D01*
X1326848Y285352D01*
X1319320D01*
X1312560Y292112D01*
Y313643D01*
X1301456Y324747D01*
Y332894D01*
X1273597Y360753D01*
Y453350D01*
X1278009Y457762D01*
Y465618D01*
X1280227Y467836D01*
Y485252D01*
X1285542Y490567D01*
Y498276D01*
X1281314Y502504D01*
Y504745D01*
X1279273Y506786D01*
Y517449D01*
X1280349Y518525D01*
Y523482D01*
X1275740Y528091D01*
Y534432D01*
X1273974Y536198D01*
Y540902D01*
X1274900Y541828D01*
Y542900D01*
X1272085Y545715D01*
Y581085D01*
X1273200Y582200D01*
G01X1434300Y251600D02*
X1431000D01*
X1417191Y265409D01*
X1410832D01*
X1406764Y269477D01*
X1387885D01*
X1387884Y269476D01*
X1357969D01*
X1353314Y274131D01*
X1338165D01*
X1334435Y277861D01*
X1322282D01*
X1319852Y280291D01*
X1315663D01*
X1311600Y284354D01*
Y287000D01*
X1308900Y289700D01*
Y300582D01*
X1300012Y309470D01*
Y316976D01*
X1293985Y323003D01*
Y331807D01*
X1267320Y358472D01*
Y359287D01*
X1267319Y359289D01*
Y361151D01*
X1267320Y361152D01*
Y389980D01*
X1257400Y399900D01*
X1248900D01*
X1245100Y396100D01*
X1241113D01*
X1239698Y397515D01*
Y470097D01*
X1245977Y476376D01*
X1256194D01*
X1256195Y476375D01*
X1257729D01*
X1263382Y482028D01*
Y497014D01*
X1262843Y497553D01*
G01X1277137Y547393D02*
Y545164D01*
X1280848Y541453D01*
Y538512D01*
X1278848Y536512D01*
Y529375D01*
X1284075Y524148D01*
X1298931D01*
X1302376Y520703D01*
Y511429D01*
X1288602Y497655D01*
Y489371D01*
X1283366Y484135D01*
Y465945D01*
X1281886Y464465D01*
Y456925D01*
X1278539Y453578D01*
Y362461D01*
X1306300Y334700D01*
Y324760D01*
X1318254Y312806D01*
Y304925D01*
X1315974Y302645D01*
Y295526D01*
X1319888Y291612D01*
Y290205D01*
G01X1279318Y545212D02*
Y544047D01*
X1281600Y541765D01*
Y538200D01*
X1279600Y536200D01*
Y529687D01*
X1284187Y525100D01*
X1299043D01*
X1303128Y521015D01*
Y511098D01*
X1289400Y497370D01*
Y488256D01*
X1284318Y483174D01*
Y465718D01*
X1282638Y464038D01*
Y456613D01*
X1279491Y453466D01*
Y362856D01*
X1307252Y335095D01*
Y325155D01*
X1319206Y313201D01*
Y304530D01*
X1316926Y302250D01*
Y295921D01*
X1322642Y290205D01*
X1323688D01*
G01X1255120Y518000D02*
Y513120D01*
X1253347Y511347D01*
Y503347D01*
X1251500Y501500D01*
Y497000D01*
X1249193Y494693D01*
Y491308D01*
G01X1255120Y510158D02*
Y503490D01*
X1253249Y501619D01*
Y496249D01*
X1250769Y493769D01*
Y490268D01*
X1249414Y488913D01*
X1248474D01*
G01X1338700Y284700D02*
X1341804Y281596D01*
X1360383D01*
X1363475Y278504D01*
X1386586D01*
X1387354Y279272D01*
X1393977D01*
X1396251Y276998D01*
X1406454D01*
X1411294Y281838D01*
X1429562D01*
X1445052Y297328D01*
X1446063D01*
X1446924Y298189D01*
Y299198D01*
X1448126Y300400D01*
X1455433D01*
X1456456Y301423D01*
Y302433D01*
X1457442Y303419D01*
X1458660D01*
X1459732Y302347D01*
Y301339D01*
X1460593Y300478D01*
X1474407D01*
X1475268Y301339D01*
Y303628D01*
X1473798Y305098D01*
G01X1316100Y543400D02*
X1315316Y542616D01*
Y538580D01*
X1315792Y538104D01*
Y522516D01*
X1321926Y516382D01*
Y496458D01*
X1308450Y482982D01*
X1301774D01*
X1298114Y479322D01*
Y442091D01*
X1294653Y438630D01*
Y366246D01*
X1318254Y342645D01*
Y336842D01*
X1330074Y324992D01*
Y316597D01*
X1330997Y315674D01*
X1331052D01*
X1333648Y313071D01*
Y299269D01*
X1335302Y297615D01*
X1340715D01*
X1344839Y293491D01*
X1349356D01*
X1353498Y289349D01*
X1359079D01*
X1366158Y282270D01*
X1382841D01*
X1386239Y285668D01*
X1386900Y285799D01*
X1428203D01*
X1436797Y294393D01*
Y308697D01*
X1441500Y313400D01*
X1443439D01*
X1447133Y317094D01*
Y318733D01*
X1448800Y320400D01*
X1451718D01*
X1463991Y332673D01*
X1471440D01*
X1472413Y331700D01*
X1493800D01*
X1497650Y327850D01*
X1510600D01*
X1511850Y329100D01*
X1514610D01*
X1515430Y329920D01*
Y331250D01*
X1516190Y332010D01*
X1518430D01*
X1521340Y329100D01*
X1522253D01*
X1524964Y331811D01*
X1528007D01*
X1530482Y329336D01*
X1533932D01*
X1536953Y326315D01*
X1542897D01*
X1545720Y323492D01*
Y321998D01*
X1547149Y320569D01*
X1549287D01*
X1550597Y321879D01*
X1551903D01*
X1553108Y320674D01*
X1570853D01*
X1575212Y316315D01*
X1582786D01*
X1584995Y318524D01*
X1585860D01*
X1587330Y317054D01*
X1598024D01*
X1602795Y321825D01*
X1608149D01*
X1608764Y322440D01*
G01X1336336Y333825D02*
Y333964D01*
X1329277Y341023D01*
Y342332D01*
X1326678Y344931D01*
X1325087D01*
X1301049Y368969D01*
Y423280D01*
X1303524Y425755D01*
Y444574D01*
X1308450Y449500D01*
Y459129D01*
X1311596Y462275D01*
Y480373D01*
X1326628Y495405D01*
Y533858D01*
X1337648Y544878D01*
X1346524D01*
X1355358Y553712D01*
X1371880D01*
X1372744Y552848D01*
X1385686D01*
X1395098Y562260D01*
X1412230D01*
X1414762Y564792D01*
X1419301D01*
X1419984Y564109D01*
Y562802D01*
X1420907Y561879D01*
X1422213D01*
X1428484Y568150D01*
X1429520D01*
X1429560Y568190D01*
X1464020D01*
X1464538Y567672D01*
X1466989D01*
X1467477Y567184D01*
X1469821D01*
X1470898Y568261D01*
X1533594D01*
X1545363Y580030D01*
X1560154D01*
X1563459Y583335D01*
X1589272D01*
X1595904Y589967D01*
Y599535D01*
X1596752Y600383D01*
Y610269D01*
X1596751Y610270D01*
Y612320D01*
X1599385Y614954D01*
X1603546D01*
X1606130Y612370D01*
Y612219D01*
X1610387Y607962D01*
X1612580D01*
X1618100Y613482D01*
Y617929D01*
X1621317Y621146D01*
X1691963D01*
X1698020Y615089D01*
Y610900D01*
X1700710Y608210D01*
X1737780D01*
X1740120Y610550D01*
X1756961D01*
X1763259Y604252D01*
X1793802D01*
X1800352Y597702D01*
Y596101D01*
G01X1288100Y562000D02*
X1290091Y560009D01*
X1290772D01*
X1295775Y555006D01*
Y549830D01*
X1299130Y546475D01*
X1308025D01*
X1311350Y543150D01*
Y537498D01*
X1313448Y535400D01*
Y520340D01*
X1315700Y518088D01*
Y509500D01*
X1302851Y496651D01*
Y491453D01*
X1300181Y488783D01*
X1297862D01*
X1294354Y485275D01*
Y443651D01*
X1290759Y440056D01*
Y361012D01*
X1312893Y338878D01*
Y326302D01*
X1324646Y314549D01*
Y310232D01*
X1328447Y306431D01*
Y293452D01*
X1332263Y289636D01*
X1337128D01*
X1343664Y283100D01*
X1361008D01*
X1364100Y280008D01*
X1385962D01*
X1386731Y280777D01*
X1394600D01*
X1396875Y278502D01*
X1405830D01*
X1410670Y283342D01*
X1428938D01*
X1440680Y295084D01*
Y299255D01*
X1441904Y300479D01*
X1442912D01*
X1443773Y301340D01*
Y303417D01*
X1445454Y305098D01*
G01X1285400Y561000D02*
X1287143Y559257D01*
X1290460D01*
X1294781Y554936D01*
Y549194D01*
X1303900Y540075D01*
Y533936D01*
X1306888Y530948D01*
Y509538D01*
X1293222Y495872D01*
Y490292D01*
X1293552Y489962D01*
Y443913D01*
X1290007Y440368D01*
Y360700D01*
X1312141Y338566D01*
Y325990D01*
X1323894Y314237D01*
Y309920D01*
X1327695Y306119D01*
Y293140D01*
X1331951Y288884D01*
X1336816D01*
X1343352Y282348D01*
X1360695D01*
X1363787Y279256D01*
X1386274D01*
X1387043Y280025D01*
X1394288D01*
X1396563Y277750D01*
X1406142D01*
X1410982Y282590D01*
X1429250D01*
X1443773Y297113D01*
Y299196D01*
X1445055Y300478D01*
X1446063D01*
X1446924Y301339D01*
Y303419D01*
X1448603Y305098D01*
G01X1299450Y484950D02*
X1297362Y482862D01*
Y442403D01*
X1293853Y438894D01*
Y365416D01*
X1317102Y342167D01*
Y335497D01*
X1329321Y323278D01*
Y309813D01*
X1331455Y307679D01*
Y299266D01*
X1334258Y296463D01*
X1340237D01*
X1344361Y292339D01*
X1348878D01*
X1352620Y288597D01*
X1358767D01*
X1361552Y285812D01*
Y284685D01*
X1364725Y281512D01*
X1385192D01*
X1385961Y282281D01*
X1395224D01*
X1397499Y280006D01*
X1405206D01*
X1410046Y284846D01*
X1428314D01*
X1438293Y294825D01*
Y304236D01*
X1442304Y308247D01*
G01X1381431Y284259D02*
X1374141D01*
X1370835Y287565D01*
X1363728D01*
X1360392Y290901D01*
X1353576D01*
X1349834Y294643D01*
X1345317D01*
X1341193Y298767D01*
X1335214D01*
X1334400Y299581D01*
Y325954D01*
X1333626Y326728D01*
Y327269D01*
X1324482Y336413D01*
Y341994D01*
X1298545Y367931D01*
Y431108D01*
X1300438Y433001D01*
G01X1320300Y498300D02*
X1308526Y486526D01*
X1298797D01*
X1296610Y484339D01*
Y442715D01*
X1293053Y439158D01*
Y365152D01*
X1316349Y341856D01*
Y334371D01*
X1328569Y322118D01*
Y309501D01*
X1330703Y307367D01*
Y298954D01*
X1333947Y295710D01*
X1334569D01*
X1334570Y295711D01*
X1339925D01*
X1344049Y291587D01*
X1346196D01*
X1346197Y291586D01*
X1346819D01*
X1346820Y291587D01*
X1348566D01*
X1352308Y287845D01*
X1358455D01*
X1360800Y285500D01*
Y284372D01*
X1364412Y280760D01*
X1385650D01*
X1386419Y281529D01*
X1394912D01*
X1397187Y279254D01*
X1405518D01*
X1410358Y284094D01*
X1428626D01*
X1439045Y294513D01*
Y300770D01*
X1441775Y303500D01*
X1442785D01*
X1443984Y304699D01*
Y305707D01*
X1444927Y306650D01*
X1466973D01*
X1470040Y309717D01*
X1471264D01*
X1472944Y311397D01*
X1473798D01*
G01X1809700Y506875D02*
X1816428Y513603D01*
Y522710D01*
X1815224Y523914D01*
Y526907D01*
X1818757Y530440D01*
Y541157D01*
X1821376Y543776D01*
Y573470D01*
X1814577Y580269D01*
X1812149D01*
X1811661Y579781D01*
X1800781D01*
X1790424Y569424D01*
X1784876D01*
X1782000Y572300D01*
X1769200D01*
X1768229Y573271D01*
X1766271D01*
X1765700Y572700D01*
X1757700D01*
X1744500Y559500D01*
X1742271D01*
X1734771Y567000D01*
X1719000D01*
X1712334Y560334D01*
X1654327D01*
X1650681Y563980D01*
Y568389D01*
X1644678Y574392D01*
X1621608D01*
X1616237Y579763D01*
X1613200D01*
X1607315Y585648D01*
X1601250D01*
X1589820Y574218D01*
X1585400D01*
X1584331Y575287D01*
X1575384D01*
X1571067Y570970D01*
Y567167D01*
X1562753Y558853D01*
X1546678D01*
X1544705Y556880D01*
X1516952D01*
X1514396Y559436D01*
X1508876D01*
X1507002Y557562D01*
X1461124D01*
X1460320Y558366D01*
X1438323D01*
X1435708Y555751D01*
X1426566D01*
X1426324Y555509D01*
X1421267D01*
X1412258Y546500D01*
X1388977D01*
X1388789Y546688D01*
X1373380D01*
X1368761Y542069D01*
X1353468D01*
X1333424Y522025D01*
Y513241D01*
X1336137Y510528D01*
X1336272D01*
X1337176Y509624D01*
X1337419D01*
X1347589Y499454D01*
Y493726D01*
X1345970Y492107D01*
Y476244D01*
X1347697Y474517D01*
X1347849D01*
X1353009Y469357D01*
Y461561D01*
X1351757Y460309D01*
Y457928D01*
X1350453Y456624D01*
X1348735D01*
X1342928Y450817D01*
Y416987D01*
X1340081Y414140D01*
X1318987D01*
X1310451Y405604D01*
Y379838D01*
X1310450Y379837D01*
Y376971D01*
X1330321Y357100D01*
X1338400D01*
X1341100Y354400D01*
X1372126D01*
X1375100Y351426D01*
Y338430D01*
X1378030Y335500D01*
X1390984D01*
X1396470Y330014D01*
G01X1816584Y530542D02*
X1814754Y532372D01*
Y546600D01*
X1813292Y548062D01*
Y572389D01*
X1809531Y576150D01*
X1805381D01*
X1781816Y552585D01*
X1773586D01*
X1772217Y551216D01*
X1749000D01*
X1744197Y546413D01*
X1738087D01*
X1737837Y546663D01*
X1737563D01*
X1736640Y547586D01*
Y547860D01*
X1733284Y551216D01*
X1716204D01*
X1710542Y556878D01*
X1643481D01*
X1640250Y560109D01*
X1628391D01*
X1625000Y563500D01*
X1622729D01*
X1619756Y566473D01*
Y569203D01*
X1613667Y575292D01*
X1601989D01*
X1601773Y575508D01*
X1596569D01*
X1591823Y570762D01*
X1579303D01*
X1574967Y566426D01*
Y561976D01*
X1572527Y559536D01*
X1568326D01*
X1564187Y555397D01*
X1548112D01*
X1544528Y551813D01*
X1516513D01*
X1515021Y553305D01*
X1460491D01*
X1458886Y554910D01*
X1439757D01*
X1433147Y548300D01*
X1424490D01*
X1405779Y529589D01*
X1378030D01*
X1376101Y527660D01*
X1364900D01*
X1360724Y523484D01*
Y504502D01*
X1355909Y499687D01*
Y479732D01*
X1358342Y477299D01*
Y460374D01*
X1356367Y458399D01*
Y456018D01*
X1352828Y452479D01*
Y436358D01*
X1350160Y433690D01*
Y417699D01*
X1341993Y409532D01*
X1320899D01*
X1315060Y403693D01*
Y378881D01*
X1330169Y363772D01*
X1371286D01*
X1375967Y359091D01*
X1382781D01*
X1385589Y356283D01*
X1395485D01*
X1408376Y343392D01*
Y339882D01*
G01X1410489Y337988D02*
Y342909D01*
X1395670Y357728D01*
X1389537D01*
X1385852Y361413D01*
X1375667D01*
X1372156Y364924D01*
X1330647D01*
X1316212Y379359D01*
Y403215D01*
X1321376Y408379D01*
X1342470D01*
X1353100Y419009D01*
Y433270D01*
X1357519Y437689D01*
Y457921D01*
X1359494Y459896D01*
Y477777D01*
X1357061Y480210D01*
Y499161D01*
X1361876Y503976D01*
Y523006D01*
X1365350Y526480D01*
X1376551D01*
X1378508Y528437D01*
X1406257D01*
X1420422Y542602D01*
X1429079D01*
X1440235Y553758D01*
X1458408D01*
X1460013Y552153D01*
X1514543D01*
X1516035Y550661D01*
X1545006D01*
X1548590Y554245D01*
X1564665D01*
X1568804Y558384D01*
X1573005D01*
X1576467Y561846D01*
Y566296D01*
X1579781Y569610D01*
X1592369D01*
X1597115Y574356D01*
X1601295D01*
X1601511Y574140D01*
X1613189D01*
X1618604Y568725D01*
Y556034D01*
X1621387Y553251D01*
X1654890D01*
X1657365Y555726D01*
X1710064D01*
X1715854Y549936D01*
X1732934D01*
X1735488Y547382D01*
Y547108D01*
X1737085Y545511D01*
X1737359D01*
X1737609Y545261D01*
X1744675D01*
X1749350Y549936D01*
X1759764D01*
X1769267Y540433D01*
X1775264D01*
X1779200Y544369D01*
Y548339D01*
X1805562Y574701D01*
X1809350D01*
X1811963Y572088D01*
Y564383D01*
X1809008Y561428D01*
Y557981D01*
X1804600Y553573D01*
Y546600D01*
X1806024Y545176D01*
Y529376D01*
X1806076Y529324D01*
Y523525D01*
G01X1750399Y603201D02*
X1745965D01*
X1744340Y601576D01*
X1707709D01*
X1704630Y604655D01*
X1668565D01*
X1654478Y618742D01*
X1625240D01*
X1620621Y614123D01*
Y612602D01*
X1613576Y605557D01*
X1609391D01*
X1603726Y611222D01*
Y611373D01*
X1602803Y612296D01*
X1601497D01*
X1599286Y610085D01*
Y599216D01*
X1598442Y598372D01*
Y588153D01*
X1588263Y577974D01*
X1586957D01*
X1585752Y579179D01*
X1563644D01*
X1561367Y576902D01*
X1546294D01*
X1535185Y565793D01*
X1471831D01*
X1470817Y564779D01*
X1464020D01*
X1463223Y565576D01*
X1432127D01*
X1429132Y562581D01*
Y562149D01*
X1426515Y559532D01*
X1425034D01*
X1424767Y559265D01*
X1419710D01*
X1413470Y553025D01*
X1389264D01*
X1386683Y550444D01*
X1371544D01*
X1366965Y545865D01*
X1352958D01*
X1352918Y545825D01*
X1351911D01*
X1347972Y541886D01*
X1340968D01*
X1329042Y529960D01*
Y494418D01*
X1314001Y479377D01*
Y460828D01*
X1316676Y458153D01*
Y450591D01*
X1311676Y445591D01*
Y438232D01*
X1308425Y434981D01*
Y425216D01*
X1303939Y420730D01*
Y382538D01*
X1303938Y382537D01*
Y374271D01*
X1303939Y374270D01*
Y370518D01*
X1316147Y358310D01*
X1317890D01*
X1329689Y346511D01*
X1329757D01*
G01X1392400Y330800D02*
X1389200Y334000D01*
X1377510D01*
X1373800Y337710D01*
Y349990D01*
X1370642Y353148D01*
X1340252D01*
X1337600Y355800D01*
X1329850D01*
X1309198Y376452D01*
Y380356D01*
X1309199Y380357D01*
Y417779D01*
X1314654Y423234D01*
X1318063D01*
X1321900Y427071D01*
Y433300D01*
X1328780Y440180D01*
X1335009D01*
X1341676Y446847D01*
Y452305D01*
X1349239Y459868D01*
X1349254D01*
X1351757Y462371D01*
Y466151D01*
X1344718Y473190D01*
Y492626D01*
X1346337Y494245D01*
Y498935D01*
X1336900Y508372D01*
X1336657D01*
X1335753Y509276D01*
X1335618D01*
X1332172Y512722D01*
Y522544D01*
X1352949Y543321D01*
X1368242D01*
X1372861Y547940D01*
X1389308D01*
X1389496Y547752D01*
X1411739D01*
X1420748Y556761D01*
X1425805D01*
X1426072Y557028D01*
X1435066D01*
X1440731Y562693D01*
X1442507D01*
X1445441Y559759D01*
X1460698D01*
X1461643Y558814D01*
X1506483D01*
X1508676Y561007D01*
X1514596D01*
X1517471Y558132D01*
X1544186D01*
X1546254Y560200D01*
X1562329D01*
X1569767Y567638D01*
Y571441D01*
X1574883Y576557D01*
X1584832D01*
X1585919Y575470D01*
X1589301D01*
X1600731Y586900D01*
X1607834D01*
X1613719Y581015D01*
X1616756D01*
X1622127Y575644D01*
X1646768D01*
X1649640Y572772D01*
X1654202D01*
X1655083Y573653D01*
X1736000D01*
X1741847Y579500D01*
X1745000D01*
X1748500Y583000D01*
X1762087D01*
X1769279Y590192D01*
X1780308D01*
X1783061Y587439D01*
Y584132D01*
X1784989Y582204D01*
X1798328D01*
X1802924Y586800D01*
X1811100D01*
G01X1822273Y595046D02*
X1821907Y595412D01*
X1817212D01*
X1815200Y593400D01*
X1807300D01*
X1804598Y590698D01*
X1782501D01*
X1779399Y593800D01*
X1762829D01*
X1762798Y593831D01*
X1761326D01*
X1761295Y593800D01*
X1756196D01*
X1743396Y581000D01*
X1741224D01*
X1735500Y575276D01*
X1654930D01*
X1653678Y574024D01*
X1650512D01*
X1647640Y576896D01*
X1625924D01*
X1617880Y584940D01*
Y590395D01*
X1609499Y598776D01*
X1600617D01*
X1599694Y597853D01*
Y587634D01*
X1588782Y576722D01*
X1586438D01*
X1585233Y577927D01*
X1564163D01*
X1561886Y575650D01*
X1546813D01*
X1535704Y564541D01*
X1509424D01*
X1504949Y560066D01*
X1462584D01*
X1461638Y561012D01*
X1445959D01*
X1442945Y564026D01*
X1432348D01*
X1430384Y562062D01*
Y561630D01*
X1427034Y558280D01*
X1425553D01*
X1425286Y558013D01*
X1420229D01*
X1413989Y551773D01*
X1389783D01*
X1387202Y549192D01*
X1372171D01*
X1367552Y544573D01*
X1352430D01*
X1348491Y540634D01*
X1341487D01*
X1330294Y529441D01*
Y493581D01*
X1315253Y478540D01*
Y465537D01*
X1319630Y461160D01*
Y459854D01*
X1317928Y458152D01*
Y450072D01*
X1312928Y445072D01*
Y437713D01*
X1311815Y436600D01*
Y426835D01*
X1305191Y420211D01*
Y382019D01*
X1305190Y382018D01*
Y374790D01*
X1305191Y374789D01*
Y373739D01*
X1318324Y360606D01*
Y359718D01*
X1328524Y349518D01*
Y349447D01*
X1329535Y348436D01*
X1330594D01*
X1332613Y346417D01*
G01X1816280Y550400D02*
X1814444Y552236D01*
Y572867D01*
X1809992Y577319D01*
X1804920D01*
X1785101Y557500D01*
X1772000D01*
X1768000Y553500D01*
X1765030D01*
X1762030Y556500D01*
X1749260D01*
X1745128Y552368D01*
X1744998D01*
X1743977Y551347D01*
X1743703D01*
X1743630Y551274D01*
X1741368D01*
X1740044Y552598D01*
X1734732D01*
X1734502Y552368D01*
X1730953D01*
X1725291Y558030D01*
X1643959D01*
X1640728Y561261D01*
X1629039D01*
X1624900Y565400D01*
X1622459D01*
X1620908Y566951D01*
Y569681D01*
X1614145Y576444D01*
X1602467D01*
X1602251Y576660D01*
X1595977D01*
X1591231Y571914D01*
X1578825D01*
X1573410Y566499D01*
Y566250D01*
X1563709Y556549D01*
X1547634D01*
X1545661Y554576D01*
X1460850D01*
X1459364Y556062D01*
X1439279D01*
X1436568Y553351D01*
X1427911D01*
X1405319Y530759D01*
X1377570D01*
X1375831Y529020D01*
X1364630D01*
X1359572Y523962D01*
Y505130D01*
X1354757Y500315D01*
Y479254D01*
X1357190Y476821D01*
Y460852D01*
X1355215Y458877D01*
Y456496D01*
X1351676Y452957D01*
Y436846D01*
X1349000Y434170D01*
Y418169D01*
X1341515Y410684D01*
X1320421D01*
X1313907Y404170D01*
Y378404D01*
X1329692Y362619D01*
X1330646D01*
X1330647Y362620D01*
X1370516D01*
X1375280Y357856D01*
X1382386D01*
X1385111Y355131D01*
X1395007D01*
X1400400Y349738D01*
Y335400D01*
G01X1816280Y553500D02*
X1817751Y554971D01*
Y571946D01*
X1816074Y573623D01*
X1815351D01*
X1810436Y578538D01*
X1801338D01*
X1789300Y566500D01*
X1788229D01*
X1780729Y559000D01*
X1770000D01*
X1769200Y558200D01*
X1744200D01*
X1741830Y555830D01*
X1739152D01*
X1739151Y555831D01*
X1737845D01*
X1737844Y555830D01*
X1736830D01*
X1734750Y553750D01*
X1731432D01*
X1726000Y559182D01*
X1653849D01*
X1649528Y563503D01*
Y567912D01*
X1644200Y573240D01*
X1621130D01*
X1615759Y578611D01*
X1612722D01*
X1606837Y584496D01*
X1601793D01*
X1590363Y573066D01*
X1578347D01*
X1572257Y566976D01*
Y566727D01*
X1563231Y557701D01*
X1547156D01*
X1545183Y555728D01*
X1461328D01*
X1459842Y557214D01*
X1438801D01*
X1436138Y554551D01*
X1426996D01*
X1426802Y554357D01*
X1421745D01*
X1412736Y545348D01*
X1389066D01*
X1388477Y545937D01*
X1380785D01*
X1378704Y543856D01*
X1376997D01*
X1373320Y540179D01*
Y533960D01*
X1370930Y531570D01*
X1363920D01*
X1355940Y523590D01*
Y513399D01*
X1352453Y509912D01*
Y473921D01*
X1354161Y472213D01*
Y461083D01*
X1352909Y459831D01*
Y457450D01*
X1350931Y455472D01*
X1349213D01*
X1346676Y452935D01*
Y419105D01*
X1340559Y412988D01*
X1319465D01*
X1311603Y405126D01*
Y379360D01*
X1311602Y379359D01*
Y377449D01*
X1330751Y358300D01*
X1339000D01*
X1341748Y355552D01*
X1374856D01*
X1379950Y350458D01*
Y338590D01*
X1381730Y336810D01*
X1394752D01*
X1398890Y332672D01*
X1404265D01*
X1404593Y333000D01*
X1408250D01*
G01X1408348Y336436D02*
X1406216D01*
X1403604Y333824D01*
X1399747D01*
X1396800Y336771D01*
Y351708D01*
X1395098Y353410D01*
X1384278D01*
X1380984Y356704D01*
X1342396D01*
X1339500Y359600D01*
X1331081D01*
X1312754Y377927D01*
Y378881D01*
X1312755Y378882D01*
Y404648D01*
X1319943Y411836D01*
X1341037D01*
X1347828Y418627D01*
Y452457D01*
X1349691Y454320D01*
X1351409D01*
X1354061Y456972D01*
Y459353D01*
X1356038Y461330D01*
Y476343D01*
X1353605Y478776D01*
Y503379D01*
X1357852Y507626D01*
Y523872D01*
X1364152Y530172D01*
X1375353D01*
X1377218Y532037D01*
X1379503D01*
X1382331Y534865D01*
Y543818D01*
G01X1344090Y463630D02*
X1342432Y465288D01*
X1340659D01*
X1317428Y442057D01*
Y427218D01*
X1316133Y425923D01*
X1314224D01*
X1307195Y418894D01*
Y381188D01*
X1307194Y381187D01*
Y375621D01*
X1307195Y375620D01*
Y375305D01*
X1332600Y349900D01*
G01X1346739Y463615D02*
X1344085Y466269D01*
X1336086D01*
X1330212Y460395D01*
X1325766D01*
X1322048Y456677D01*
Y452219D01*
X1315753Y445924D01*
Y444076D01*
X1316676Y443153D01*
Y439166D01*
X1313113Y435603D01*
Y425876D01*
X1306443Y419206D01*
Y381500D01*
X1306442Y381499D01*
Y375309D01*
X1306443Y375308D01*
Y374258D01*
X1330100Y350601D01*
Y350100D01*
G01X1335100Y507700D02*
X1338700Y504100D01*
Y476993D01*
X1350505Y465188D01*
Y462890D01*
X1348735Y461120D01*
X1345554D01*
X1343740Y459306D01*
X1339677D01*
X1318661Y438290D01*
Y433290D01*
X1318524Y433153D01*
Y426367D01*
X1316643Y424486D01*
X1314135D01*
X1307947Y418298D01*
Y380876D01*
X1307946Y380875D01*
Y375933D01*
X1329579Y354300D01*
X1337282D01*
X1363144Y328438D01*
X1411258D01*
X1415720Y332900D01*
X1416000D01*
G01X1784200Y593924D02*
X1780824Y597300D01*
X1771400D01*
X1767256Y601444D01*
X1759246D01*
X1757916Y602774D01*
X1757897D01*
X1756974Y603697D01*
Y603716D01*
X1752240Y608450D01*
X1742169D01*
X1740572Y606853D01*
X1700176D01*
X1697377Y609652D01*
Y609682D01*
X1696615Y610444D01*
Y614723D01*
X1691444Y619894D01*
X1624762D01*
X1619469Y614601D01*
Y613080D01*
X1613099Y606710D01*
X1609868D01*
X1604878Y611700D01*
Y611851D01*
X1603028Y613701D01*
X1600329D01*
X1598004Y611376D01*
Y599794D01*
X1597190Y598980D01*
Y588994D01*
X1590041Y581845D01*
X1563839D01*
X1560859Y578865D01*
X1560760D01*
X1560673Y578778D01*
X1546540D01*
X1534707Y566945D01*
X1471353D01*
X1470340Y565932D01*
X1464497D01*
X1463498Y566931D01*
X1431181D01*
X1427255Y563005D01*
Y562043D01*
X1425896Y560684D01*
X1424556D01*
X1424289Y560417D01*
X1418718D01*
X1412478Y554177D01*
X1388786D01*
X1386205Y551596D01*
X1372225D01*
X1371361Y552460D01*
X1356916D01*
X1348082Y543626D01*
X1338167D01*
X1333453Y538912D01*
Y536001D01*
X1327890Y530438D01*
Y494896D01*
X1312849Y479855D01*
Y448394D01*
X1308107Y443652D01*
Y437138D01*
X1307313Y436344D01*
Y435499D01*
X1307273Y435459D01*
Y425694D01*
X1302787Y421208D01*
Y383016D01*
X1302786Y383015D01*
Y373793D01*
X1302787Y373792D01*
Y369713D01*
X1324768Y347732D01*
X1326014D01*
G01X1590530Y610620D02*
X1592650Y608500D01*
Y595850D01*
X1590604Y593804D01*
X1582088D01*
X1582087Y593805D01*
X1580921D01*
X1575990Y588874D01*
X1563406D01*
X1558480Y583948D01*
X1543747D01*
X1531972Y572173D01*
X1522680D01*
X1515363Y579490D01*
X1467854D01*
X1462653Y574289D01*
X1461794D01*
X1453491Y582592D01*
X1443088D01*
X1432692Y572196D01*
X1426797D01*
X1423508Y568907D01*
X1414827D01*
X1414040Y568120D01*
X1395424D01*
X1384064Y556760D01*
X1352872D01*
X1344902Y548790D01*
X1324390D01*
X1316724Y541124D01*
Y539164D01*
X1317200Y538688D01*
Y523100D01*
X1323630Y516670D01*
Y496170D01*
X1308936Y481476D01*
Y480487D01*
X1304677Y476228D01*
X1301240D01*
G01X1318500Y539900D02*
X1322129Y543529D01*
X1330628D01*
X1334481Y547382D01*
X1344318D01*
X1344319Y547381D01*
X1345485D01*
X1353456Y555352D01*
X1384648D01*
X1395906Y566610D01*
X1414630D01*
X1415519Y567499D01*
X1424092D01*
X1427381Y570788D01*
X1433276D01*
X1443672Y581184D01*
X1452907D01*
X1461210Y572881D01*
X1463237D01*
X1463278Y572922D01*
X1465700Y570500D01*
G01X1355300Y321675D02*
Y322728D01*
X1357125Y324553D01*
X1374102D01*
X1375998Y322657D01*
X1382523D01*
X1385376Y325510D01*
X1395791D01*
X1397965Y323336D01*
X1405720D01*
X1408738Y326354D01*
X1410238D01*
X1414505Y330621D01*
X1416522D01*
X1417838Y331937D01*
Y341662D01*
X1417173Y342327D01*
Y357527D01*
X1413400Y361300D01*
G01X1395242Y520301D02*
Y518725D01*
X1390558Y514041D01*
X1375789D01*
X1358213Y496465D01*
Y480688D01*
X1360772Y478129D01*
Y459976D01*
X1361676Y459072D01*
Y427631D01*
X1373359Y415948D01*
X1384845D01*
X1408310Y392483D01*
Y352196D01*
X1414101Y346405D01*
Y337399D01*
X1416000Y335500D01*
G01X1396035Y514863D02*
X1393768Y512596D01*
X1375408D01*
X1358965Y496153D01*
Y481000D01*
X1364711Y475254D01*
Y460056D01*
X1362428Y457773D01*
Y427943D01*
X1373271Y417100D01*
X1384757D01*
X1409169Y392688D01*
Y352981D01*
X1416000Y346150D01*
Y338100D01*
G01X1405950Y510650D02*
X1405262D01*
X1403902Y509290D01*
Y508249D01*
X1402247Y506594D01*
X1388394D01*
X1377850Y496050D01*
Y473300D01*
X1383450Y467700D01*
Y454150D01*
X1385100Y452500D01*
G01X1402950Y510650D02*
Y508644D01*
X1401852Y507546D01*
X1387999D01*
X1376898Y496445D01*
Y472552D01*
X1382250Y467200D01*
Y452900D01*
X1385100Y450050D01*
Y447500D01*
G01X1509400Y3500D02*
X1506650Y750D01*
X1505150D01*
X1495300Y-9100D01*
X1457900D01*
X1452000Y-15000D01*
G01X1677600Y172700D02*
X1676735D01*
X1675096Y174339D01*
X1673367D01*
X1671152Y176554D01*
X1667456D01*
X1666594Y177416D01*
X1656784D01*
X1652392Y181808D01*
X1650391D01*
X1649931Y181348D01*
X1649929D01*
X1648420Y179839D01*
X1632797D01*
X1626521Y186115D01*
X1626520D01*
X1625769Y186866D01*
Y186867D01*
X1624539Y188097D01*
X1607524D01*
X1605730Y186303D01*
Y183391D01*
X1605701Y183362D01*
Y183359D01*
X1604672Y182330D01*
Y179750D01*
X1602649Y177727D01*
X1584826D01*
X1578591Y171492D01*
X1571348D01*
X1570147Y170291D01*
X1569425D01*
X1568118Y168984D01*
X1562956D01*
X1557472Y163500D01*
X1552500D01*
X1550689Y165311D01*
X1544308D01*
X1536292Y157295D01*
Y156500D01*
X1532928Y153136D01*
X1519836D01*
X1516867Y150167D01*
X1514705D01*
X1513172Y151700D01*
X1511600D01*
X1508900Y154400D01*
Y155284D01*
X1500556Y163628D01*
X1498172D01*
X1498146Y163654D01*
X1496840D01*
X1496814Y163628D01*
X1496528D01*
X1494024Y161124D01*
X1491676D01*
X1489524Y163276D01*
X1486775D01*
X1477800Y154301D01*
X1476108D01*
X1475146Y153339D01*
Y152809D01*
X1472737Y150400D01*
X1455228D01*
X1451233Y146405D01*
G01X1476826Y152725D02*
X1476722Y152621D01*
Y152321D01*
X1476298Y151897D01*
Y151868D01*
X1473678Y149248D01*
X1473649D01*
X1469862Y145461D01*
X1460579D01*
X1456379Y141261D01*
X1451228D01*
G01X1489088Y176680D02*
X1487451D01*
X1483969Y173198D01*
X1481828D01*
X1478880Y170250D01*
X1456739D01*
X1455095Y171894D01*
X1450761D01*
X1448832Y173823D01*
Y177560D01*
X1449644Y178372D01*
X1450532D01*
G01X1451365Y176014D02*
X1451379Y176000D01*
X1454480D01*
X1459078Y171402D01*
X1478402D01*
X1481350Y174350D01*
X1483491D01*
X1487397Y178256D01*
X1491131D01*
X1492500Y176887D01*
G01X1452200Y254500D02*
X1454053Y252647D01*
X1460052D01*
X1463938Y248761D01*
X1479325D01*
X1484232Y253668D01*
X1485589D01*
X1485958Y254037D01*
X1486918D01*
X1490711Y250244D01*
X1496280D01*
X1497824Y248700D01*
X1503290D01*
X1511391Y256801D01*
X1515200D01*
X1521575Y250426D01*
X1531856D01*
X1532414Y249868D01*
X1550457D01*
X1556073Y244252D01*
X1568177D01*
X1572721Y248796D01*
X1586708D01*
X1589592Y251680D01*
Y252472D01*
G01X1525650Y248700D02*
X1525550Y248600D01*
X1522300D01*
X1515299Y255601D01*
X1511315D01*
X1503214Y247500D01*
X1497960D01*
X1495968Y249492D01*
X1490399D01*
X1489072Y250819D01*
X1485948D01*
X1485353Y250224D01*
X1481852D01*
X1479637Y248009D01*
X1463274D01*
X1459681Y251602D01*
X1452822D01*
X1448500Y255924D01*
Y257700D01*
G01X1600810Y266006D02*
X1602085Y264731D01*
Y263985D01*
X1601492Y263392D01*
X1595796D01*
X1594888Y264300D01*
X1581312D01*
X1575740Y258728D01*
X1572398D01*
X1569300Y255630D01*
X1566481D01*
X1565055Y254204D01*
X1560924D01*
X1559996Y255132D01*
X1552641D01*
X1552639Y255134D01*
X1548897D01*
X1548896Y255133D01*
X1548274D01*
X1548273Y255132D01*
X1537476D01*
X1528964Y263644D01*
X1500796D01*
X1497848Y260696D01*
X1490196D01*
X1489496Y259996D01*
X1480812D01*
X1480808Y260000D01*
X1480617D01*
X1479862Y260755D01*
X1475650D01*
X1472910Y263495D01*
X1472264D01*
X1472263Y263496D01*
X1471017D01*
X1471016Y263495D01*
X1465206D01*
X1459600Y269101D01*
Y270983D01*
X1458583Y272000D01*
X1448127D01*
X1446924Y273203D01*
Y274212D01*
X1446063Y275073D01*
X1444845D01*
X1443375Y273603D01*
X1442304D01*
G01X1567000Y259560D02*
X1565730Y260830D01*
X1557454D01*
X1555540Y258916D01*
X1540971D01*
X1540970Y258915D01*
X1539100D01*
X1530502Y267513D01*
X1499185D01*
X1496444Y264772D01*
X1496443D01*
X1496128Y264457D01*
X1489611D01*
X1489610Y264456D01*
X1488636D01*
X1488214Y264034D01*
X1482312D01*
X1481831Y264515D01*
X1479493D01*
X1475395Y268613D01*
Y271342D01*
X1474690Y272047D01*
X1473275D01*
X1472328Y272994D01*
Y274672D01*
X1471717Y275283D01*
X1450317D01*
X1448847Y276753D01*
X1448603D01*
G01X1461300Y270400D02*
X1463196D01*
X1469245Y264351D01*
X1473187D01*
X1476031Y261507D01*
X1480365D01*
X1481124Y260748D01*
X1489184D01*
X1489884Y261448D01*
X1497536D01*
X1500484Y264396D01*
X1529276D01*
X1537788Y255884D01*
X1547961D01*
X1547962Y255885D01*
X1548584D01*
X1548585Y255886D01*
X1552951D01*
X1552953Y255884D01*
X1560308D01*
X1561236Y254956D01*
X1564615D01*
X1566079Y256420D01*
X1568931D01*
X1577956Y265445D01*
X1579867D01*
G01X1447154Y251710D02*
X1449168Y249696D01*
X1458704D01*
X1465378Y243022D01*
X1466798D01*
X1468465Y241355D01*
X1475455D01*
X1477003Y242903D01*
X1484021D01*
X1485033Y243915D01*
Y244654D01*
X1486513Y246134D01*
X1488829D01*
X1489387Y245576D01*
X1494960D01*
X1495573Y244963D01*
X1499940D01*
X1501785Y243118D01*
X1506691D01*
X1507507Y242302D01*
X1511297D01*
Y242362D01*
X1512500Y243565D01*
Y249115D01*
X1513677Y250292D01*
X1515067D01*
X1515106Y250253D01*
X1515830D01*
X1517379Y248704D01*
Y243800D01*
X1518427Y242752D01*
X1519867D01*
X1522235Y245120D01*
X1525209D01*
X1527585Y242744D01*
X1528748D01*
X1528756Y242752D01*
X1537060D01*
X1539398Y245090D01*
X1541325D01*
G01X1461202Y273603D02*
X1462297D01*
X1466916Y268984D01*
X1471116D01*
X1477089Y263011D01*
X1480989D01*
X1481700Y262300D01*
X1488608D01*
X1489260Y262952D01*
X1496752D01*
X1499700Y265900D01*
X1518156D01*
X1518157Y265901D01*
X1518779D01*
X1518780Y265900D01*
X1529900D01*
X1538412Y257388D01*
X1547337D01*
X1547338Y257389D01*
X1547960D01*
X1547961Y257390D01*
X1553575D01*
X1553577Y257388D01*
X1561112D01*
X1562040Y256460D01*
X1563991D01*
X1565455Y257924D01*
X1566651D01*
X1566660Y257933D01*
X1567282D01*
X1567283Y257932D01*
X1568315D01*
X1577332Y266949D01*
X1577478D01*
X1579235Y268706D01*
X1579576D01*
X1579577Y268707D01*
X1580199D01*
X1580200Y268706D01*
X1602406D01*
X1603568Y269868D01*
X1605822D01*
X1607888Y267802D01*
X1620198D01*
X1620200Y267800D01*
X1629952D01*
X1629953Y267799D01*
X1630301D01*
X1631820Y266280D01*
Y259783D01*
X1637281Y254322D01*
G01X1666345Y241987D02*
X1665521Y241163D01*
X1661905D01*
X1661208Y241860D01*
X1658219D01*
X1641779Y258300D01*
X1635864D01*
X1632572Y261592D01*
Y266592D01*
X1630613Y268551D01*
X1630265D01*
X1630262Y268554D01*
X1608200D01*
X1604609Y272145D01*
X1601009D01*
X1599538Y270674D01*
X1564254D01*
X1554000Y260420D01*
X1540347D01*
X1540346Y260419D01*
X1539724D01*
X1531008Y269135D01*
X1492308D01*
X1491127Y267954D01*
X1490007D01*
X1487590Y265537D01*
X1482935D01*
X1481620Y266852D01*
Y271447D01*
X1481021Y272046D01*
X1479357D01*
X1478508Y272895D01*
Y274266D01*
X1477562Y275212D01*
X1476143D01*
X1475478Y275877D01*
Y277152D01*
X1474230Y278400D01*
X1450105D01*
X1448603Y279902D01*
G01X1426658Y274252D02*
Y272042D01*
X1432134Y266566D01*
X1434381D01*
X1445200Y255747D01*
Y251420D01*
X1447887Y248733D01*
X1458603D01*
X1461348Y245988D01*
Y244350D01*
G01X1444850Y242730D02*
X1447830Y239750D01*
X1476560D01*
X1477940Y241130D01*
X1486860D01*
X1489470Y243740D01*
X1497250D01*
X1499150Y241840D01*
X1505280D01*
X1509630Y237490D01*
X1520750D01*
X1523250Y239990D01*
X1539190D01*
X1540390Y238790D01*
X1545120D01*
X1545930Y237980D01*
X1550910D01*
X1553374Y240444D01*
X1570084D01*
X1574374Y244734D01*
X1599954D01*
X1603360Y248140D01*
Y253530D01*
X1606420Y256590D01*
X1612580D01*
X1616005Y253165D01*
X1620903D01*
X1620922Y253184D01*
X1620924D01*
X1624640Y256900D01*
X1626401D01*
G01X1458052Y273603D02*
X1459522Y272133D01*
X1462526D01*
X1469220Y265439D01*
X1473498D01*
X1474747Y264190D01*
Y264189D01*
X1476677Y262259D01*
X1480677D01*
X1481436Y261500D01*
X1488872D01*
X1489572Y262200D01*
X1497224D01*
X1500172Y265148D01*
X1529588D01*
X1538100Y256636D01*
X1547649D01*
X1547650Y256637D01*
X1548272D01*
X1548273Y256638D01*
X1553263D01*
X1553265Y256636D01*
X1560620D01*
X1561548Y255708D01*
X1564303D01*
X1565767Y257172D01*
X1566963D01*
X1566971Y257180D01*
X1568627D01*
X1577644Y266197D01*
X1578131D01*
X1579888Y267954D01*
X1601554D01*
X1603556Y265952D01*
X1606478D01*
X1607576Y267050D01*
X1619886D01*
X1619889Y267047D01*
X1620511D01*
X1620512Y267048D01*
X1629640D01*
X1629641Y267047D01*
X1629989D01*
X1631068Y265968D01*
Y257996D01*
X1636412Y252652D01*
X1646363D01*
X1657907Y241108D01*
X1660896D01*
X1661593Y240411D01*
X1670613D01*
X1678173Y247971D01*
X1682169D01*
X1684509Y245631D01*
G01X1610290Y265352D02*
X1608164D01*
X1602317Y259505D01*
X1599801D01*
X1599586Y259720D01*
X1598280D01*
X1594496Y263504D01*
X1582828D01*
X1582827Y263505D01*
X1581581D01*
X1576492Y258416D01*
Y257724D01*
X1572972Y254204D01*
X1571153D01*
X1570498Y254859D01*
X1568704D01*
X1568703Y254858D01*
X1566801D01*
X1565313Y253370D01*
X1560694D01*
X1559684Y254380D01*
X1552329D01*
X1552327Y254382D01*
X1549209D01*
X1549208Y254381D01*
X1548586D01*
X1548585Y254380D01*
X1537160D01*
X1535916Y255624D01*
X1524136D01*
X1516868Y262892D01*
X1501108D01*
X1498153Y259937D01*
X1490537D01*
X1489844Y259244D01*
X1480309D01*
X1479550Y260003D01*
X1475338D01*
X1472598Y262743D01*
X1471952D01*
X1471951Y262744D01*
X1471329D01*
X1471328Y262743D01*
X1460857D01*
X1459099Y264501D01*
Y264502D01*
X1458551Y265050D01*
Y269953D01*
X1458102Y270402D01*
G01X1586950Y251267D02*
X1585231Y249548D01*
X1572409D01*
X1567865Y245004D01*
X1556385D01*
X1550769Y250620D01*
X1532962D01*
X1532285Y251297D01*
X1522302D01*
X1516046Y257553D01*
X1510255D01*
X1508744Y256042D01*
X1503678D01*
X1500334Y252698D01*
X1491152D01*
X1488112Y255738D01*
X1485531D01*
X1484965Y255172D01*
X1482062D01*
X1478735Y258499D01*
X1471186D01*
X1470957Y258728D01*
X1462078D01*
X1456226Y264580D01*
X1451598D01*
X1450938Y265240D01*
X1448588D01*
X1447133Y266695D01*
Y267704D01*
X1446063Y268774D01*
X1441904D01*
X1440083Y270595D01*
Y280823D01*
X1443783Y284523D01*
X1459731D01*
X1461202Y283052D01*
G01X1570318Y238116D02*
X1569783Y238651D01*
X1554274D01*
X1551545Y235922D01*
X1544791D01*
X1543343Y234474D01*
X1541325D01*
X1539710Y236089D01*
Y236560D01*
X1538652Y237618D01*
X1526090D01*
X1523692Y235220D01*
X1519510D01*
X1518006Y236724D01*
X1507953D01*
X1504162Y240515D01*
X1495878D01*
X1491888Y236525D01*
X1475532D01*
X1474002Y238055D01*
X1446894D01*
X1442980Y241969D01*
Y256903D01*
X1434668Y265215D01*
X1425165D01*
X1419768Y270612D01*
X1412856D01*
X1412717Y270473D01*
X1410979D01*
G01X1412579Y268273D02*
Y269271D01*
X1412970Y269662D01*
X1419374D01*
X1424771Y264265D01*
X1434554D01*
X1442093Y256726D01*
Y241689D01*
X1446552Y237230D01*
X1473660D01*
X1475190Y235700D01*
X1492230D01*
X1496220Y239690D01*
X1503820D01*
X1507538Y235972D01*
X1517658D01*
X1519220Y234410D01*
X1523946D01*
X1525593Y236057D01*
X1530953D01*
X1532680Y234330D01*
X1540405D01*
X1541013Y233722D01*
X1543655D01*
X1545103Y235170D01*
X1551857D01*
X1554586Y237899D01*
X1566792D01*
X1568223Y236468D01*
X1570968D01*
X1572700Y238200D01*
Y239400D01*
G01X1448603Y283053D02*
X1443376D01*
X1440834Y280511D01*
Y272994D01*
X1441695Y272133D01*
X1445968D01*
X1447133Y270968D01*
Y269845D01*
X1447994Y268984D01*
X1453553D01*
X1458347Y264190D01*
Y264189D01*
X1460545Y261991D01*
X1471640D01*
X1474380Y259251D01*
X1479047D01*
X1482374Y255924D01*
X1484653D01*
X1485219Y256490D01*
X1488990D01*
X1492030Y253450D01*
X1500022D01*
X1503366Y256794D01*
X1508432D01*
X1510374Y258736D01*
X1515927D01*
X1522459Y252204D01*
X1532890D01*
X1533722Y251372D01*
X1549833D01*
X1549834Y251373D01*
X1550456D01*
X1550457Y251374D01*
X1551079D01*
X1556697Y245756D01*
X1566725D01*
X1568365Y247396D01*
Y247761D01*
G01X1442304Y305098D02*
X1443774Y306568D01*
Y311796D01*
X1447994Y316016D01*
X1455300D01*
X1456450Y317166D01*
Y318629D01*
X1458279Y320458D01*
X1460479D01*
X1461267Y319670D01*
X1464295D01*
X1465541Y318424D01*
X1467421D01*
X1468812Y319815D01*
X1470575D01*
X1474260Y323500D01*
X1506733D01*
X1510913Y319320D01*
X1519510D01*
X1522230Y316600D01*
X1526720D01*
X1527772Y317652D01*
X1539920D01*
X1542288Y315284D01*
Y310746D01*
X1542300Y310734D01*
Y310625D01*
X1543621Y309304D01*
X1549144D01*
X1549828Y309988D01*
Y310029D01*
X1550751Y310952D01*
X1550792D01*
X1550936Y311096D01*
X1556987D01*
X1560400Y307683D01*
G01X1445454Y308247D02*
X1447134Y309927D01*
X1458661D01*
X1459732Y310998D01*
Y312006D01*
X1460593Y312867D01*
X1465828D01*
X1470043Y317082D01*
X1474627D01*
X1478665Y321120D01*
X1497361D01*
X1500187Y318294D01*
X1501493D01*
X1503409Y320210D01*
X1506831D01*
X1512491Y314550D01*
Y312167D01*
X1515485Y309173D01*
X1518774D01*
X1523167Y313566D01*
X1535437D01*
X1538619Y310384D01*
X1539237D01*
X1542944Y306677D01*
X1545079D01*
X1545581Y306175D01*
X1555538D01*
X1557110Y304603D01*
X1561677D01*
X1564400Y307326D01*
Y308383D01*
G01X1454928Y317723D02*
Y319070D01*
X1458663Y322805D01*
X1468503D01*
X1469203Y323505D01*
X1472525D01*
X1473272Y324252D01*
X1520809D01*
X1521481Y323580D01*
X1525846D01*
X1529734Y319692D01*
G01X1581077Y284825D02*
X1581076D01*
X1579163Y282912D01*
X1578209D01*
X1577234Y283887D01*
Y283928D01*
X1576996Y284166D01*
Y284634D01*
X1571601Y290029D01*
X1568057D01*
X1565458Y292628D01*
X1556065D01*
X1555765Y292928D01*
X1552949D01*
X1552389Y292368D01*
X1546552D01*
X1541315Y297605D01*
X1519582D01*
X1518817Y296840D01*
X1497843D01*
X1495913Y298770D01*
X1494512D01*
X1493070Y297328D01*
X1476548D01*
X1475478Y296258D01*
Y295250D01*
X1474407Y294179D01*
X1460593D01*
X1459701Y295071D01*
Y297149D01*
X1458052Y298798D01*
G01X1552900Y281700D02*
X1552060Y280860D01*
X1521561D01*
X1518283Y277582D01*
X1501598D01*
X1500062Y276046D01*
X1489646D01*
X1488883Y275283D01*
X1482316D01*
X1481714Y275885D01*
Y277650D01*
X1480932Y278432D01*
X1476339D01*
X1475334Y279437D01*
Y280445D01*
X1474407Y281372D01*
X1446924D01*
X1445454Y279902D01*
G01X1451753Y317696D02*
X1462668Y328611D01*
X1482596D01*
X1484100Y330115D01*
G01X1636684Y274815D02*
X1635555D01*
X1632815Y277555D01*
X1632628D01*
X1632625Y277558D01*
X1631047D01*
X1631046Y277557D01*
X1630284D01*
X1622309Y285532D01*
X1602178D01*
X1600246Y287464D01*
X1598044D01*
X1598043Y287463D01*
X1585477D01*
X1583659Y289281D01*
X1578029D01*
X1573646Y293664D01*
X1569296D01*
X1566399Y296561D01*
X1559769D01*
X1557522Y298808D01*
X1544934D01*
X1542729Y301013D01*
X1502758D01*
X1498969Y304802D01*
X1496528D01*
X1494571Y306759D01*
X1473380D01*
X1472328Y305707D01*
Y304698D01*
X1471258Y303628D01*
X1459522D01*
X1458052Y305098D01*
G01X1458400Y318500D02*
X1460390D01*
X1462160Y316730D01*
X1466916D01*
X1468846Y318660D01*
X1473778D01*
X1473798Y318680D01*
X1473882D01*
X1477950Y322748D01*
X1506421D01*
X1511199Y317970D01*
X1515200D01*
X1517910Y315260D01*
X1526760D01*
X1528400Y316900D01*
X1539608D01*
X1541500Y315008D01*
Y310361D01*
X1543680Y308181D01*
X1549319D01*
X1549821Y307679D01*
X1556162D01*
X1557734Y306107D01*
X1561053D01*
X1561976Y307030D01*
Y312452D01*
X1562975Y313451D01*
X1566097D01*
X1566891Y312657D01*
Y311523D01*
X1568119Y310295D01*
X1574530D01*
X1577204Y307621D01*
X1577486D01*
G01X1626291Y273309D02*
X1624375Y275225D01*
X1620912D01*
X1618898Y277239D01*
X1610810D01*
X1609179Y278870D01*
X1563931D01*
X1563930Y278869D01*
X1563308D01*
X1559205Y282972D01*
X1558835D01*
X1557070Y284737D01*
X1553446D01*
X1550321Y281612D01*
X1521065D01*
X1517787Y278334D01*
X1499028D01*
X1499008Y278354D01*
X1498944D01*
X1497735Y279563D01*
X1495345D01*
X1494214Y278432D01*
X1482530D01*
X1480231Y280731D01*
X1478198D01*
X1477383Y281546D01*
X1476375D01*
X1475278Y282643D01*
Y283651D01*
X1474407Y284522D01*
X1465821D01*
X1464351Y283052D01*
G01X1559800Y285300D02*
X1558859Y286241D01*
X1552675D01*
X1549801Y283367D01*
X1499931D01*
X1499500Y283798D01*
X1489656D01*
X1487440Y281582D01*
X1479489D01*
X1478628Y282443D01*
Y283451D01*
X1477558Y284521D01*
X1476550D01*
X1475333Y285738D01*
Y286746D01*
X1474407Y287672D01*
X1457172D01*
X1455702Y286202D01*
X1454902D01*
G01X1458052Y308247D02*
X1459522Y309717D01*
X1464750D01*
X1467240Y312207D01*
Y313216D01*
X1470155Y316131D01*
X1476697D01*
X1477772Y317206D01*
X1479434D01*
X1482247Y320019D01*
X1496371D01*
X1500510Y315880D01*
X1509510D01*
X1511339Y314051D01*
Y311689D01*
X1515007Y308021D01*
X1519284D01*
X1523098Y311835D01*
X1525677D01*
G01X1559500Y290300D02*
Y289947D01*
X1559029Y289476D01*
X1558047D01*
X1557295Y288724D01*
X1549885D01*
X1547745Y290864D01*
X1545928D01*
X1542292Y294500D01*
X1536800D01*
X1536001Y293701D01*
X1531773D01*
X1527858Y289786D01*
X1520514D01*
X1519200Y291100D01*
X1503400D01*
X1502550Y291950D01*
X1489301D01*
X1488900Y292351D01*
X1457902D01*
X1454902Y289351D01*
G01X1510584Y330640D02*
X1508946Y329002D01*
X1498298D01*
X1494300Y333000D01*
X1490792D01*
X1488492Y335300D01*
X1478900D01*
X1474800Y339400D01*
X1467978D01*
X1456478Y327900D01*
X1443500D01*
G01X1662000Y250008D02*
X1656455D01*
X1641917Y264546D01*
Y268126D01*
X1637567Y272476D01*
X1635200D01*
X1632025Y275651D01*
X1631838D01*
X1631836Y275653D01*
X1630429D01*
X1630428Y275652D01*
X1629495D01*
X1622647Y282500D01*
X1611866D01*
X1610738Y283628D01*
X1601388D01*
X1599456Y285560D01*
X1598834D01*
X1598833Y285559D01*
X1584355D01*
X1582626Y287288D01*
X1576710D01*
X1572338Y291660D01*
X1568606D01*
X1565609Y294657D01*
X1558979D01*
X1556732Y296904D01*
X1554122D01*
X1553153Y295935D01*
Y295260D01*
X1551765Y293872D01*
X1547176D01*
X1541939Y299109D01*
X1511749D01*
X1511170Y298530D01*
X1498406D01*
X1494006Y302930D01*
X1492891D01*
X1492403Y303418D01*
X1479489D01*
X1478500Y302429D01*
Y301421D01*
X1477479Y300400D01*
X1476471D01*
X1475440Y299369D01*
Y298361D01*
X1474407Y297328D01*
X1460593D01*
X1459732Y298189D01*
Y299197D01*
X1458661Y300268D01*
X1457443D01*
X1456387Y299212D01*
Y298204D01*
X1455511Y297328D01*
X1453223D01*
X1451753Y298798D01*
G01X1565000Y290500D02*
Y290760D01*
X1563884Y291876D01*
X1555753D01*
X1555453Y292176D01*
X1553277D01*
X1552717Y291616D01*
X1546240D01*
X1542056Y295800D01*
X1537000D01*
X1535653Y294453D01*
X1532778D01*
X1532777Y294454D01*
X1532155D01*
X1532154Y294453D01*
X1531461D01*
X1527546Y290538D01*
X1523489D01*
X1518514Y295513D01*
X1491434D01*
X1489349Y293428D01*
X1457123D01*
X1454902Y295649D01*
G01X1571293Y284755D02*
X1571242D01*
X1570944Y284457D01*
X1567736D01*
X1564145Y288048D01*
X1561972D01*
X1561168Y288852D01*
X1560281D01*
X1560153Y288724D01*
X1558359D01*
X1557607Y287972D01*
X1549573D01*
X1547433Y290112D01*
X1545616D01*
X1545446Y290282D01*
X1530482D01*
X1528099Y287899D01*
X1520273D01*
X1518772Y289400D01*
X1502907D01*
X1502207Y290100D01*
X1488400D01*
X1487679Y290821D01*
X1479489D01*
X1478600Y289932D01*
Y288924D01*
X1477557Y287881D01*
X1476339D01*
X1475300Y288920D01*
Y289928D01*
X1474407Y290821D01*
X1457443D01*
X1456582Y289960D01*
Y288952D01*
X1455511Y287881D01*
X1454293D01*
X1453432Y288742D01*
Y289751D01*
X1452362Y290821D01*
X1443775D01*
X1442304Y289350D01*
G01X1445454Y311397D02*
X1446924Y312867D01*
X1455302D01*
X1456372Y313937D01*
Y314945D01*
X1457443Y316016D01*
X1461810D01*
X1461847Y315979D01*
X1467587D01*
X1469516Y317908D01*
X1474174D01*
X1478262Y321996D01*
X1506109D01*
X1510895Y317210D01*
X1514761D01*
X1516301Y315670D01*
Y313244D01*
G01X1464351Y305098D02*
X1467299D01*
X1468769Y306568D01*
X1471049D01*
X1472192Y307711D01*
Y308720D01*
X1473361Y309889D01*
X1474369D01*
X1475450Y310970D01*
Y311978D01*
X1476489Y313017D01*
X1496994D01*
X1501711Y308300D01*
Y305818D01*
X1503835Y303694D01*
X1520841D01*
X1521793Y304646D01*
X1529613D01*
X1531591Y306624D01*
X1537677D01*
X1541384Y302917D01*
X1543519D01*
X1545724Y300712D01*
X1558312D01*
X1560559Y298465D01*
X1577335D01*
X1580364Y295436D01*
Y295167D01*
X1581287Y294244D01*
X1581556D01*
X1586428Y289372D01*
X1601598D01*
X1603534Y287436D01*
X1624564D01*
X1625846Y286154D01*
G01X1489915Y352637D02*
X1490803Y353525D01*
Y365278D01*
X1488733Y367348D01*
X1482251D01*
X1474915Y374684D01*
X1472604D01*
X1471163Y376125D01*
Y378264D01*
X1464361Y385066D01*
Y385275D01*
G01X1463617Y357259D02*
X1463876Y357000D01*
X1470299D01*
X1479149Y348150D01*
G01X1662000Y399300D02*
X1662900Y400200D01*
Y405099D01*
X1657757Y410242D01*
X1634166D01*
X1632778Y411630D01*
Y462378D01*
X1636300Y465900D01*
Y472900D01*
X1633976Y475224D01*
X1624495D01*
X1621271Y472000D01*
X1603600D01*
X1588400Y487200D01*
X1581519D01*
X1578318Y490401D01*
X1494418D01*
X1492902Y491917D01*
X1492901D01*
X1491961Y492857D01*
X1486488D01*
X1485548Y491917D01*
X1481828D01*
X1477700Y487789D01*
X1466548D01*
X1462420Y491917D01*
X1454061D01*
X1449884Y487740D01*
Y487592D01*
X1449568Y487276D01*
G01X1458060Y495020D02*
X1460411Y492669D01*
X1463043D01*
X1467030Y488682D01*
X1477238D01*
X1481224Y492668D01*
X1485236D01*
X1486176Y493608D01*
X1492661D01*
X1495094Y491175D01*
X1578606D01*
X1578628Y491153D01*
X1578630D01*
X1581183Y488600D01*
X1590629D01*
X1598157Y481072D01*
X1603044D01*
X1605200Y478916D01*
Y474716D01*
X1606916Y473000D01*
X1621036D01*
X1624012Y475976D01*
X1634524D01*
X1637292Y473208D01*
Y465308D01*
X1633800Y461816D01*
Y424900D01*
X1636500Y422200D01*
Y414900D01*
X1634500Y412900D01*
X1634400D01*
G01X1461267Y489790D02*
X1464281Y486776D01*
X1478235D01*
X1479928Y488469D01*
X1483163D01*
X1486800Y492106D01*
X1491649D01*
X1494106Y489649D01*
X1578006D01*
X1581455Y486200D01*
X1588300D01*
X1610336Y464164D01*
Y463050D01*
X1611509Y461877D01*
X1611642D01*
G01X1456602Y485864D02*
X1457554Y486816D01*
X1460965D01*
X1476132Y471649D01*
Y445298D01*
X1478375Y443055D01*
Y440495D01*
X1480068Y438802D01*
Y422369D01*
X1481937Y420500D01*
X1482441D01*
X1483750Y419191D01*
Y416744D01*
X1485700Y414794D01*
Y410918D01*
X1487114Y409504D01*
X1490126D01*
X1491500Y408130D01*
Y406700D01*
X1494945Y403255D01*
Y400523D01*
X1493755Y399333D01*
Y396255D01*
X1494945Y395065D01*
Y393635D01*
X1496895Y391685D01*
Y389495D01*
X1495705Y388305D01*
Y386115D01*
X1496895Y384925D01*
Y384383D01*
X1498814Y382464D01*
X1509626D01*
X1510545Y381545D01*
Y381003D01*
X1513255Y378293D01*
Y376863D01*
X1514174Y375944D01*
X1521055D01*
X1522625Y377514D01*
G01X1456590Y488976D02*
X1457594Y487972D01*
X1461638D01*
X1467154Y482456D01*
X1476058D01*
X1477167Y483565D01*
X1483638D01*
X1484747Y482456D01*
X1566111D01*
X1567307Y481260D01*
Y480623D01*
X1568774Y479156D01*
X1578184D01*
X1584970Y472370D01*
G01X1515328Y363389D02*
Y370372D01*
X1509000Y376700D01*
Y377760D01*
X1507436Y379324D01*
X1492724D01*
X1491805Y380243D01*
Y381673D01*
X1489855Y383623D01*
Y384925D01*
X1491045Y386115D01*
Y389193D01*
X1489855Y390383D01*
Y391685D01*
X1491045Y392875D01*
Y395572D01*
X1489855Y396762D01*
Y398814D01*
X1491045Y400004D01*
Y402655D01*
X1489800Y403900D01*
Y405200D01*
X1486900Y408100D01*
Y408600D01*
X1483900Y411600D01*
Y415104D01*
X1481904Y417100D01*
X1481399D01*
X1479317Y419182D01*
Y438490D01*
X1477624Y440183D01*
Y442743D01*
X1475380Y444987D01*
Y470172D01*
X1460661Y484891D01*
G01X1598602Y-600D02*
X1594102Y3900D01*
X1586160D01*
X1585260Y3000D01*
X1578100D01*
X1576024Y5076D01*
X1526376D01*
X1524800Y3500D01*
G01X1501900Y-9124D02*
Y-9200D01*
X1501500Y-8800D01*
Y-6300D01*
X1504700Y-3100D01*
X1520400D01*
X1522500Y-1000D01*
Y5500D01*
X1525800Y8800D01*
X1529400D01*
X1530251Y7949D01*
X1574903D01*
X1575876Y6976D01*
X1586724D01*
X1588651Y5049D01*
X1600501D01*
X1604694Y856D01*
X1637109D01*
X1643218Y-5253D01*
X1654916D01*
X1662243Y2074D01*
X1677016D01*
X1679518Y4576D01*
X1686424D01*
X1688000Y3000D01*
G01X1473200Y118300D02*
X1475100Y116400D01*
Y113949D01*
X1487090Y101959D01*
Y94280D01*
X1505864Y75506D01*
X1540647D01*
X1544600Y79459D01*
Y84700D01*
X1545700Y85800D01*
X1553730D01*
X1559047Y80483D01*
X1577273D01*
X1579400Y82610D01*
Y87000D01*
X1583327Y90927D01*
X1594026D01*
X1596999Y93900D01*
X1597867D01*
G01X1472500Y123700D02*
X1471503Y122703D01*
Y116800D01*
X1472897Y115406D01*
Y109914D01*
X1474206Y108604D01*
X1475575D01*
X1483892Y100287D01*
Y93935D01*
X1504925Y72902D01*
X1541586D01*
X1541786Y73102D01*
X1541980D01*
X1548609Y79731D01*
X1586212D01*
X1587597Y81116D01*
X1594563D01*
X1596179Y79500D01*
X1597987D01*
G01X1643500Y80400D02*
X1642598Y81302D01*
X1631469D01*
X1625253Y87518D01*
X1612904D01*
X1608960Y91462D01*
X1602950D01*
X1600873Y93539D01*
Y94940D01*
X1599413Y96400D01*
X1595700D01*
X1595164Y95864D01*
X1581725D01*
X1578445Y92584D01*
X1555646D01*
X1553680Y94550D01*
X1534897D01*
X1526464Y86117D01*
X1519599D01*
G01X1473096Y120999D02*
X1477910Y116185D01*
Y113891D01*
X1483906Y107895D01*
X1490848D01*
X1492922Y105821D01*
Y99978D01*
X1511900Y81000D01*
X1514892D01*
X1518427Y84535D01*
X1531424D01*
X1533558Y82401D01*
X1541187D01*
X1545566Y86780D01*
X1554909D01*
X1559264Y82425D01*
X1577171D01*
X1578023Y83277D01*
Y86605D01*
X1574780Y89848D01*
Y90992D01*
G01X1473100Y131900D02*
X1472448D01*
X1470460Y129912D01*
Y126140D01*
X1471200Y125400D01*
X1475943D01*
X1478918Y122425D01*
Y115185D01*
X1485456Y108647D01*
X1491160D01*
X1494580Y105227D01*
Y99483D01*
X1511348Y82715D01*
X1515263D01*
X1516801Y84253D01*
Y86310D01*
X1520709Y90218D01*
X1527527D01*
X1533033Y95724D01*
X1542553D01*
X1543409Y96580D01*
X1557110D01*
X1558400Y95290D01*
X1569240D01*
X1570767Y93763D01*
X1577994D01*
X1581247Y97016D01*
X1587886D01*
X1591518Y100648D01*
X1596267D01*
X1602990Y93925D01*
X1604000D01*
G01X1546370Y84180D02*
Y79599D01*
X1541025Y74254D01*
X1505486D01*
X1485671Y94069D01*
Y100730D01*
X1476031Y110370D01*
X1474717D01*
G01X1591800Y164900D02*
X1591750Y164850D01*
X1585326D01*
X1581724Y161248D01*
X1577562D01*
X1566814Y150500D01*
X1552220D01*
X1546665Y144945D01*
X1535966D01*
X1533963Y142942D01*
X1528158D01*
X1527071Y144029D01*
X1512062D01*
X1511149Y144942D01*
X1506791D01*
X1505617Y146116D01*
Y146346D01*
X1505673D01*
G01X1552051Y172053D02*
X1551298Y171300D01*
X1528753D01*
X1526802Y169349D01*
X1525938D01*
X1521013Y164424D01*
X1508076D01*
X1506053Y166447D01*
X1501163D01*
X1499516Y164800D01*
X1498630D01*
X1498624Y164806D01*
X1496362D01*
X1496356Y164800D01*
X1486390D01*
X1477043Y155453D01*
X1475561D01*
X1473354Y153246D01*
G01X1552171Y133000D02*
X1549249Y130078D01*
X1533397D01*
X1532877Y129558D01*
X1522885D01*
X1519865Y132578D01*
X1517523D01*
X1514600Y129655D01*
Y126650D01*
G01X1518376Y111499D02*
Y108826D01*
X1516862Y107312D01*
Y100273D01*
X1517785Y99350D01*
X1520442D01*
X1522196Y101104D01*
X1530200D01*
X1533310Y104214D01*
X1543910D01*
X1546191Y106495D01*
X1551645D01*
X1554540Y103600D01*
X1564062D01*
X1566693Y100969D01*
X1577418D01*
X1579249Y102800D01*
X1596341D01*
X1602465Y96676D01*
X1604540D01*
X1605014Y96202D01*
X1607096D01*
X1607097Y96201D01*
X1607736D01*
X1612176Y91761D01*
Y91747D01*
X1613002Y90921D01*
X1613016D01*
X1613064Y90873D01*
X1625127D01*
X1630000Y86000D01*
X1640376D01*
X1640377Y86001D01*
X1642063D01*
X1644340Y83724D01*
X1659736D01*
X1661936Y85924D01*
X1664924D01*
X1667000Y88000D01*
G01X1476761Y152725D02*
X1476826D01*
G01X1651536Y159585D02*
X1650061Y158110D01*
X1647820D01*
X1646512Y156802D01*
X1621515D01*
X1618625Y153912D01*
Y149784D01*
X1617503Y148662D01*
X1609552D01*
X1608828Y149386D01*
X1608058D01*
X1608057Y149387D01*
X1607715D01*
X1604779Y152323D01*
X1602847D01*
X1600760Y150236D01*
X1599436D01*
X1596116Y146916D01*
X1592498D01*
X1587452Y141870D01*
X1584013D01*
X1579773Y137630D01*
X1577433D01*
X1573032Y142031D01*
X1566869D01*
X1562529Y146371D01*
X1554270D01*
X1551930Y144031D01*
X1551910D01*
X1550370Y142491D01*
Y142471D01*
X1546183Y138284D01*
X1534771D01*
X1534071Y138984D01*
X1528604D01*
X1525220Y135600D01*
X1518201D01*
X1514164Y131563D01*
X1509436D01*
X1505884Y135115D01*
X1490353D01*
X1479800Y145668D01*
Y149751D01*
X1476826Y152725D01*
G01X1632006Y94500D02*
X1631257Y95249D01*
X1620154D01*
X1617717Y97686D01*
X1612077D01*
X1611898Y97865D01*
X1611897D01*
X1608808Y100954D01*
X1606190D01*
X1601010Y106134D01*
X1591974D01*
X1589744Y108364D01*
X1586575D01*
X1584631Y106420D01*
X1581057D01*
X1580214Y107263D01*
X1577552D01*
X1577551Y107264D01*
X1575271D01*
X1573727Y105720D01*
X1572115D01*
X1570995Y104600D01*
X1554887D01*
X1552040Y107447D01*
X1545796D01*
X1543515Y105166D01*
X1532915D01*
X1529849Y102100D01*
X1521845D01*
X1520671Y100926D01*
X1518438D01*
G01X1562150Y160700D02*
X1561618Y161232D01*
X1548301D01*
X1546187Y159118D01*
X1542263D01*
X1542262Y159119D01*
X1541308D01*
X1538549Y156360D01*
Y155857D01*
X1538550Y155856D01*
Y155500D01*
X1533930Y150880D01*
X1530376D01*
X1527183Y147687D01*
X1513858D01*
X1512747Y148798D01*
X1509934D01*
X1505822Y152910D01*
X1499416D01*
X1499064Y153262D01*
Y156085D01*
X1495649Y159500D01*
X1494939D01*
G01X1563108Y126423D02*
X1559876Y129655D01*
Y129662D01*
X1558836Y130702D01*
X1554173D01*
X1552045Y128574D01*
X1534021D01*
X1533501Y128054D01*
X1520604D01*
X1520150Y127600D01*
G01X1475200Y142600D02*
X1480018D01*
X1491807Y130811D01*
X1514692D01*
X1517211Y133330D01*
X1520276D01*
X1523296Y130310D01*
X1532565D01*
X1533085Y130830D01*
X1546750D01*
X1552965Y137045D01*
Y141631D01*
X1554380Y143046D01*
X1559776D01*
X1561125Y141697D01*
Y137512D01*
X1562987Y135650D01*
Y132233D01*
X1564951Y130269D01*
X1575951D01*
X1578362Y132680D01*
X1595472D01*
X1596167Y133375D01*
X1602411D01*
X1606222Y129564D01*
X1612066D01*
X1612817Y130315D01*
X1625694D01*
X1626289Y129720D01*
X1638080D01*
X1640240Y127560D01*
Y124366D01*
X1641280Y123326D01*
X1652010D01*
X1653211Y124527D01*
Y125552D01*
X1654084Y126425D01*
X1658437D01*
X1659310Y125552D01*
Y124328D01*
X1660373Y123265D01*
X1661597D01*
X1662460Y122402D01*
Y120315D01*
X1664135Y118640D01*
G01X1613741D02*
X1612266Y117165D01*
X1604430D01*
X1599223Y122372D01*
X1597300D01*
X1594402Y119474D01*
X1583119D01*
X1580604Y116959D01*
X1554441D01*
X1543578Y127822D01*
X1534333D01*
X1533769Y127258D01*
X1522408D01*
X1518449Y123299D01*
X1510181D01*
X1504454Y129026D01*
X1499831D01*
X1497451Y126646D01*
X1481357D01*
X1479053Y128950D01*
X1473100D01*
G01X1497493Y162078D02*
X1497629Y161942D01*
X1499398D01*
X1511038Y150302D01*
X1513371D01*
X1514482Y149191D01*
X1518016D01*
X1521209Y152384D01*
X1533306D01*
X1537044Y156122D01*
Y156983D01*
X1544127Y164066D01*
X1550435D01*
X1551753Y162748D01*
X1557784D01*
X1563268Y168232D01*
X1568430D01*
X1569700Y169502D01*
X1572409D01*
X1572817Y169910D01*
G01X1500643Y154819D02*
X1501040Y154422D01*
X1505374D01*
X1510246Y149550D01*
X1513059D01*
X1514170Y148439D01*
X1518328D01*
X1521521Y151632D01*
X1533618D01*
X1537797Y155811D01*
Y156167D01*
X1537796Y156168D01*
Y156671D01*
X1540996Y159871D01*
X1542574D01*
X1542575Y159870D01*
X1542771D01*
X1542795Y159894D01*
X1545899D01*
X1548005Y162000D01*
X1551437D01*
X1551441Y161996D01*
X1558096D01*
X1563486Y167386D01*
X1570292D01*
X1570294Y167384D01*
G01X1655031Y184505D02*
X1654526Y184000D01*
X1646863D01*
X1646279Y183416D01*
X1643234D01*
X1640925Y181107D01*
X1632592D01*
X1626521Y187178D01*
Y187179D01*
X1624851Y188849D01*
X1607212D01*
X1604950Y186587D01*
Y183671D01*
X1603921Y182642D01*
Y180222D01*
X1603760Y180061D01*
Y180056D01*
X1602838Y179134D01*
X1601532D01*
X1600610Y180056D01*
Y180058D01*
X1600525Y180143D01*
Y180953D01*
X1599603Y181875D01*
X1594128D01*
X1592896Y180643D01*
X1583726D01*
X1576131Y173048D01*
X1569842D01*
X1567494Y170700D01*
X1561894D01*
X1559590Y168396D01*
X1541759D01*
X1541414Y168051D01*
X1536000D01*
X1532006Y164057D01*
X1525656D01*
X1515599Y154000D01*
X1513700D01*
X1513500Y153800D01*
G01X1598950Y180300D02*
X1597153Y178503D01*
X1584538D01*
X1578279Y172244D01*
X1571036D01*
X1569835Y171043D01*
X1569043D01*
X1567736Y169736D01*
X1562644D01*
X1559921Y167013D01*
X1544452D01*
X1535460Y158021D01*
Y157131D01*
X1532353Y154024D01*
X1517924D01*
X1515643Y151743D01*
X1515358D01*
G01X1488300Y161700D02*
Y160700D01*
X1486724Y159124D01*
Y144564D01*
X1488064Y143224D01*
X1489753D01*
X1492827Y146298D01*
Y150328D01*
X1494675Y152176D01*
X1496549D01*
X1498612Y150113D01*
X1504229D01*
X1508648Y145694D01*
X1511461D01*
X1512372Y144783D01*
X1527539D01*
X1531332Y148576D01*
X1535776D01*
X1540700Y153500D01*
X1543829D01*
X1549257Y158928D01*
X1558902D01*
X1560330Y157500D01*
X1565209D01*
X1576014Y168305D01*
X1579700D01*
X1585054Y173659D01*
X1594429D01*
X1594430Y173660D01*
X1595654D01*
X1595655Y173659D01*
X1595761D01*
X1597236Y172184D01*
X1597642D01*
G01X1518514Y130991D02*
X1520358D01*
X1522543Y128806D01*
X1533189D01*
X1533709Y129326D01*
X1551733D01*
X1553861Y131454D01*
X1561080D01*
X1564704Y127830D01*
X1573848D01*
X1573933Y127915D01*
X1574197D01*
G01X1513879Y113349D02*
X1520169Y119639D01*
Y123762D01*
X1522903Y126496D01*
X1527693D01*
X1529800Y124389D01*
Y123497D01*
X1536603Y116694D01*
X1544882D01*
X1545519Y117331D01*
X1550463D01*
X1553140Y114654D01*
X1580472D01*
X1583790Y117972D01*
X1595026D01*
X1595106Y118052D01*
X1599644D01*
X1606930Y110766D01*
X1617545D01*
X1617569Y110790D01*
X1643140D01*
X1643730Y111380D01*
Y113080D01*
X1645237Y114587D01*
Y115491D01*
G01X1524900Y139100D02*
X1526513D01*
X1527901Y140488D01*
X1534980D01*
X1535094Y140602D01*
X1535095D01*
X1536786Y142293D01*
X1547763D01*
X1548102Y142632D01*
X1548103D01*
X1553346Y147875D01*
X1563153D01*
X1564099Y146929D01*
X1571652D01*
X1572359Y146222D01*
X1586653D01*
X1596131Y155700D01*
X1600310D01*
X1605233Y160623D01*
Y162613D01*
X1606939Y164319D01*
X1620561D01*
X1620651Y164409D01*
X1620653D01*
X1621517Y165273D01*
Y167445D01*
X1620006Y168956D01*
G01X1620041Y165885D02*
X1618566Y167360D01*
X1608865D01*
X1601051Y159546D01*
X1595850D01*
X1592804Y156500D01*
X1592038D01*
X1583462Y147924D01*
X1573064D01*
X1571308Y149680D01*
X1552743D01*
X1547058Y143995D01*
X1536080D01*
X1534275Y142190D01*
X1526310D01*
G01X1651536Y162735D02*
X1650690D01*
X1649117Y161162D01*
X1647878D01*
X1647777Y161061D01*
X1647775D01*
X1646911Y160197D01*
Y158645D01*
X1646182Y157916D01*
X1603590D01*
X1600622Y154948D01*
X1596472D01*
X1586994Y145470D01*
X1572047D01*
X1571340Y146177D01*
X1563787D01*
X1562841Y147123D01*
X1553658D01*
X1547989Y141454D01*
X1537413D01*
X1535695Y139736D01*
X1528236D01*
X1524900Y136400D01*
X1521649D01*
X1515771Y142278D01*
X1512077D01*
X1510837Y141038D01*
X1507463D01*
X1505612Y142889D01*
Y143438D01*
X1504988Y144062D01*
X1500203D01*
X1496150Y148115D01*
G01X1590569Y152464D02*
X1585277Y147172D01*
X1572473D01*
X1570852Y148793D01*
X1552920D01*
X1548193Y144066D01*
Y144065D01*
X1547377Y143249D01*
X1547376D01*
X1547370Y143243D01*
X1536672D01*
X1534851Y141422D01*
X1527771D01*
X1526963Y140614D01*
X1525657D01*
X1524971Y141300D01*
X1517813D01*
X1515836Y143277D01*
X1511750D01*
X1510837Y144190D01*
X1505924D01*
X1505300Y144814D01*
X1500885D01*
X1497726Y147973D01*
Y148768D01*
X1495894Y150600D01*
X1495848D01*
G01X1696907Y99077D02*
Y99985D01*
X1690965Y105927D01*
X1668804D01*
X1666102Y103225D01*
X1656589D01*
X1654129Y100765D01*
X1650902D01*
X1647851Y103816D01*
X1612818D01*
X1610421Y106213D01*
X1609557D01*
X1607257Y108513D01*
X1605898D01*
X1601191Y113220D01*
X1596122D01*
X1595584Y113758D01*
X1593000D01*
X1590542Y111300D01*
X1583329D01*
X1583153Y111476D01*
X1581847D01*
X1581671Y111300D01*
X1580657D01*
X1579277Y109920D01*
X1573790D01*
X1573048Y109178D01*
X1562651D01*
X1561529Y110300D01*
X1538472D01*
X1528289Y120483D01*
Y121505D01*
X1527249Y122545D01*
X1524755D01*
X1524000Y123300D01*
G01X1645237Y112341D02*
Y111378D01*
X1641529Y107670D01*
X1616678D01*
X1616633Y107715D01*
X1610181D01*
X1607881Y110015D01*
X1606617D01*
X1601731Y114901D01*
X1597616D01*
X1596315Y116202D01*
X1583431D01*
X1578653Y111424D01*
X1577347D01*
X1575663Y113108D01*
X1545226D01*
X1542392Y115942D01*
X1533894D01*
X1529048Y120788D01*
Y124077D01*
X1527381Y125744D01*
X1523215D01*
X1520921Y123450D01*
Y118162D01*
X1514496Y111737D01*
X1507069D01*
X1502256Y106924D01*
X1500176D01*
X1498810Y108290D01*
G01X1482455Y124222D02*
X1487114D01*
X1494808Y116509D01*
Y112116D01*
X1496930Y109994D01*
Y109957D01*
X1497150Y109737D01*
Y107721D01*
X1498699Y106172D01*
X1502568D01*
X1507381Y110985D01*
X1515445D01*
X1517535Y113075D01*
X1521689D01*
X1524030Y110734D01*
X1528118D01*
X1529400Y109452D01*
X1561124D01*
X1562804Y107772D01*
X1572747D01*
X1574143Y109168D01*
X1578341D01*
X1578342Y109167D01*
X1579588D01*
X1579589Y109168D01*
X1581003D01*
X1581847Y108324D01*
X1583153D01*
X1585229Y110400D01*
X1590995D01*
X1593601Y113006D01*
X1593928D01*
X1593929Y113007D01*
X1595153D01*
X1595828Y112332D01*
X1601015D01*
X1605251Y108096D01*
Y106145D01*
X1606829Y104567D01*
X1609543D01*
X1613016Y101094D01*
X1641317D01*
X1644957Y97454D01*
X1652361D01*
X1652362Y97453D01*
X1652962D01*
X1652963Y97454D01*
X1652985D01*
X1657159Y101628D01*
X1666011D01*
X1667109Y100530D01*
X1670657D01*
X1671552Y101425D01*
X1679053D01*
X1679229Y101601D01*
X1684237D01*
X1686876Y98962D01*
G01X1674455Y172658D02*
X1673552D01*
X1670407Y175803D01*
X1667144D01*
X1666503Y176444D01*
X1655653D01*
X1651500Y180597D01*
X1650241D01*
X1648732Y179088D01*
X1628412D01*
X1623823Y183677D01*
Y184406D01*
X1623824Y184407D01*
Y185713D01*
X1622592Y186945D01*
X1608002D01*
X1606481Y185424D01*
Y183076D01*
X1605423Y182018D01*
Y179598D01*
X1605422Y179597D01*
Y179287D01*
X1602283Y176148D01*
X1585348D01*
X1579057Y169857D01*
X1575276D01*
X1572654Y167235D01*
Y167232D01*
X1571230Y165808D01*
X1567726D01*
X1565278Y163360D01*
Y159404D01*
X1564874Y159000D01*
X1560999D01*
X1559919Y160080D01*
X1548779D01*
X1546665Y157966D01*
X1541785D01*
X1539702Y155883D01*
Y155000D01*
X1534430Y149728D01*
X1530854D01*
X1527461Y146335D01*
X1513015D01*
X1512104Y147246D01*
X1509291D01*
X1505535Y151002D01*
X1505534D01*
X1505271Y151265D01*
X1499090D01*
X1498664Y151691D01*
Y151709D01*
X1497614Y152759D01*
Y155340D01*
X1496444Y156510D01*
X1494883D01*
X1493465Y157928D01*
X1491409D01*
X1490237Y156756D01*
Y148449D01*
X1488800Y147012D01*
Y145000D01*
G01X1603300Y185100D02*
X1602197Y183997D01*
X1593318D01*
X1592421Y183100D01*
X1583489D01*
X1575358Y174969D01*
X1569069D01*
X1567600Y173500D01*
X1562618D01*
X1562191Y173073D01*
X1561573D01*
X1558800Y170300D01*
X1533177D01*
X1528688Y165811D01*
X1524005D01*
X1521098Y162904D01*
X1506673D01*
X1504706Y164871D01*
G01X1513136Y157081D02*
X1516581D01*
X1524309Y164809D01*
X1529666D01*
X1531080Y166223D01*
Y166259D01*
X1533624Y168803D01*
X1541102D01*
X1541847Y169548D01*
X1559112D01*
X1561885Y172321D01*
X1567485D01*
X1569364Y174200D01*
X1575653D01*
X1583586Y182133D01*
X1592710D01*
X1593398Y182821D01*
X1600073D01*
X1602185Y180709D01*
G01X1473798Y273603D02*
X1474430D01*
X1475900Y272133D01*
X1477912D01*
X1478607Y271438D01*
Y266716D01*
X1480057Y265266D01*
X1482143D01*
X1482623Y264786D01*
X1487902D01*
X1488324Y265208D01*
X1495816D01*
X1498873Y268265D01*
X1530814D01*
X1539412Y259667D01*
X1540658D01*
X1540659Y259668D01*
X1555000D01*
X1565231Y269899D01*
X1600200D01*
X1600771Y270470D01*
X1601870D01*
G01X1596300Y250320D02*
X1592872Y246892D01*
X1573511D01*
X1568967Y242348D01*
X1552018D01*
X1550298Y240628D01*
X1550182D01*
X1550144Y240590D01*
X1546640D01*
X1543948Y243282D01*
X1540457D01*
X1539202Y242027D01*
X1539180D01*
X1539145Y241992D01*
X1527218D01*
X1524850Y244360D01*
X1522650D01*
X1519614Y241324D01*
X1517281D01*
X1516613Y240656D01*
G01X1563157Y258164D02*
X1541283D01*
X1541282Y258163D01*
X1538788D01*
X1530190Y266761D01*
X1499497D01*
X1496440Y263704D01*
X1488948D01*
X1488526Y263282D01*
X1482000D01*
X1481519Y263763D01*
X1477800D01*
X1472241Y269322D01*
Y271206D01*
X1470649Y272798D01*
Y273603D01*
G01X1661186Y245352D02*
X1656855D01*
X1639709Y262498D01*
X1636136D01*
X1634828Y263806D01*
Y267528D01*
X1631546Y270810D01*
X1609136D01*
X1604720Y275226D01*
X1507725D01*
X1504299Y271800D01*
X1494677D01*
X1492753Y273724D01*
G01X1476948Y276753D02*
X1477551D01*
X1479207Y275097D01*
X1481273D01*
X1481673Y274697D01*
Y272952D01*
X1482492Y272133D01*
X1487006D01*
X1490167Y275294D01*
X1500409D01*
X1501853Y276738D01*
X1605336D01*
X1606939Y275135D01*
X1618025D01*
X1619330Y273830D01*
Y273815D01*
X1621583Y271562D01*
X1631858D01*
X1635861Y267559D01*
X1636562D01*
X1639661Y264460D01*
Y263610D01*
X1656343Y246928D01*
X1662000D01*
X1662956Y245972D01*
Y243582D01*
G01X1495696Y258361D02*
X1497641D01*
X1501280Y262000D01*
X1516600D01*
X1523946Y254654D01*
X1533948D01*
X1534974Y253628D01*
X1548897D01*
X1548898Y253629D01*
X1549520D01*
X1549521Y253630D01*
X1552015D01*
X1552017Y253628D01*
X1559372D01*
X1560430Y252570D01*
X1565577D01*
X1567113Y254106D01*
X1570187D01*
X1570841Y253452D01*
X1573284D01*
X1577244Y257412D01*
Y258104D01*
X1581893Y262753D01*
X1582515D01*
X1582516Y262752D01*
X1594184D01*
X1597968Y258968D01*
X1599274D01*
X1599489Y258753D01*
X1602629D01*
X1604260Y260384D01*
X1624217D01*
X1626101Y258500D01*
X1629500D01*
X1636100Y251900D01*
X1646051D01*
X1657595Y240356D01*
X1660584D01*
X1661281Y239659D01*
X1677992D01*
X1679103Y240770D01*
X1684758D01*
X1685305Y241317D01*
Y244196D01*
X1690565Y249456D01*
Y251052D01*
G01X1547869Y243356D02*
X1549124Y244611D01*
Y246576D01*
X1546800Y248900D01*
X1536295D01*
X1533545Y246150D01*
X1530640D01*
X1529666Y247124D01*
X1522712D01*
X1514987Y254849D01*
X1511719D01*
X1510495Y253625D01*
Y252801D01*
X1507140Y249446D01*
Y246336D01*
X1508800Y244676D01*
X1509800D01*
G01X1483247Y267304D02*
X1484927Y268984D01*
X1491094D01*
X1491996Y269886D01*
X1496187D01*
X1496188Y269887D01*
X1531320D01*
X1540035Y261172D01*
X1553500D01*
X1563894Y271566D01*
X1598941D01*
X1600279Y272904D01*
X1600286Y272897D01*
X1604297D01*
X1604298Y272898D01*
X1604920D01*
X1608512Y269306D01*
X1630574D01*
X1630577Y269303D01*
X1630925D01*
X1633324Y266904D01*
Y261904D01*
X1636028Y259200D01*
X1641943D01*
X1658531Y242612D01*
X1661520D01*
X1662217Y241915D01*
X1664044D01*
X1665692Y243563D01*
X1672701D01*
X1677861Y248723D01*
X1684232D01*
X1686113Y250604D01*
G01X1486397Y270454D02*
X1487867Y271924D01*
X1491908D01*
X1493193Y270639D01*
X1531632D01*
X1540347Y261924D01*
X1553000D01*
X1563394Y272318D01*
X1598629D01*
X1599975Y273664D01*
X1605218D01*
X1608824Y270058D01*
X1630886D01*
X1630888Y270056D01*
X1631236D01*
X1634076Y267216D01*
Y262216D01*
X1635370Y260922D01*
X1637281D01*
G01X1523580Y237960D02*
X1525120D01*
X1525530Y238370D01*
X1539350D01*
X1540050Y237670D01*
X1544687D01*
X1545683Y236674D01*
X1551233D01*
X1554251Y239692D01*
X1570691D01*
X1574823Y243824D01*
X1600573D01*
X1605240Y248491D01*
Y253833D01*
X1607245Y255838D01*
X1612268D01*
X1615693Y252413D01*
X1621215D01*
X1621234Y252432D01*
X1621236D01*
X1624004Y255200D01*
X1628200D01*
X1628204Y255196D01*
X1631020D01*
X1635165Y251051D01*
X1640157D01*
X1643775Y247433D01*
Y246137D01*
G01X1620250Y254741D02*
X1619782D01*
X1619478Y255045D01*
X1616620D01*
X1614085Y257580D01*
X1605587D01*
X1600879Y252872D01*
X1597846D01*
X1596273Y254445D01*
X1580303D01*
X1576748Y250890D01*
X1571380D01*
X1569840Y249350D01*
X1566430D01*
X1563588Y246508D01*
X1557900D01*
X1552284Y252124D01*
X1551393D01*
X1551391Y252126D01*
X1550145D01*
X1550144Y252125D01*
X1549522D01*
X1549521Y252124D01*
X1534180D01*
X1533223Y253081D01*
X1523212D01*
X1516405Y259888D01*
X1510109D01*
X1507845Y257624D01*
X1503132D01*
X1499789Y254281D01*
X1494425D01*
X1493199Y255507D01*
G01X1620240Y257660D02*
X1620123D01*
X1618260Y255797D01*
X1616932D01*
X1614397Y258332D01*
X1605275D01*
X1600783Y253840D01*
X1597942D01*
X1596585Y255197D01*
X1579991D01*
X1579694Y254900D01*
X1579565D01*
X1576307Y251642D01*
X1571052D01*
X1569530Y250120D01*
X1566130D01*
X1563270Y247260D01*
X1558212D01*
X1552596Y252876D01*
X1551705D01*
X1551703Y252878D01*
X1549833D01*
X1549832Y252877D01*
X1549210D01*
X1549209Y252876D01*
X1534492D01*
X1533500Y253868D01*
X1523489D01*
X1516357Y261000D01*
X1501344D01*
X1497854Y257510D01*
X1497331D01*
X1495682Y255861D01*
G01X1504461Y274426D02*
X1506021Y275986D01*
X1605024D01*
X1607577Y273433D01*
X1617498D01*
G01X1596600Y246350D02*
X1595990Y245740D01*
X1573989D01*
X1569445Y241196D01*
X1552496D01*
X1550776Y239476D01*
X1550660D01*
X1550574Y239390D01*
X1546210D01*
X1543470Y242130D01*
X1540935D01*
X1539645Y240840D01*
X1521755D01*
X1520413Y239498D01*
G01X1489546Y279902D02*
X1492690Y283046D01*
X1499188D01*
X1503148Y279086D01*
X1517239D01*
X1520517Y282364D01*
X1549862D01*
X1552987Y285489D01*
X1557752D01*
X1558224Y285017D01*
Y284647D01*
X1559147Y283724D01*
X1559517D01*
X1563619Y279622D01*
X1609503D01*
X1611134Y277991D01*
X1619478D01*
X1621374Y276097D01*
X1625858D01*
X1628560Y273395D01*
X1631089D01*
X1636173Y268311D01*
X1636874D01*
X1640413Y264772D01*
Y263922D01*
X1656655Y247680D01*
X1662320D01*
X1664861Y245139D01*
X1666329D01*
G01X1550619Y303087D02*
X1545477D01*
X1544143Y304421D01*
X1542008D01*
X1538301Y308128D01*
X1530796D01*
X1529683Y307015D01*
X1526936D01*
G01X1516138Y310749D02*
X1519286D01*
X1522855Y314318D01*
X1535749D01*
X1538931Y311136D01*
X1539549D01*
X1543256Y307429D01*
X1545391D01*
X1545893Y306927D01*
X1555850D01*
X1557422Y305355D01*
X1561365D01*
X1562786Y306776D01*
Y312004D01*
X1563448Y312666D01*
X1565328D01*
X1566051Y311943D01*
Y309089D01*
X1569937Y305203D01*
X1578393D01*
X1581390Y308200D01*
X1587800D01*
G01X1636914Y270900D02*
X1635712D01*
X1631713Y274899D01*
X1631526D01*
X1631525Y274900D01*
X1631364D01*
X1631363Y274901D01*
X1630741D01*
X1630740Y274900D01*
X1629183D01*
X1622583Y281500D01*
X1611610D01*
X1610234Y282876D01*
X1601076D01*
X1599145Y284807D01*
X1584043D01*
X1582314Y286536D01*
X1576398D01*
X1572153Y290781D01*
X1568369D01*
X1565770Y293380D01*
X1556377D01*
X1556077Y293680D01*
X1552637D01*
X1552077Y293120D01*
X1546864D01*
X1541627Y298357D01*
X1512562D01*
X1511983Y297778D01*
X1497969D01*
X1496226Y299521D01*
X1494199D01*
X1494008Y299330D01*
X1490987D01*
X1490049Y300268D01*
X1481568D01*
X1480098Y298798D01*
G01X1688451Y249716D02*
Y251132D01*
X1687382Y252201D01*
X1678059D01*
X1675447Y249589D01*
X1665822D01*
X1663275Y252136D01*
X1655391D01*
X1642669Y264858D01*
Y268438D01*
X1637879Y273228D01*
X1635512D01*
X1632337Y276403D01*
X1632150D01*
X1632147Y276406D01*
X1631525D01*
X1631524Y276405D01*
X1630117D01*
X1630116Y276404D01*
X1629807D01*
X1622711Y283500D01*
X1611930D01*
X1611050Y284380D01*
X1601700D01*
X1599768Y286312D01*
X1598522D01*
X1598521Y286311D01*
X1584999D01*
X1583270Y288040D01*
X1577111D01*
X1572691Y292460D01*
X1568870D01*
X1565921Y295409D01*
X1559291D01*
X1557044Y297656D01*
X1553810D01*
X1552400Y296246D01*
Y295571D01*
X1551453Y294624D01*
X1547488D01*
X1542251Y299861D01*
X1502214D01*
X1500393Y301682D01*
X1498159D01*
X1498121Y301644D01*
X1496898D01*
X1496033Y302509D01*
Y303946D01*
X1494109Y305870D01*
X1490870D01*
X1490098Y305098D01*
X1486397D01*
G01X1631300Y280400D02*
X1629200D01*
X1622916Y286684D01*
X1602656D01*
X1600720Y288620D01*
X1586740D01*
X1586739Y288619D01*
X1586117D01*
X1581244Y293492D01*
X1580975D01*
X1579612Y294855D01*
Y295124D01*
X1577023Y297713D01*
X1560247D01*
X1558000Y299960D01*
X1545412D01*
X1543207Y302165D01*
X1503236D01*
X1500206Y305195D01*
Y306436D01*
X1499699Y306943D01*
X1499698D01*
X1498947Y307694D01*
Y307695D01*
X1497955Y308687D01*
X1492208D01*
X1491121Y309774D01*
X1475325D01*
X1473798Y308247D01*
G01X1537500Y292800D02*
X1537100Y292400D01*
X1531536D01*
X1527787Y288651D01*
X1520585D01*
X1519036Y290200D01*
X1503171D01*
X1502371Y291000D01*
X1489100D01*
X1488500Y291600D01*
X1479197D01*
X1476948Y289351D01*
G01X1664324Y248002D02*
X1663894Y248432D01*
X1656967D01*
X1641165Y264234D01*
Y265084D01*
X1637186Y269063D01*
X1636485D01*
X1631401Y274147D01*
X1631053D01*
X1631052Y274148D01*
X1628871D01*
X1626170Y276849D01*
X1621952D01*
X1620056Y278743D01*
X1611494D01*
X1608865Y281372D01*
X1600100D01*
X1598557Y282915D01*
X1583547D01*
X1582040Y281408D01*
X1567548D01*
X1560984Y287972D01*
X1558671D01*
X1557692Y286993D01*
X1552363D01*
X1549489Y284119D01*
X1500443D01*
X1499830Y284732D01*
X1481568D01*
X1480098Y286202D01*
G01X1478612Y361670D02*
X1479156Y361126D01*
X1484637D01*
X1485879Y359884D01*
Y350226D01*
X1491453Y344652D01*
X1498828D01*
X1503490Y339990D01*
Y337490D01*
X1506520Y334460D01*
X1511597D01*
X1513077Y332980D01*
X1528095D01*
X1530939Y330136D01*
X1534584D01*
X1537653Y327067D01*
X1543209D01*
X1546531Y323745D01*
X1551623D01*
X1553942Y321426D01*
X1571165D01*
X1572393Y320198D01*
X1573727D01*
X1575607Y318318D01*
X1581561D01*
X1581834Y318591D01*
G01X1489546Y317696D02*
X1495764D01*
X1501379Y312081D01*
X1506765D01*
X1512729Y306117D01*
X1520074D01*
X1523304Y309347D01*
X1529790D01*
X1532505Y312062D01*
X1534813D01*
X1537995Y308880D01*
X1538613D01*
X1542320Y305173D01*
X1544455D01*
X1544957Y304671D01*
X1554914D01*
X1556661Y302924D01*
X1562126D01*
X1565099Y305897D01*
X1565738D01*
X1570119Y301516D01*
X1579013D01*
X1590127Y290402D01*
X1601902D01*
X1604088Y288216D01*
X1626383D01*
X1634969Y279630D01*
Y279030D01*
X1636684Y277315D01*
G01X1488479Y360367D02*
X1486631Y358519D01*
Y350538D01*
X1491551Y345618D01*
X1500360D01*
X1502280Y343698D01*
X1505252D01*
X1507150Y341800D01*
Y340949D01*
X1509819Y338280D01*
X1511372D01*
X1511946Y338854D01*
X1512442D01*
X1512942Y338354D01*
Y337857D01*
X1511739Y336654D01*
Y336156D01*
X1512238Y335657D01*
X1512734D01*
X1513938Y336862D01*
X1514434D01*
X1514934Y336362D01*
Y335865D01*
X1513731Y334662D01*
Y334164D01*
X1514163Y333732D01*
X1528654D01*
X1530121Y332265D01*
X1539075D01*
X1544055Y327285D01*
X1549147D01*
X1554254Y322178D01*
X1574131D01*
X1575645Y320664D01*
G01X1486396Y317696D02*
X1487866Y319166D01*
X1495454D01*
X1500003Y314617D01*
X1509108D01*
X1510187Y313538D01*
Y311211D01*
X1514529Y306869D01*
X1519762D01*
X1523064Y310171D01*
X1529550D01*
X1532193Y312814D01*
X1535125D01*
X1538307Y309632D01*
X1538925D01*
X1542632Y305925D01*
X1544767D01*
X1545269Y305423D01*
X1555226D01*
X1556798Y303851D01*
X1561989D01*
X1564787Y306649D01*
X1566050D01*
X1570431Y302268D01*
X1579325D01*
X1583675Y297918D01*
X1591544D01*
X1597380Y303754D01*
Y309228D01*
X1605320Y317168D01*
X1620132D01*
X1628886Y308414D01*
Y292147D01*
X1635391Y285642D01*
X1635821D01*
X1635835Y285628D01*
X1637765D01*
X1637780Y285643D01*
X1638908D01*
X1639839Y284712D01*
Y274528D01*
X1644974Y269393D01*
Y264093D01*
X1656080Y252987D01*
X1663488D01*
X1666134Y250341D01*
X1667380D01*
X1667381Y250342D01*
X1674933D01*
X1677544Y252953D01*
X1774429D01*
X1780388Y246994D01*
X1801744D01*
X1803298Y245440D01*
X1825956D01*
X1830907Y240489D01*
Y217100D01*
X1833435Y214572D01*
X1835365D01*
X1840500Y219707D01*
X1846721D01*
X1850136Y223122D01*
X1866558D01*
X1869380Y220300D01*
Y212477D01*
X1869387Y212470D01*
Y212142D01*
X1870599Y210930D01*
X1871222D01*
X1871223Y210931D01*
X1873369D01*
X1876700Y207600D01*
G01X1530500Y287700D02*
X1527945Y285145D01*
X1518674D01*
X1518659Y285130D01*
X1517353D01*
X1517338Y285145D01*
X1507155D01*
X1505900Y286400D01*
X1492453D01*
X1490253Y288600D01*
X1488100D01*
X1487349Y289351D01*
X1483247D01*
G01X1495699Y314546D02*
X1496603D01*
X1502786Y308363D01*
Y306567D01*
X1504738Y304615D01*
X1520698D01*
X1521481Y305398D01*
X1529301D01*
X1531279Y307376D01*
X1537989D01*
X1541696Y303669D01*
X1543831D01*
X1546036Y301464D01*
X1558624D01*
X1560871Y299217D01*
X1579083D01*
X1581940Y296360D01*
Y295820D01*
G01X1548273Y313227D02*
X1548263Y313217D01*
X1547765D01*
X1544600Y316382D01*
Y318293D01*
X1540165Y322728D01*
X1530771D01*
X1528355Y325144D01*
X1522146D01*
X1521534Y325756D01*
X1498644D01*
X1494100Y330300D01*
X1490070D01*
X1487629Y327859D01*
X1470597D01*
X1468399Y325661D01*
Y324930D01*
G01X1886093Y202184D02*
X1883915Y204362D01*
X1882242D01*
X1874921Y211683D01*
X1870911D01*
X1870139Y212455D01*
Y212782D01*
X1870132Y212789D01*
Y220612D01*
X1870052Y220692D01*
Y221196D01*
X1867374Y223874D01*
X1849526D01*
X1846111Y220459D01*
X1840188D01*
X1835053Y215324D01*
X1833747D01*
X1831659Y217412D01*
Y240801D01*
X1826224Y246236D01*
X1803566D01*
X1802056Y247746D01*
X1780700D01*
X1774741Y253705D01*
X1677136D01*
X1674525Y251094D01*
X1667069D01*
X1667068Y251093D01*
X1666446D01*
X1663800Y253739D01*
X1656392D01*
X1645726Y264405D01*
Y270485D01*
X1640591Y275620D01*
Y285024D01*
X1639220Y286395D01*
X1637468D01*
X1637453Y286380D01*
X1636147D01*
X1636132Y286395D01*
X1635702D01*
X1629638Y292459D01*
Y308726D01*
X1620444Y317920D01*
X1605008D01*
X1597612Y310524D01*
X1575683D01*
X1569418Y316789D01*
X1562280D01*
X1558091Y312600D01*
X1550271D01*
X1549121Y311450D01*
X1547419D01*
X1546496Y312373D01*
Y313204D01*
X1543600Y316100D01*
Y318229D01*
X1539881Y321948D01*
X1533452D01*
X1533424Y321976D01*
X1530459D01*
X1528043Y324392D01*
X1521834D01*
X1521222Y325004D01*
X1497890D01*
X1494644Y328250D01*
X1492540D01*
G01X1525051Y329553D02*
X1526504Y328100D01*
X1533529D01*
X1536653Y324976D01*
X1538981D01*
X1547300Y316657D01*
Y316000D01*
X1548300Y315000D01*
X1554228D01*
X1557521Y318293D01*
X1570042D01*
X1574431Y313904D01*
X1583544D01*
X1584899Y312549D01*
X1598573D01*
X1604696Y318672D01*
X1620756D01*
X1621351Y318077D01*
X1637306D01*
X1639040Y316343D01*
G01X1536027Y305048D02*
X1535203Y305872D01*
X1531903D01*
X1529925Y303894D01*
X1522105D01*
X1521153Y302942D01*
X1503523D01*
X1500958Y305507D01*
Y306129D01*
X1500959Y306130D01*
Y306747D01*
X1500011Y307695D01*
X1500010D01*
X1497825Y309880D01*
X1494196D01*
X1492700Y311376D01*
G01X1563575Y394414D02*
X1562784D01*
X1559800Y391430D01*
Y390888D01*
X1558262Y389350D01*
X1551350D01*
X1549545Y387545D01*
Y387003D01*
X1548626Y386084D01*
X1539524D01*
X1538605Y387003D01*
Y387545D01*
X1536800Y389350D01*
X1525988D01*
X1524195Y391143D01*
Y391685D01*
X1523276Y392604D01*
X1519504D01*
X1518345Y393763D01*
Y395065D01*
X1516395Y397015D01*
Y398445D01*
X1515476Y399364D01*
X1510274D01*
X1509419Y398509D01*
X1507989D01*
X1507000Y399498D01*
Y402358D01*
X1505455Y403903D01*
Y405205D01*
X1503505Y407155D01*
Y409783D01*
X1504193Y410471D01*
Y411093D01*
X1498058Y417228D01*
Y419837D01*
X1498770Y420549D01*
Y421851D01*
X1497084Y423537D01*
Y425630D01*
X1494945Y427769D01*
Y430786D01*
X1493173Y432558D01*
Y433958D01*
X1495201Y435986D01*
Y437409D01*
X1493149Y439461D01*
Y441417D01*
X1491146Y443420D01*
Y444966D01*
X1485125Y450987D01*
Y456625D01*
X1483375Y458375D01*
G01X1524575Y394414D02*
X1526307Y392682D01*
X1538798D01*
X1539795Y391685D01*
Y391143D01*
X1541474Y389464D01*
X1546676D01*
X1547595Y390383D01*
Y390925D01*
X1549512Y392842D01*
X1556424D01*
X1557345Y393763D01*
Y394305D01*
X1559024Y395984D01*
X1573808D01*
X1579507Y401683D01*
X1582784D01*
X1587501Y406400D01*
X1592300D01*
X1594600Y408700D01*
X1606290D01*
X1611316Y403674D01*
X1618674D01*
X1628942Y413942D01*
X1630386D01*
G01X1660890Y397300D02*
Y395070D01*
X1637560Y371740D01*
Y358633D01*
X1631499Y352572D01*
X1625673D01*
X1621724Y356521D01*
X1618432D01*
X1614068Y352160D01*
X1597943D01*
X1592125Y346342D01*
X1591954D01*
X1591953Y346341D01*
X1585052D01*
X1583555Y347838D01*
X1573166D01*
X1571501Y346173D01*
X1556973D01*
X1554800Y344000D01*
X1545192D01*
X1545191Y343999D01*
X1542073D01*
X1542072Y344000D01*
X1533673D01*
X1531500Y346173D01*
X1520827D01*
X1517367Y349633D01*
Y349964D01*
G01X1630408Y357603D02*
X1632110Y355901D01*
Y354247D01*
X1631187Y353324D01*
X1625985D01*
X1621928Y357381D01*
X1617913D01*
X1613476Y352944D01*
X1597663D01*
X1591813Y347094D01*
X1591446D01*
X1591445Y347093D01*
X1585364D01*
X1583867Y348590D01*
X1572685D01*
X1571020Y346925D01*
X1556661D01*
X1554488Y344752D01*
X1544880D01*
X1544879Y344751D01*
X1542385D01*
X1542384Y344752D01*
X1536214D01*
X1526400Y354566D01*
Y375418D01*
X1524955Y376863D01*
Y377405D01*
X1523036Y379324D01*
X1516124D01*
X1515205Y380243D01*
Y381673D01*
X1513255Y383623D01*
Y385053D01*
X1511305Y387003D01*
Y387545D01*
X1509386Y389464D01*
X1506374D01*
X1505455Y390383D01*
Y391245D01*
X1503856Y392844D01*
X1500524D01*
X1499605Y393763D01*
Y395065D01*
X1497655Y397015D01*
Y398445D01*
X1498854Y399644D01*
Y401816D01*
X1494945Y405725D01*
Y408585D01*
X1492995Y410535D01*
Y411965D01*
X1492076Y412884D01*
X1489064D01*
X1485388Y416560D01*
Y420991D01*
X1483570Y422809D01*
Y427246D01*
X1480819Y429997D01*
Y439114D01*
X1479438Y440495D01*
Y443362D01*
X1478283Y444517D01*
Y476616D01*
X1481466Y479799D01*
X1485014D01*
X1485665Y479148D01*
X1537181D01*
X1538267Y478062D01*
Y476145D01*
X1540175Y474237D01*
Y470586D01*
G01X1565525Y377514D02*
X1564734D01*
X1562005Y380243D01*
Y380785D01*
X1560326Y382464D01*
X1559024D01*
X1557873Y381313D01*
Y380771D01*
X1556426Y379324D01*
X1531724D01*
X1530805Y380243D01*
Y380785D01*
X1529126Y382464D01*
X1518314D01*
X1517155Y383623D01*
Y385053D01*
X1515205Y387003D01*
Y388433D01*
X1513255Y390383D01*
Y390925D01*
X1511336Y392844D01*
X1508324D01*
X1507405Y393763D01*
Y396623D01*
X1507022Y397006D01*
X1504558D01*
X1503776Y396224D01*
X1502474D01*
X1501555Y397143D01*
Y398573D01*
X1499605Y400523D01*
Y401825D01*
X1500795Y403015D01*
Y405205D01*
X1499000Y407000D01*
Y408115D01*
X1496895Y410220D01*
Y411965D01*
X1494945Y413915D01*
Y415345D01*
X1494026Y416264D01*
X1491014D01*
X1489855Y417423D01*
Y418853D01*
X1487905Y420803D01*
Y422105D01*
X1489070Y423270D01*
Y425251D01*
X1487163Y427158D01*
Y437097D01*
X1489407Y439341D01*
Y440735D01*
X1487518Y442624D01*
Y444756D01*
X1483832Y448442D01*
X1481929D01*
X1479034Y451337D01*
Y473094D01*
X1481564Y475624D01*
X1535345D01*
X1536384Y474585D01*
Y472698D01*
X1538100Y470982D01*
Y470440D01*
X1539640Y468900D01*
X1596780D01*
X1606987Y458693D01*
X1622005D01*
X1628909Y465597D01*
Y468913D01*
X1632855Y472859D01*
X1633359D01*
G01X1491425Y446926D02*
X1491073Y447278D01*
Y451121D01*
X1492068Y452116D01*
X1499876D01*
X1499944Y452184D01*
X1508122D01*
X1508720Y452782D01*
X1514434D01*
X1516181Y454529D01*
X1525315D01*
X1526826Y453018D01*
X1527542D01*
X1527584Y452976D01*
X1528798D01*
X1528840Y453018D01*
X1544453D01*
X1548735Y448736D01*
X1552836D01*
X1554800Y450700D01*
X1556800D01*
X1558974Y448526D01*
X1582847D01*
X1584335Y447038D01*
Y442765D01*
X1593400Y433700D01*
Y432200D01*
G01X1472250Y485100D02*
X1477622D01*
X1480240Y487718D01*
X1484459D01*
X1486261Y485916D01*
X1568964D01*
X1570179Y484701D01*
X1587609D01*
X1608755Y463555D01*
Y462065D01*
X1610719Y460101D01*
X1620901D01*
X1622700Y461900D01*
G01X1485100Y469900D02*
X1486322D01*
X1487331Y468891D01*
X1531427D01*
X1532582Y467736D01*
Y466209D01*
X1534296Y464495D01*
Y463059D01*
X1535141Y462214D01*
X1539051D01*
X1540295Y460970D01*
Y459862D01*
X1541357Y458800D01*
X1544562D01*
X1545645Y457717D01*
Y453655D01*
X1547200Y452100D01*
X1558729D01*
X1558949Y452320D01*
X1560680D01*
X1561039Y451961D01*
G01X1583358Y449354D02*
X1585997Y446715D01*
Y444647D01*
X1587926Y442718D01*
X1589200D01*
X1591446Y440472D01*
G01X1592934Y592396D02*
X1581504D01*
X1576574Y587466D01*
X1563990D01*
X1559064Y582540D01*
X1546520D01*
X1546519Y582539D01*
X1544330D01*
X1532556Y570765D01*
X1522096D01*
X1514779Y578082D01*
X1474762D01*
X1468649Y571969D01*
Y570012D01*
G01X1590431Y-6702D02*
X1588855Y-8278D01*
X1578371D01*
X1576977Y-6884D01*
X1557084D01*
X1546800Y3400D01*
G01X1919514Y131701D02*
X1917773Y129960D01*
Y120676D01*
X1915585Y118488D01*
X1913136D01*
X1902730Y108082D01*
Y105457D01*
X1900007Y102734D01*
Y91178D01*
X1880127Y71298D01*
X1876893D01*
X1856405Y50810D01*
X1851850D01*
X1846751Y45711D01*
X1805535D01*
X1800772Y40948D01*
Y36121D01*
X1801350Y35543D01*
Y34237D01*
X1799213Y32100D01*
X1793106D01*
X1788759Y27753D01*
Y22040D01*
X1771309Y4590D01*
X1699167D01*
X1692577Y-2000D01*
X1662377D01*
X1656268Y-8109D01*
X1642033D01*
X1635948Y-2024D01*
X1622300D01*
X1619084Y-5240D01*
X1596586D01*
X1590370Y976D01*
X1587277D01*
X1584983Y-1318D01*
X1581909D01*
X1581051Y-2176D01*
X1575224D01*
X1574324Y-3076D01*
X1564476D01*
X1558000Y3400D01*
G01X1919702Y125920D02*
X1918725Y124943D01*
Y120281D01*
X1915980Y117536D01*
X1913531D01*
X1903682Y107687D01*
Y104937D01*
X1900959Y102214D01*
Y90783D01*
X1880522Y70346D01*
X1877288D01*
X1856752Y49810D01*
X1852349D01*
X1847298Y44759D01*
X1805930D01*
X1801724Y40553D01*
Y36776D01*
X1802302Y36198D01*
Y33842D01*
X1799608Y31148D01*
X1793501D01*
X1789772Y27419D01*
Y21706D01*
X1771704Y3638D01*
X1699562D01*
X1692924Y-3000D01*
X1662724D01*
X1656663Y-9061D01*
X1637298D01*
X1632171Y-3934D01*
X1625307D01*
X1625306Y-3933D01*
X1622938D01*
X1620679Y-6192D01*
X1596191D01*
X1592268Y-2269D01*
X1589900D01*
X1589899Y-2270D01*
X1582304D01*
X1581446Y-3128D01*
X1575772D01*
X1574872Y-4028D01*
X1562228D01*
X1554800Y3400D01*
G01X1779750Y36530D02*
Y27455D01*
X1758789Y6494D01*
X1698377D01*
X1691883Y0D01*
X1661683D01*
X1655478Y-6205D01*
X1642823D01*
X1636738Y-120D01*
X1605025D01*
X1602969Y-2176D01*
X1597949D01*
X1592893Y2880D01*
X1586487D01*
X1585655Y2048D01*
X1571954D01*
X1571730Y1824D01*
X1564776D01*
X1563200Y3400D01*
G01X1848322Y12723D02*
Y7892D01*
X1840306Y-124D01*
X1833576D01*
X1831800Y-1900D01*
Y-6300D01*
X1826547Y-11553D01*
Y-17653D01*
X1822600Y-21600D01*
X1564700D01*
X1561100Y-18000D01*
Y-14300D01*
X1557600Y-10800D01*
X1552565D01*
X1542565Y-800D01*
X1535100D01*
X1530800Y3500D01*
G01X1791500Y26918D02*
Y22087D01*
X1772099Y2686D01*
X1699957D01*
X1693271Y-4000D01*
X1663071D01*
X1657058Y-10013D01*
X1636903D01*
X1631776Y-4886D01*
X1624912D01*
X1624911Y-4885D01*
X1623333D01*
X1621074Y-7144D01*
X1595796D01*
X1591873Y-3221D01*
X1590295D01*
X1590294Y-3222D01*
X1582699D01*
X1581841Y-4080D01*
X1576167D01*
X1575267Y-4980D01*
X1560680D01*
X1552300Y3400D01*
G01X1543500D02*
X1543807D01*
X1555043Y-7836D01*
X1576582D01*
X1578946Y-10200D01*
X1622059D01*
X1624516Y-7743D01*
X1625304D01*
X1625305Y-7742D01*
X1626883D01*
X1626885Y-7744D01*
X1630593D01*
X1636085Y-13236D01*
X1641130D01*
X1641131Y-13237D01*
X1646659D01*
X1646660Y-13236D01*
X1657876D01*
X1663821Y-7291D01*
X1664609D01*
X1664610Y-7290D01*
X1666978D01*
X1666980Y-7292D01*
X1678320D01*
X1678321Y-7291D01*
X1681979D01*
X1682004Y-7316D01*
X1693996D01*
X1701142Y-170D01*
X1701930D01*
X1701931Y-171D01*
X1789918D01*
X1797098Y7009D01*
X1805079D01*
X1806048Y7978D01*
Y11169D01*
X1806169Y11290D01*
Y19911D01*
X1801800Y24280D01*
Y26932D01*
X1810426Y35558D01*
Y38055D01*
X1815748Y43377D01*
X1830130D01*
X1830560Y43807D01*
X1847747D01*
X1852798Y48858D01*
X1857147D01*
X1877683Y69394D01*
X1881089D01*
X1887038Y75343D01*
X1890729D01*
X1901911Y86525D01*
Y101819D01*
X1905261Y105169D01*
Y106971D01*
X1905915Y107625D01*
X1911495D01*
X1919677Y115807D01*
Y123154D01*
X1921278Y124755D01*
Y133282D01*
X1920164Y134396D01*
X1919195D01*
G01X1808100Y21800D02*
X1807121Y20821D01*
Y10895D01*
X1807026Y10800D01*
Y7526D01*
X1805500Y6000D01*
X1797456D01*
X1790333Y-1123D01*
X1701536D01*
X1694391Y-8268D01*
X1681609D01*
X1681584Y-8243D01*
X1678716D01*
X1678715Y-8244D01*
X1666585D01*
X1666583Y-8242D01*
X1665005D01*
X1665004Y-8243D01*
X1664216D01*
X1658271Y-14188D01*
X1647055D01*
X1647054Y-14189D01*
X1640736D01*
X1640735Y-14188D01*
X1635690D01*
X1630198Y-8696D01*
X1626490D01*
X1626488Y-8694D01*
X1625700D01*
X1625699Y-8695D01*
X1624911D01*
X1622406Y-11200D01*
X1578599D01*
X1576187Y-8788D01*
X1554648D01*
X1544036Y1824D01*
X1541576D01*
X1540000Y3400D01*
G01X1586500Y-16100D02*
X1593200D01*
X1594600Y-14700D01*
X1612253D01*
X1614581Y-17028D01*
X1619572D01*
X1626000Y-10600D01*
X1629408D01*
X1634900Y-16092D01*
X1639945D01*
X1639946Y-16093D01*
X1647844D01*
X1647845Y-16092D01*
X1659061D01*
X1665006Y-10147D01*
X1665794D01*
X1665795Y-10148D01*
X1679505D01*
X1679506Y-10147D01*
X1680294D01*
X1680295Y-10148D01*
X1680795D01*
X1680819Y-10172D01*
X1697081D01*
X1697304Y-9949D01*
X1822280D01*
X1827576Y-4653D01*
Y-300D01*
X1830750Y2874D01*
Y8150D01*
X1832900Y10300D01*
G01X1581947Y-6702D02*
X1583523Y-5126D01*
X1591084D01*
X1595006Y-9048D01*
X1621864D01*
X1624122Y-6790D01*
X1630986D01*
X1636113Y-11917D01*
X1657848D01*
X1663782Y-5983D01*
X1693982D01*
X1700747Y782D01*
X1778048D01*
X1785366Y8100D01*
G01X1560500Y3400D02*
X1563028Y872D01*
X1572125D01*
X1572349Y1096D01*
X1586050D01*
X1586882Y1928D01*
X1592498D01*
X1597554Y-3128D01*
X1603669D01*
X1605725Y-1072D01*
X1636343D01*
X1642428Y-7157D01*
X1655873D01*
X1662030Y-1000D01*
X1692230D01*
X1698772Y5542D01*
X1770032D01*
X1786865Y22375D01*
G01X1534000Y3500D02*
X1536628Y872D01*
X1543641D01*
X1554253Y-9740D01*
X1575792D01*
X1578352Y-12300D01*
X1622953D01*
X1625605Y-9648D01*
X1629803D01*
X1635295Y-15140D01*
X1640340D01*
X1640341Y-15141D01*
X1647449D01*
X1647450Y-15140D01*
X1658666D01*
X1664611Y-9195D01*
X1665399D01*
X1665400Y-9194D01*
X1666188D01*
X1666190Y-9196D01*
X1679110D01*
X1679111Y-9195D01*
X1680689D01*
X1680690Y-9196D01*
X1681190D01*
X1681214Y-9220D01*
X1696686D01*
X1696910Y-8996D01*
X1820990D01*
X1824100Y-5886D01*
Y-400D01*
X1822500Y1200D01*
Y7700D01*
X1823600Y8800D01*
G01X1549800Y3400D02*
X1559132Y-5932D01*
X1576068D01*
X1576968Y-5032D01*
X1582236D01*
X1583094Y-4174D01*
X1590689D01*
X1590690Y-4173D01*
X1591478D01*
X1595401Y-8096D01*
X1621469D01*
X1623728Y-5837D01*
X1624516D01*
X1624517Y-5838D01*
X1631381D01*
X1636508Y-10965D01*
X1657453D01*
X1663418Y-5000D01*
X1693618D01*
X1700352Y1734D01*
X1774388D01*
X1793672Y21018D01*
X1797700D01*
G01X1597867Y93900D02*
Y90846D01*
X1595521Y88500D01*
X1586622D01*
X1585197Y87075D01*
Y83654D01*
X1586101Y82750D01*
X1595250D01*
X1596892Y81108D01*
X1601992D01*
X1605300Y77800D01*
Y77008D01*
X1603645Y75353D01*
Y74855D01*
X1604811Y73689D01*
X1605309D01*
X1607361Y75741D01*
X1607859D01*
X1610523Y73077D01*
Y72223D01*
X1608599Y70299D01*
Y70000D01*
X1610499Y68100D01*
X1618250D01*
X1618750Y67600D01*
X1625406D01*
X1631954Y61052D01*
Y60554D01*
X1630788Y59388D01*
X1630290D01*
X1623838Y65840D01*
X1623340D01*
X1622174Y64674D01*
Y64176D01*
X1629100Y57250D01*
X1654550D01*
X1660000Y62700D01*
X1725871D01*
X1734571Y54000D01*
X1765471D01*
X1777700Y66229D01*
Y67537D01*
X1785663Y75500D01*
X1795123D01*
X1795475Y75852D01*
Y76748D01*
X1795827Y77100D01*
X1797476D01*
X1797828Y76748D01*
Y75852D01*
X1798180Y75500D01*
X1799829D01*
X1800181Y75852D01*
Y76748D01*
X1800533Y77100D01*
X1802182D01*
X1802534Y76748D01*
Y75852D01*
X1802886Y75500D01*
X1804535D01*
X1804887Y75852D01*
Y76748D01*
X1805239Y77100D01*
X1806888D01*
X1807240Y76748D01*
Y75852D01*
X1807592Y75500D01*
X1809241D01*
X1809593Y75852D01*
Y76748D01*
X1809945Y77100D01*
X1811594D01*
X1811946Y76748D01*
Y75852D01*
X1812298Y75500D01*
X1813674D01*
X1820213Y82039D01*
X1823970D01*
X1829481Y76528D01*
Y69583D01*
X1835027Y64037D01*
X1857202D01*
X1870468Y77303D01*
Y87669D01*
X1871606Y88807D01*
Y89305D01*
X1869705Y91206D01*
Y91704D01*
X1870871Y92870D01*
X1871369D01*
X1873270Y90969D01*
X1873768D01*
X1874934Y92135D01*
Y92633D01*
X1873033Y94534D01*
Y95032D01*
X1874199Y96198D01*
X1874697D01*
X1876598Y94297D01*
X1877096D01*
X1878569Y95770D01*
X1888430D01*
X1892550Y99890D01*
Y125522D01*
X1900144Y133116D01*
Y137395D01*
X1901249Y138500D01*
X1905000D01*
X1907400Y140900D01*
Y143744D01*
X1908356Y144700D01*
X1915000D01*
X1917908Y147608D01*
Y150208D01*
X1919124Y151424D01*
X1921917D01*
X1924468Y153975D01*
X1930224D01*
X1931700Y155451D01*
Y159900D01*
X1937600Y165800D01*
Y167330D01*
X1940240Y169970D01*
G01X1812743Y104395D02*
X1810238Y106900D01*
X1786964D01*
X1768500Y88436D01*
Y82236D01*
X1765112Y78848D01*
X1757369D01*
X1753861Y75340D01*
X1735721D01*
X1731063Y79998D01*
X1706577D01*
X1698079Y88496D01*
X1684168D01*
X1679820Y84148D01*
X1662747D01*
X1660619Y82020D01*
X1649439D01*
X1646243Y78824D01*
X1629827D01*
X1626084Y82567D01*
X1624693D01*
X1620943Y86317D01*
X1612475D01*
X1608529Y90263D01*
X1602456D01*
X1599443Y93276D01*
Y94553D01*
X1598521Y95475D01*
X1596054D01*
X1592579Y92000D01*
X1580623D01*
X1579615Y90992D01*
X1574780D01*
G01X1927500Y170400D02*
X1918029D01*
X1900872Y153243D01*
Y148387D01*
X1898064Y145579D01*
Y139859D01*
X1896981Y138776D01*
Y134917D01*
X1888981Y126917D01*
Y111739D01*
X1886920Y109678D01*
X1869478D01*
X1864364Y104564D01*
X1842605D01*
X1829166Y91125D01*
X1823653D01*
X1814824Y82296D01*
X1804976D01*
X1801760Y85512D01*
X1795669D01*
X1791076Y80919D01*
X1782894D01*
X1773324Y71349D01*
Y68948D01*
X1766681Y62305D01*
X1752559D01*
X1749368Y65496D01*
X1683210D01*
X1680364Y68342D01*
X1655362D01*
X1652438Y71266D01*
X1651816D01*
X1651815Y71265D01*
X1627385D01*
X1625557Y73093D01*
X1619449D01*
X1611092Y81450D01*
X1611028D01*
X1611027Y81451D01*
X1607278D01*
X1602566Y86163D01*
X1589174D01*
X1587359Y84348D01*
G01X1584748Y70840D02*
X1585300Y70288D01*
Y53389D01*
X1600852Y37837D01*
Y27629D01*
X1603042Y25439D01*
X1632879D01*
X1635638Y22680D01*
Y11462D01*
X1637977Y9123D01*
X1653622D01*
X1655593Y11094D01*
Y11994D01*
X1658775Y15176D01*
X1693523D01*
X1694005Y15658D01*
X1695311D01*
X1695793Y15176D01*
X1738824D01*
X1744900Y9100D01*
G01X1575018Y71213D02*
X1575066Y71261D01*
X1579916D01*
X1583005Y74350D01*
X1590621D01*
X1591047Y73924D01*
X1593475D01*
X1594300Y73099D01*
Y63971D01*
X1613071Y45200D01*
X1652750D01*
X1654826Y43124D01*
X1676324D01*
X1677204Y44004D01*
X1767733D01*
X1782500Y58771D01*
Y65512D01*
X1783605Y66617D01*
X1817230D01*
X1820708Y63139D01*
G01X1834914Y52928D02*
X1856684D01*
X1876006Y72250D01*
X1878850D01*
X1883200Y76600D01*
G01X1654686Y109191D02*
X1653777D01*
X1652302Y110666D01*
X1647576D01*
X1646810Y109900D01*
Y107440D01*
X1643937Y104567D01*
X1613130D01*
X1610733Y106964D01*
X1609869D01*
X1607569Y109264D01*
X1606305D01*
X1601482Y114087D01*
X1596603D01*
X1595239Y115451D01*
X1583744D01*
X1578965Y110672D01*
X1577035D01*
X1575377Y112330D01*
X1543435D01*
X1541765Y114000D01*
G01X1695300Y94712D02*
X1695211Y94801D01*
X1694751D01*
X1692881Y96671D01*
X1691369D01*
X1688872Y94174D01*
X1679343D01*
X1677802Y95715D01*
X1661922D01*
X1659743Y93536D01*
X1635288D01*
X1632610Y96214D01*
X1621536D01*
X1619132Y98618D01*
X1612208D01*
X1609091Y101735D01*
X1606472D01*
X1601321Y106886D01*
X1593119D01*
X1590489Y109516D01*
X1585473D01*
X1583529Y107572D01*
X1581535D01*
X1580691Y108416D01*
X1579901D01*
X1579900Y108415D01*
X1578030D01*
X1578029Y108416D01*
X1574717D01*
X1573321Y107020D01*
X1562492D01*
X1560869Y108643D01*
X1543322D01*
X1541421Y106742D01*
G01X1808226Y136171D02*
X1807315Y135260D01*
X1782657D01*
X1768844Y121447D01*
X1757950D01*
X1751365Y114862D01*
Y97240D01*
X1746655Y92530D01*
X1740841D01*
X1737746Y95625D01*
X1724065D01*
X1723112Y94672D01*
X1716684D01*
X1713043Y98313D01*
Y98314D01*
X1705168Y106189D01*
X1705167D01*
X1704999Y106357D01*
X1699769D01*
X1692110Y114016D01*
X1671788D01*
X1670625Y112853D01*
Y112552D01*
X1668939Y110866D01*
X1663523D01*
X1662660Y111729D01*
Y113075D01*
X1661719Y114016D01*
X1660374D01*
X1659310Y115080D01*
Y116102D01*
X1658446Y116966D01*
X1657224D01*
X1656660Y116402D01*
X1653293D01*
X1652319Y117376D01*
X1650104D01*
X1647265Y120215D01*
X1602835D01*
X1599927Y123123D01*
X1596988D01*
X1596383Y122518D01*
X1595343D01*
X1593050Y120225D01*
X1582807D01*
X1580693Y118111D01*
X1556389D01*
X1553500Y121000D01*
G01X1855670Y206430D02*
X1856594Y205506D01*
Y203594D01*
X1855972Y202972D01*
Y199028D01*
X1857927Y197072D01*
Y194167D01*
X1857166Y193406D01*
X1857163Y193402D01*
X1856686Y192925D01*
X1856682Y192922D01*
X1852200Y188440D01*
Y180000D01*
X1846033Y173833D01*
X1843931D01*
X1840356Y170258D01*
Y169257D01*
X1840001Y168902D01*
X1827795D01*
X1825995Y167102D01*
X1815052D01*
X1813000Y165050D01*
Y159250D01*
X1812261Y158511D01*
X1807847D01*
X1805241Y155905D01*
X1794684D01*
X1791509Y159080D01*
X1776300D01*
X1773502Y161878D01*
X1712842D01*
X1711154Y160190D01*
X1706690D01*
X1704206Y157706D01*
X1694455D01*
X1692890Y156141D01*
X1684639D01*
X1678497Y162283D01*
Y162284D01*
X1676939Y163842D01*
X1669367D01*
X1661415Y171794D01*
X1649580D01*
X1648920Y171134D01*
X1629043D01*
X1628944Y171233D01*
X1618832D01*
X1616818Y169219D01*
X1608313D01*
X1600344Y161250D01*
X1588391D01*
X1579741Y152600D01*
X1577950D01*
G01X1858470Y206335D02*
X1857546Y205411D01*
Y203147D01*
X1856924Y202525D01*
Y199375D01*
X1858879Y197420D01*
Y193772D01*
X1853100Y187993D01*
Y179553D01*
X1846628Y173081D01*
X1844243D01*
X1841108Y169946D01*
Y168662D01*
X1840396Y167950D01*
X1828006D01*
X1826206Y166150D01*
X1815447D01*
X1813952Y164655D01*
Y158855D01*
X1812656Y157559D01*
X1808574D01*
X1805968Y154953D01*
X1794572D01*
X1791197Y158328D01*
X1775988D01*
X1773190Y161126D01*
X1713154D01*
X1711432Y159404D01*
X1706994D01*
X1704544Y156954D01*
X1694767D01*
X1693202Y155389D01*
X1684228D01*
X1676526Y163091D01*
X1669055D01*
X1661103Y171043D01*
X1649942D01*
X1649282Y170383D01*
X1628731D01*
X1628648Y170466D01*
X1619266D01*
X1617067Y168267D01*
X1608708D01*
X1600739Y160298D01*
X1588786D01*
X1578007Y149519D01*
X1577770D01*
G01X1541390Y136498D02*
X1545461D01*
X1551122Y142159D01*
Y142179D01*
X1552222Y143279D01*
X1552242D01*
X1554478Y145515D01*
X1562321D01*
X1566572Y141264D01*
X1572735D01*
X1577121Y136878D01*
X1580085D01*
X1583985Y140778D01*
X1587829D01*
X1590081Y143030D01*
G01X1591143Y144092D02*
X1593216Y146165D01*
X1599872D01*
X1602169Y148462D01*
X1607973D01*
X1608949Y147486D01*
Y146542D01*
X1609979Y145512D01*
X1617503D01*
X1618366Y146375D01*
Y147599D01*
X1619229Y148462D01*
X1620449D01*
X1621725Y149738D01*
Y154236D01*
X1623019Y155530D01*
X1642050D01*
X1642670Y154910D01*
X1652365D01*
X1653070Y155615D01*
Y160496D01*
X1654685Y162111D01*
Y162735D01*
G01X1767250Y94500D02*
Y92887D01*
X1766898Y92535D01*
X1765635D01*
X1763546Y90446D01*
Y83961D01*
X1760558Y80973D01*
X1756963D01*
X1752857Y76867D01*
X1736837D01*
X1732202Y81502D01*
X1707225D01*
X1697919Y90808D01*
X1683295D01*
X1681433Y92670D01*
X1678109D01*
X1676566Y94213D01*
X1671951D01*
X1670996Y93258D01*
Y91567D01*
X1669757Y90328D01*
X1660943D01*
X1659565Y91706D01*
X1630600D01*
X1629324Y92982D01*
X1613918D01*
X1608995Y97905D01*
X1606085D01*
X1603226Y100764D01*
X1602105D01*
X1602104Y100765D01*
X1600966D01*
X1596832Y104899D01*
X1590537D01*
X1590536Y104900D01*
X1580947D01*
X1579736Y106111D01*
X1575959D01*
X1575958Y106112D01*
X1573567Y103721D01*
X1573153D01*
G01X1767250Y89500D02*
Y91230D01*
X1766897Y91583D01*
X1765782D01*
X1764298Y90099D01*
Y83649D01*
X1760870Y80221D01*
X1757275D01*
X1753169Y76115D01*
X1736525D01*
X1731890Y80750D01*
X1706913D01*
X1697607Y90056D01*
X1682740D01*
X1680878Y91918D01*
X1677798D01*
X1676254Y93462D01*
X1672263D01*
X1671747Y92946D01*
Y92537D01*
X1671748Y92536D01*
Y91255D01*
X1670068Y89575D01*
X1669446D01*
X1669445Y89576D01*
X1660348D01*
X1659170Y90754D01*
X1630205D01*
X1628934Y92025D01*
X1613542D01*
X1613494Y92073D01*
X1613480D01*
X1613328Y92225D01*
Y92239D01*
X1612190Y93377D01*
X1612176D01*
X1608600Y96953D01*
X1607409D01*
X1607408Y96954D01*
X1605689D01*
X1602830Y99813D01*
X1600855D01*
X1600655Y100013D01*
X1600654D01*
X1596520Y104147D01*
X1590225D01*
X1590224Y104148D01*
X1580635D01*
X1579424Y105359D01*
X1577573D01*
X1576606Y104392D01*
G01X1541831Y149030D02*
X1544872D01*
X1549868Y154026D01*
X1565028D01*
X1576407Y165405D01*
X1580605D01*
X1584180Y168980D01*
X1598860D01*
X1599566Y169686D01*
X1599567D01*
X1599580Y169699D01*
X1602300D01*
X1610401Y177800D01*
X1614000D01*
G01X1608731Y180819D02*
Y177193D01*
X1601988Y170450D01*
X1599268D01*
X1599255Y170437D01*
X1599254D01*
X1598753Y169936D01*
X1593627D01*
X1593225Y170338D01*
X1583908D01*
X1580128Y166558D01*
X1575897D01*
X1564763Y155424D01*
X1548608D01*
X1545084Y151900D01*
X1541351D01*
G01X1531726Y123800D02*
X1532238Y123288D01*
X1546334D01*
X1553816Y115806D01*
X1580514D01*
X1583431Y118723D01*
X1594714D01*
X1594794Y118803D01*
X1600907D01*
X1605736Y113974D01*
X1619596D01*
X1622588Y116966D01*
X1636424D01*
X1641050Y112340D01*
X1641770D01*
G01X1532923Y144518D02*
X1534102Y145697D01*
X1546353D01*
X1552130Y151474D01*
X1566724D01*
X1577250Y162000D01*
X1581412D01*
X1585888Y166476D01*
X1592453D01*
X1594539Y164390D01*
X1600016D01*
X1609015Y173389D01*
X1609222D01*
G01X1531985Y147000D02*
X1532384Y147399D01*
X1545648D01*
X1551458Y153209D01*
X1566052D01*
X1576545Y163702D01*
X1580707D01*
X1585204Y168199D01*
X1599142D01*
X1599878Y168935D01*
X1599879D01*
X1599892Y168948D01*
X1602612D01*
X1602617Y168953D01*
X1602654D01*
X1608801Y175100D01*
X1612300D01*
X1613650Y173750D01*
G01X1576506Y143416D02*
X1586016D01*
X1592900Y150300D01*
X1596371D01*
X1599682Y153611D01*
X1604896D01*
X1608370Y150137D01*
X1610591D01*
G01X1572634Y98546D02*
X1573012Y98924D01*
X1588653D01*
X1591129Y101400D01*
X1596579D01*
X1602055Y95924D01*
X1604228D01*
X1604702Y95450D01*
X1607140D01*
X1611224Y91366D01*
Y91352D01*
X1613629Y88947D01*
X1625706D01*
X1629605Y85048D01*
X1641669D01*
X1643945Y82772D01*
X1660271D01*
X1662399Y84900D01*
X1672599D01*
X1674749Y87050D01*
G01X1529449Y137408D02*
Y137440D01*
X1530159Y138150D01*
X1532851D01*
X1539256Y131745D01*
X1546285D01*
X1551874Y137334D01*
Y141604D01*
X1554841Y144571D01*
X1559563D01*
X1563739Y140395D01*
Y132545D01*
X1565263Y131021D01*
X1573758D01*
X1578863Y136126D01*
X1580397D01*
X1582657Y138386D01*
X1587885D01*
X1594764Y145265D01*
X1606782D01*
X1606829Y145312D01*
X1608053D01*
X1608100Y145265D01*
X1608239D01*
X1609170Y144334D01*
Y143171D01*
X1610033Y142308D01*
X1617403D01*
X1617500Y142405D01*
X1617512D01*
X1618375Y143268D01*
Y144492D01*
X1619355Y145472D01*
X1620783D01*
X1621715Y146404D01*
Y148399D01*
X1623200Y149884D01*
Y153100D01*
G01X1859604Y213206D02*
X1857242D01*
X1850000Y205964D01*
Y181771D01*
X1844564Y176335D01*
X1840357D01*
X1837355Y173333D01*
X1807489D01*
X1803406Y169250D01*
X1793450D01*
X1790200Y166000D01*
X1783576D01*
X1780500Y162924D01*
X1774584D01*
X1774126Y163382D01*
X1712082D01*
X1710520Y161820D01*
X1706027D01*
X1704305Y163542D01*
X1700532D01*
X1696201Y159211D01*
X1693832D01*
X1692280Y157659D01*
X1685575D01*
X1685257Y157977D01*
X1685256D01*
X1677610Y165623D01*
X1669712D01*
X1662039Y173296D01*
X1654515D01*
X1653097Y174714D01*
X1649446D01*
X1648697Y175463D01*
X1648354D01*
X1648353Y175464D01*
X1647731D01*
X1647730Y175463D01*
X1620762D01*
X1616218Y170919D01*
X1607609D01*
X1599874Y163184D01*
X1585572D01*
X1582285Y159897D01*
X1578951D01*
X1574000Y154946D01*
Y152100D01*
G01Y149500D02*
X1575850Y151350D01*
Y155732D01*
X1579065Y158947D01*
X1582679D01*
X1586164Y162432D01*
X1600462D01*
X1608001Y169971D01*
X1616334D01*
X1621075Y174712D01*
X1648385D01*
X1649134Y173963D01*
X1652785D01*
X1654203Y172545D01*
X1661727D01*
X1669670Y164602D01*
X1677242D01*
X1684951Y156893D01*
X1692578D01*
X1694144Y158459D01*
X1703819D01*
X1706320Y160960D01*
X1710860D01*
X1712530Y162630D01*
X1773814D01*
X1775346Y161098D01*
X1796598D01*
X1807883Y172383D01*
X1837749D01*
X1840751Y175385D01*
X1844678D01*
X1850950Y181657D01*
Y205850D01*
X1856581Y211481D01*
X1861497D01*
G01X1657835Y118640D02*
X1656348Y117153D01*
X1654061D01*
X1653087Y118127D01*
X1650879D01*
X1648040Y120966D01*
X1632031D01*
X1629732Y123265D01*
X1610179D01*
X1608916Y124528D01*
Y125550D01*
X1607854Y126612D01*
X1599708D01*
X1595697Y130623D01*
X1585552D01*
X1581144Y126215D01*
X1573211D01*
X1570632Y123636D01*
X1563758D01*
X1560046Y119924D01*
X1556806D01*
X1553353Y123377D01*
Y124209D01*
G01X1527657Y278700D02*
X1531337D01*
X1532147Y277890D01*
X1607898D01*
X1609501Y276287D01*
X1618503D01*
X1621267Y273523D01*
X1623197D01*
X1623447Y273273D01*
G01X1558700Y252000D02*
Y251880D01*
X1561320Y249260D01*
X1564151D01*
X1565740Y250849D01*
Y251660D01*
X1567400Y253320D01*
X1569909D01*
X1570529Y252700D01*
X1573596D01*
X1577997Y257101D01*
Y257793D01*
X1582204Y262000D01*
X1593872D01*
X1597656Y258216D01*
X1598962D01*
X1599177Y258001D01*
X1602941D01*
X1604572Y259632D01*
X1623669D01*
X1626401Y256900D01*
G01X1529734Y319714D02*
Y319692D01*
G01D02*
X1534644D01*
X1535736Y318600D01*
X1540036D01*
X1545744Y312892D01*
Y312061D01*
X1547107Y310698D01*
X1549433D01*
X1550583Y311848D01*
X1558609D01*
X1559809Y310648D01*
Y310505D01*
X1559997Y310317D01*
G01X1638086Y319664D02*
X1604624D01*
X1598261Y313301D01*
X1585299D01*
X1583911Y314689D01*
X1574710D01*
X1570354Y319045D01*
X1557209D01*
X1554764Y316600D01*
X1549000D01*
G01X1563000Y341000D02*
X1564024Y339976D01*
Y338928D01*
X1565724Y337228D01*
X1570736D01*
X1572442Y335522D01*
X1576785D01*
X1577048Y335785D01*
X1584476D01*
X1585965Y337274D01*
X1593491D01*
X1597701Y341484D01*
X1614576D01*
X1616712Y343620D01*
X1620469D01*
X1625567Y338522D01*
Y338514D01*
X1628202Y335879D01*
X1643735D01*
X1647636Y339780D01*
Y379288D01*
X1659342Y390994D01*
X1660613D01*
X1661243Y390364D01*
G01X1566000Y341000D02*
X1564976Y339976D01*
Y339323D01*
X1566119Y338180D01*
X1571131D01*
X1572895Y336416D01*
X1576615D01*
X1576736Y336537D01*
X1583881D01*
X1585570Y338226D01*
X1593096D01*
X1597106Y342236D01*
X1614264D01*
X1616400Y344372D01*
X1620781D01*
X1626319Y338834D01*
Y338826D01*
X1628514Y336631D01*
X1643423D01*
X1646884Y340092D01*
Y379883D01*
X1659196Y392195D01*
X1660495D01*
X1661243Y392943D01*
G01X1643150Y348692D02*
X1642995D01*
X1642785Y348902D01*
X1638339D01*
X1636773Y350468D01*
X1624800D01*
X1620851Y354417D01*
X1618874D01*
X1614974Y350547D01*
X1599803D01*
X1593493Y344237D01*
X1584474D01*
X1582987Y345724D01*
X1574029D01*
X1572374Y344069D01*
X1559116D01*
X1557550Y342503D01*
Y341100D01*
G01X1554800D02*
X1558721Y345021D01*
X1571979D01*
X1573634Y346676D01*
X1583099D01*
X1584586Y345189D01*
X1593098D01*
X1599278Y351369D01*
X1614451D01*
X1618480Y355369D01*
X1621246D01*
X1625195Y351420D01*
X1636885D01*
X1638451Y349854D01*
X1641887D01*
X1643700Y351667D01*
G01X1548273Y313227D02*
X1548590Y313544D01*
X1557971D01*
X1561968Y317541D01*
X1569730D01*
X1575171Y312100D01*
X1582800D01*
G01X1551250Y320303D02*
X1551631Y319922D01*
X1570541D01*
X1574900Y315563D01*
X1584237D01*
X1584923Y314877D01*
X1589664D01*
X1590212Y315425D01*
G01X1548100Y342200D02*
X1550753D01*
X1554819Y338134D01*
X1559633D01*
X1561691Y336076D01*
X1570258D01*
X1571964Y334370D01*
X1576697D01*
X1577360Y335033D01*
X1585186D01*
X1586275Y336122D01*
X1593969D01*
X1595793Y337946D01*
X1601258D01*
X1602942Y339630D01*
X1609172D01*
G01X1622000Y279495D02*
X1621495Y280000D01*
X1611602D01*
X1609478Y282124D01*
X1600412D01*
X1598744Y283792D01*
X1582970D01*
X1582397Y283219D01*
X1582368D01*
X1581309Y282160D01*
X1577120D01*
X1574398Y284882D01*
X1573803D01*
X1573790Y284895D01*
G01X1569211Y334142D02*
X1569919Y333434D01*
X1576825D01*
X1577672Y334281D01*
X1586033D01*
X1586598Y334846D01*
X1596375D01*
X1598124Y336595D01*
X1605549D01*
X1608942Y333202D01*
X1613138D01*
X1614475Y334539D01*
X1626790D01*
X1627231Y334098D01*
X1647113D01*
X1649379Y336364D01*
Y339089D01*
X1649380Y339090D01*
Y340208D01*
X1649379Y340209D01*
Y352969D01*
X1650285Y353875D01*
X1651361D01*
X1652186Y354700D01*
G01X1569211Y331542D02*
X1570153Y332484D01*
X1576939D01*
X1577984Y333529D01*
X1586703D01*
X1586983Y333809D01*
X1596682D01*
X1598518Y335645D01*
X1605155D01*
X1608548Y332252D01*
X1613252D01*
X1614580Y333580D01*
X1626685D01*
X1627117Y333148D01*
X1647507D01*
X1650329Y335970D01*
Y338695D01*
X1650330Y338696D01*
Y340602D01*
X1650329Y340603D01*
Y352575D01*
X1650679Y352925D01*
X1651361D01*
X1652186Y352100D01*
G01X1581090Y338795D02*
X1580351D01*
X1578589Y340557D01*
Y342029D01*
X1579629Y343069D01*
X1583650D01*
X1587085Y339634D01*
X1592512D01*
X1601219Y348341D01*
X1606019D01*
X1608749Y345611D01*
X1611893D01*
X1614623Y348341D01*
X1618804D01*
X1627727Y339418D01*
Y339410D01*
X1629098Y338039D01*
X1642839D01*
X1645476Y340676D01*
Y367556D01*
X1642276Y370756D01*
X1640034D01*
X1640000Y370790D01*
X1640001D01*
G01X1546025Y391034D02*
X1545234D01*
X1542505Y393763D01*
Y395475D01*
X1544145Y397115D01*
Y398825D01*
X1546025Y400705D01*
Y401985D01*
G01X1574464Y407906D02*
X1576860Y410302D01*
Y417274D01*
X1588986Y429400D01*
X1592829D01*
X1595900Y432471D01*
Y437587D01*
X1602600Y444287D01*
G01X1630337Y362600D02*
X1629660Y363277D01*
X1628962D01*
X1625988Y360303D01*
X1618543D01*
X1612780Y354540D01*
X1596940D01*
X1591068Y348668D01*
X1585977D01*
X1584251Y350394D01*
X1571938D01*
X1569973Y348429D01*
X1564361D01*
X1561214Y351576D01*
X1559847D01*
X1558384Y350113D01*
X1550726D01*
X1550639Y350200D01*
G01X1530425Y384274D02*
X1531995Y385844D01*
X1534976D01*
X1536655Y384165D01*
Y383623D01*
X1537574Y382704D01*
X1550576D01*
X1551495Y383623D01*
Y384165D01*
X1553174Y385844D01*
X1562276D01*
X1563195Y384925D01*
Y384383D01*
X1564878Y382700D01*
X1568550D01*
X1570590Y380660D01*
X1577244D01*
X1599605Y403021D01*
X1607713D01*
X1615360Y395374D01*
X1621727D01*
G01X1549950Y404490D02*
Y400878D01*
X1551244Y399584D01*
X1573084D01*
X1580700Y407200D01*
X1591800D01*
X1594100Y409500D01*
X1607719D01*
X1611781Y405438D01*
X1612825D01*
G01X1654861Y396637D02*
X1654398Y397100D01*
X1614698D01*
X1608025Y403773D01*
X1598788D01*
X1590215Y395200D01*
X1585300D01*
X1584170Y394070D01*
Y388649D01*
X1581605Y386084D01*
X1567335D01*
X1565525Y384274D01*
G01X1587684Y362653D02*
X1587132D01*
X1581419Y356940D01*
X1565812D01*
X1562321Y360431D01*
Y366949D01*
X1560170Y369100D01*
X1537533D01*
X1535804Y367371D01*
Y364868D01*
X1533719Y362783D01*
G01X1586500Y358400D02*
X1584064D01*
X1581852Y356188D01*
X1565500D01*
X1561300Y360388D01*
Y366730D01*
X1559830Y368200D01*
X1538088D01*
X1536604Y366716D01*
Y363339D01*
X1533783Y360518D01*
Y360283D01*
X1533790D01*
G01X1538500Y359363D02*
Y358299D01*
X1540799Y356000D01*
Y354516D01*
X1541293Y354022D01*
X1544181D01*
X1544516Y353687D01*
X1547200D01*
X1548756Y355243D01*
X1553110D01*
X1554640Y356773D01*
X1561723D01*
X1564596Y353900D01*
X1585271D01*
X1585847Y353324D01*
X1587644D01*
X1589082Y354762D01*
X1590154D01*
G01X1589100Y358400D02*
X1587475Y356775D01*
X1583503D01*
X1582164Y355436D01*
X1565188D01*
X1562324Y358300D01*
X1552700D01*
X1552500Y358500D01*
G01X1630400Y391800D02*
X1624700D01*
X1616040Y383140D01*
X1591710D01*
X1584750Y376180D01*
X1576870D01*
X1575590Y374900D01*
X1560339D01*
X1557725Y377514D01*
G01X1586500Y354900D02*
X1586284Y354684D01*
X1564876D01*
X1562035Y357525D01*
X1554328D01*
X1553727Y356924D01*
X1551847D01*
X1551171Y357600D01*
X1544299D01*
X1540038Y361861D01*
X1538397D01*
G01X1587032Y350996D02*
X1586047D01*
X1585145Y351898D01*
X1571314D01*
X1569349Y349933D01*
X1565632D01*
X1560297Y355268D01*
X1555263D01*
X1553043Y353048D01*
X1549984D01*
X1543943Y347007D01*
X1543321D01*
X1543320Y347008D01*
X1540228D01*
X1539548Y347688D01*
Y349624D01*
X1538478Y350694D01*
G01Y353294D02*
X1540300Y351472D01*
Y348000D01*
X1540540Y347760D01*
X1543632D01*
X1549672Y353800D01*
X1552731D01*
X1554951Y356020D01*
X1560609D01*
X1565944Y350685D01*
X1568629D01*
X1570997Y353053D01*
X1585054D01*
X1585535Y352572D01*
X1588623D01*
X1588847Y352796D01*
X1593916D01*
X1596690Y355570D01*
X1604710D01*
X1609090Y359950D01*
X1616840D01*
X1617945Y361055D01*
X1624959D01*
X1627979Y364075D01*
X1629216D01*
X1630240Y365099D01*
G01X1590218Y350995D02*
Y350915D01*
X1588723Y349420D01*
X1586289D01*
X1584563Y351146D01*
X1571626D01*
X1569661Y349181D01*
X1564856D01*
X1561425Y352612D01*
X1559049D01*
X1558213Y351776D01*
X1549986D01*
X1549960Y351750D01*
X1549750D01*
X1544255Y346255D01*
X1543009D01*
X1543008Y346256D01*
X1538343D01*
X1536902Y347697D01*
Y354318D01*
X1538478Y355894D01*
G01X1630400Y398700D02*
X1614162D01*
X1608337Y404525D01*
X1598357D01*
X1593859Y400027D01*
X1586571D01*
X1585150Y398606D01*
Y397400D01*
G01X1559675Y401174D02*
X1561451Y402950D01*
X1573250D01*
X1578400Y408100D01*
Y417750D01*
X1588850Y428200D01*
X1593400D01*
X1596150Y430950D01*
Y430986D01*
X1596652Y431488D01*
Y435752D01*
X1604300Y443400D01*
Y446400D01*
X1601900Y448800D01*
X1594850D01*
X1591350Y445300D01*
G01X1528475Y380894D02*
X1528107Y380526D01*
Y353923D01*
X1536526Y345504D01*
X1542696D01*
X1542697Y345503D01*
X1544567D01*
X1544568Y345504D01*
X1554176D01*
X1556349Y347677D01*
X1570708D01*
X1572432Y349401D01*
X1584136D01*
X1585691Y347846D01*
X1591501D01*
X1597351Y353696D01*
X1613126D01*
X1617563Y358133D01*
X1622380D01*
X1625613Y354900D01*
X1630534D01*
G01X1642443Y344879D02*
X1639572Y347750D01*
X1638427D01*
X1637054Y349123D01*
X1620014D01*
X1619388Y349749D01*
X1600635D01*
X1592970Y342084D01*
X1589225D01*
X1588551Y341410D01*
G01X1613452Y387098D02*
X1618598D01*
X1624900Y393400D01*
X1631800D01*
X1632630Y392570D01*
Y390830D01*
X1631700Y389900D01*
X1628900D01*
X1623800Y384800D01*
Y379560D01*
X1613723Y369483D01*
X1605273D01*
X1598940Y363150D01*
X1595690D01*
X1591040Y367800D01*
X1578540D01*
X1572890Y362150D01*
Y361090D01*
X1571450Y359650D01*
G01X1559675Y387654D02*
X1561321Y389300D01*
X1582600D01*
G01X1630800Y378500D02*
X1626200Y373900D01*
Y368850D01*
X1622870Y365520D01*
X1607141D01*
X1603211Y361590D01*
X1595070D01*
X1590400Y366260D01*
X1585121D01*
X1578461Y359600D01*
X1576074D01*
G01X1621800Y381500D02*
Y378720D01*
X1613315Y370235D01*
X1604855D01*
X1598630Y364010D01*
X1596220D01*
X1588330Y371900D01*
X1577383D01*
X1570031Y364548D01*
Y363722D01*
X1566922Y360613D01*
Y359681D01*
G01X1621800Y386300D02*
X1617200Y381700D01*
Y375328D01*
X1612872Y371000D01*
X1604470D01*
X1598460Y364990D01*
X1596590D01*
X1588680Y372900D01*
X1576804D01*
X1567121Y363217D01*
G01X1559675Y380894D02*
Y377243D01*
X1560974Y375944D01*
X1573754D01*
X1582470Y384660D01*
X1610580D01*
X1611570Y385650D01*
Y392470D01*
X1612600Y393500D01*
X1622900D01*
X1624700Y395300D01*
X1630300D01*
G01X1571375Y394414D02*
X1575829D01*
X1582235Y400820D01*
X1593588D01*
X1598045Y405277D01*
X1608649D01*
X1611126Y402800D01*
X1627799D01*
X1628099Y403100D01*
X1653354D01*
X1654809Y401645D01*
G01X1630200Y367730D02*
X1628180D01*
X1624300Y363850D01*
X1607540D01*
X1603820Y360130D01*
X1594140D01*
X1589750Y364520D01*
X1585740D01*
X1578930Y357710D01*
X1566230D01*
X1563170Y360770D01*
Y368350D01*
X1559830Y371690D01*
X1540149D01*
X1534325Y377514D01*
G01X1544075Y463826D02*
X1544740Y462673D01*
X1545092Y462579D01*
G02X1547188Y462462I932J-2133D01*
G02X1548351Y460527I-1163J-2016D01*
G01Y460398D01*
G03X1549138Y459082I1574J48D01*
G03X1550712I787J1364D01*
G02X1553038I1163J-2016D01*
G03X1554612I787J1364D01*
G02X1556938I1163J-2016D01*
G03X1558512I787J1364D01*
G02X1560679Y459166I1163J-2016D01*
G01X1630150Y427663D02*
Y431200D01*
X1624100Y437250D01*
Y452900D01*
X1619788Y457212D01*
X1606468D01*
X1596871Y466809D01*
X1579009D01*
G01X1617900Y409900D02*
Y413100D01*
X1612700Y418300D01*
X1602600D01*
X1600650Y420250D01*
Y435389D01*
X1603652Y438391D01*
G01X1604999Y451500D02*
X1591949Y464550D01*
X1575748D01*
X1572440Y461242D01*
G01X1559100Y455400D02*
X1547420D01*
X1546405Y456415D01*
Y460066D01*
X1546025Y460446D01*
G01X1550990Y586588D02*
X1552799D01*
X1553705Y585682D01*
X1555011D01*
X1555385Y586056D01*
X1558596D01*
X1562822Y590282D01*
X1574299D01*
X1583752Y599735D01*
Y619952D01*
X1587450Y623650D01*
X1804678D01*
X1809665Y618663D01*
G01X1554358Y587258D02*
X1558698D01*
X1562474Y591034D01*
X1573987D01*
X1583000Y600047D01*
Y620600D01*
X1586802Y624402D01*
X1823926D01*
X1829665Y618663D01*
G01X1802119Y56581D02*
Y52556D01*
X1793373Y43810D01*
X1778687D01*
X1764453Y29576D01*
X1762708D01*
X1760685Y27553D01*
X1648983D01*
X1643053Y21623D01*
X1637482D01*
G01X1896970Y73460D02*
Y76789D01*
X1896426Y77333D01*
X1894066D01*
X1891124Y74391D01*
X1887433D01*
X1881484Y68442D01*
X1878078D01*
X1857542Y47906D01*
X1853247D01*
X1843400Y38059D01*
Y35000D01*
X1841700Y33300D01*
X1836741D01*
X1834641Y35400D01*
X1828700D01*
X1823850Y30550D01*
Y26850D01*
X1827900Y22800D01*
Y20671D01*
X1834476Y14095D01*
Y9647D01*
X1831702Y6873D01*
Y2326D01*
X1828744Y-632D01*
Y-4832D01*
X1822452Y-11124D01*
X1679924D01*
X1679900Y-11100D01*
X1665400D01*
X1658100Y-18400D01*
X1614600D01*
X1611900Y-15700D01*
X1606650D01*
X1605004Y-17346D01*
G01X1895354Y75650D02*
X1893447D01*
X1891436Y73639D01*
X1887745D01*
X1881796Y67690D01*
X1878390D01*
X1857610Y46910D01*
X1853351D01*
X1844440Y37999D01*
Y34976D01*
X1842011Y32547D01*
X1836430D01*
X1835046Y33931D01*
X1828366D01*
X1825066Y30631D01*
Y26698D01*
X1828800Y22964D01*
Y20835D01*
X1835228Y14407D01*
Y9959D01*
X1835229Y9958D01*
Y9336D01*
X1832454Y6561D01*
Y2014D01*
X1829496Y-944D01*
Y-5204D01*
X1823775Y-10925D01*
Y-17025D01*
X1821600Y-19200D01*
X1609358D01*
X1607504Y-17346D01*
G01X1846527Y34435D02*
X1846381Y34289D01*
Y32931D01*
X1844238Y30788D01*
Y16238D01*
X1843800Y15800D01*
Y12701D01*
X1844767Y11734D01*
X1845366D01*
X1845900Y11200D01*
Y7100D01*
X1839828Y1028D01*
X1833098D01*
X1830648Y-1422D01*
Y-5752D01*
X1825300Y-11100D01*
Y-17200D01*
X1822100Y-20400D01*
X1603058D01*
X1600004Y-17346D01*
G01X1745094Y47106D02*
X1742488Y49712D01*
X1732356D01*
X1732355Y49711D01*
X1731401D01*
X1731400Y49712D01*
X1731117D01*
X1722201Y58628D01*
X1667629D01*
X1657403Y48402D01*
X1612098D01*
X1599000Y61500D01*
G01X1625075Y80182D02*
Y79922D01*
X1628423Y76574D01*
X1646951D01*
X1648325Y75200D01*
X1673800D01*
G01X1939550Y165600D02*
Y164300D01*
X1940550Y163300D01*
X1942190D01*
X1942542Y163652D01*
Y174148D01*
X1942894Y174500D01*
X1944543D01*
X1944895Y174148D01*
Y164952D01*
X1948973Y160874D01*
X1966226D01*
X1967100Y160000D01*
Y158502D01*
X1966748Y158150D01*
X1963653D01*
X1963301Y157798D01*
Y154652D01*
X1962949Y154300D01*
X1961300D01*
X1960948Y154652D01*
Y157798D01*
X1960596Y158150D01*
X1958947D01*
X1958595Y157798D01*
Y154652D01*
X1958243Y154300D01*
X1956594D01*
X1956242Y154652D01*
Y157798D01*
X1955890Y158150D01*
X1954241D01*
X1953889Y157798D01*
Y152252D01*
X1953537Y151900D01*
X1951888D01*
X1951536Y152252D01*
Y157798D01*
X1951184Y158150D01*
X1944750D01*
X1943200Y159700D01*
X1939600D01*
X1938975Y160325D01*
X1934275D01*
X1933097Y159147D01*
Y155512D01*
X1926685Y149100D01*
X1921501D01*
X1912803Y140402D01*
X1910239D01*
X1907337Y137500D01*
X1902215D01*
X1901021Y136306D01*
Y132471D01*
X1894098Y125548D01*
Y98968D01*
X1889350Y94220D01*
X1879088D01*
X1873020Y88152D01*
Y77763D01*
X1857620Y62363D01*
X1834481D01*
X1827995Y68849D01*
Y73452D01*
X1825897Y75550D01*
X1818170D01*
X1816790Y74170D01*
X1786788D01*
X1779300Y66682D01*
Y65558D01*
X1766262Y52520D01*
X1733578D01*
X1724798Y61300D01*
X1662600D01*
X1657100Y55800D01*
X1628108D01*
X1626082Y57826D01*
X1625584D01*
X1623928Y56170D01*
X1623430D01*
X1622264Y57336D01*
Y57834D01*
X1623920Y59490D01*
Y59988D01*
X1620559Y63349D01*
X1620061D01*
X1617305Y60593D01*
X1616807D01*
X1615641Y61759D01*
Y62257D01*
X1618397Y65013D01*
Y65511D01*
X1617249Y66659D01*
X1609992D01*
X1606947Y69704D01*
X1606449D01*
X1604572Y67827D01*
X1604074D01*
X1602908Y68993D01*
Y69491D01*
X1604785Y71368D01*
Y71866D01*
X1603619Y73032D01*
X1603121D01*
X1601244Y71155D01*
X1600746D01*
X1599580Y72321D01*
Y72819D01*
X1601457Y74696D01*
Y75462D01*
X1597987Y78932D01*
Y79500D01*
G01X1883350Y202410D02*
X1881840Y200900D01*
Y199199D01*
X1884762Y196277D01*
Y190482D01*
X1889149Y186095D01*
Y152289D01*
X1886188Y149328D01*
X1884435D01*
X1876053Y140946D01*
X1868418D01*
X1866888Y139416D01*
X1860723D01*
X1858595Y137288D01*
Y130273D01*
X1858596Y130272D01*
Y128966D01*
X1858595Y128965D01*
Y127273D01*
X1858596Y127272D01*
Y125966D01*
X1857498Y124868D01*
Y123622D01*
X1857499Y123621D01*
Y120807D01*
X1846875Y110183D01*
X1821182D01*
X1813699Y102700D01*
X1794200D01*
X1792430Y104470D01*
X1787473D01*
X1774500Y91497D01*
Y86108D01*
X1765735Y77343D01*
X1764535D01*
X1759253Y72061D01*
X1734074D01*
X1730335Y75800D01*
X1706824D01*
X1705404Y77220D01*
X1702793D01*
X1697217Y82796D01*
X1683948D01*
X1679704Y78552D01*
X1654541D01*
X1653593Y79500D01*
X1650800D01*
X1649900Y78600D01*
G01X1940500Y157600D02*
X1936450D01*
X1934449Y155599D01*
Y154951D01*
X1927398Y147900D01*
X1921931D01*
X1913081Y139050D01*
X1910800D01*
X1908076Y136326D01*
X1902954D01*
X1902928Y136300D01*
X1902836D01*
X1902245Y135709D01*
Y131695D01*
X1895450Y124900D01*
Y98407D01*
X1889911Y92868D01*
X1889718D01*
X1889580Y92730D01*
X1879511D01*
X1878300Y91519D01*
Y91023D01*
X1880162Y89160D01*
Y88664D01*
X1878994Y87496D01*
X1878498D01*
X1876636Y89359D01*
X1876140D01*
X1874972Y88191D01*
Y87695D01*
X1876834Y85832D01*
Y85336D01*
X1874602Y83104D01*
Y77420D01*
X1858081Y60899D01*
X1833812D01*
X1826616Y68095D01*
Y72741D01*
X1825201Y74156D01*
X1818689D01*
X1817351Y72818D01*
X1787812D01*
X1780900Y65906D01*
Y65148D01*
X1766920Y51168D01*
X1732231D01*
X1723619Y59780D01*
X1664380D01*
X1654342Y49742D01*
X1613252D01*
X1612900Y50094D01*
Y51743D01*
X1613252Y52095D01*
X1652548D01*
X1652900Y52447D01*
Y54096D01*
X1652548Y54448D01*
X1608552D01*
X1608200Y54800D01*
Y56449D01*
X1608552Y56801D01*
X1620348D01*
X1620700Y57153D01*
Y58802D01*
X1620348Y59154D01*
X1603846D01*
X1598200Y64800D01*
Y72640D01*
X1597600Y73240D01*
X1595981D01*
X1593997Y75224D01*
Y77143D01*
X1593000Y78140D01*
G01X1931065Y175520D02*
X1932400Y174185D01*
Y166962D01*
X1930428Y164990D01*
X1914940D01*
X1902396Y152446D01*
Y149625D01*
X1903345Y148676D01*
Y144454D01*
X1902439Y143548D01*
Y141320D01*
X1898935Y137816D01*
Y133666D01*
X1890485Y125216D01*
Y111115D01*
X1887544Y108174D01*
X1870102D01*
X1864988Y103060D01*
X1843261D01*
X1829821Y89620D01*
X1829199D01*
X1829198Y89621D01*
X1824277D01*
X1815448Y80792D01*
X1804352D01*
X1801136Y84008D01*
X1796293D01*
X1791700Y79415D01*
X1783518D01*
X1774828Y70725D01*
Y67972D01*
X1767657Y60801D01*
X1751935D01*
X1748744Y63992D01*
X1683210D01*
X1683209Y63991D01*
X1682587D01*
X1679740Y66838D01*
X1654738D01*
X1651815Y69761D01*
X1627385D01*
X1627384Y69760D01*
X1626762D01*
X1624933Y71589D01*
X1618825D01*
X1610468Y79946D01*
X1606655D01*
X1603677Y82924D01*
X1598476D01*
X1596900Y84500D01*
G01X1930300Y170147D02*
X1928977Y168824D01*
X1917517D01*
X1901676Y152983D01*
Y152790D01*
X1901644Y152758D01*
Y149313D01*
X1902593Y148364D01*
Y144824D01*
X1901624Y143855D01*
Y141569D01*
X1897885Y137830D01*
Y134107D01*
X1889733Y125955D01*
Y111427D01*
X1887232Y108926D01*
X1869790D01*
X1864676Y103812D01*
X1842949D01*
X1829510Y90373D01*
X1823965D01*
X1815136Y81544D01*
X1804664D01*
X1801448Y84760D01*
X1795981D01*
X1791388Y80167D01*
X1783206D01*
X1774076Y71037D01*
Y68636D01*
X1766993Y61553D01*
X1752247D01*
X1749056Y64744D01*
X1682898D01*
X1680052Y67590D01*
X1655050D01*
X1652127Y70513D01*
X1627073D01*
X1625245Y72341D01*
X1619137D01*
X1610780Y80698D01*
X1606967D01*
X1603165Y84500D01*
X1602000D01*
G01X1608000Y99400D02*
X1609200D01*
X1611968Y96632D01*
X1617559D01*
X1619817Y94374D01*
X1629670D01*
X1631259Y92785D01*
X1660056D01*
X1662235Y94964D01*
X1677396D01*
X1678938Y93422D01*
X1682624D01*
X1684486Y91560D01*
X1698231D01*
X1707537Y82254D01*
X1752438D01*
X1752967Y81725D01*
X1760246D01*
X1762794Y84273D01*
Y92406D01*
X1766464Y96076D01*
X1769674D01*
X1769786Y96188D01*
X1772625D01*
X1785763Y109326D01*
X1813127D01*
X1820310Y116509D01*
Y121394D01*
X1829257Y130341D01*
X1840310D01*
X1845469Y135500D01*
G01X1648387Y115491D02*
X1650007Y113871D01*
X1655241D01*
X1656161Y112951D01*
Y111219D01*
X1656514Y110866D01*
X1658342D01*
X1659332Y109876D01*
Y108102D01*
X1659936Y107498D01*
X1664162D01*
X1665953Y109289D01*
X1692510D01*
X1698267Y103532D01*
X1704067D01*
X1715778Y91821D01*
X1718804D01*
X1720593Y90032D01*
X1747346D01*
X1755052Y97738D01*
Y101399D01*
X1779429Y125776D01*
X1804029D01*
X1805177Y126924D01*
X1808222D01*
X1812316Y131018D01*
X1819638D01*
X1824621Y136001D01*
X1833391D01*
X1839746Y142356D01*
X1840903D01*
Y142366D01*
X1841196D01*
X1847043Y148213D01*
X1854681D01*
X1857565Y151097D01*
X1870441D01*
X1870473Y151065D01*
X1872569D01*
X1872601Y151097D01*
X1873484D01*
X1874266Y150315D01*
X1879144D01*
X1881324Y152495D01*
Y153250D01*
G01X1689368Y98750D02*
X1689348D01*
Y98318D01*
X1688178Y97148D01*
X1684624D01*
X1681766Y100006D01*
X1681743D01*
X1681363Y100386D01*
X1681338D01*
X1680875Y100849D01*
X1679540D01*
X1679365Y100674D01*
X1679228D01*
X1677922Y99368D01*
X1667207D01*
X1665699Y100876D01*
X1657471D01*
X1653043Y96448D01*
X1644900D01*
X1641022Y100326D01*
X1632967D01*
X1632965Y100328D01*
X1631035D01*
X1631033Y100326D01*
X1614180D01*
X1614179Y100327D01*
X1612627D01*
X1609707Y103247D01*
X1607086D01*
X1601943Y108390D01*
X1600511D01*
X1598190Y110711D01*
G01X1607441Y134389D02*
Y134218D01*
X1609682Y131977D01*
X1624295D01*
X1627492Y135174D01*
Y139393D01*
X1633835Y145736D01*
X1650284D01*
X1650621Y145399D01*
X1667804D01*
X1668629Y144574D01*
X1715012D01*
X1719017Y148579D01*
X1733021D01*
X1734060Y147540D01*
X1749271D01*
X1752467Y144344D01*
X1755281D01*
X1761165Y138460D01*
X1805276D01*
X1806944Y140128D01*
X1820383D01*
X1822168Y141913D01*
X1827951D01*
X1829438Y143400D01*
Y145275D01*
X1833993Y149830D01*
X1837090D01*
G01X1610591Y124939D02*
X1612208Y126556D01*
Y128643D01*
X1613129Y129564D01*
X1625382D01*
X1626503Y128443D01*
X1631428D01*
X1637327Y122544D01*
X1648588D01*
X1650817Y120315D01*
X1652177D01*
X1653043Y121181D01*
Y122376D01*
X1654032Y123365D01*
X1655338D01*
X1655864Y122839D01*
X1656797D01*
X1657223Y123265D01*
X1658447D01*
X1659310Y122402D01*
Y121126D01*
X1660347Y120089D01*
X1660373Y120115D01*
X1661597D01*
X1662460Y119252D01*
Y118228D01*
X1663523Y117165D01*
X1664747D01*
X1665995Y118410D01*
X1674102D01*
X1676694Y115818D01*
X1693203D01*
X1700317Y108704D01*
X1705386D01*
X1713860Y100230D01*
X1745077D01*
X1749174Y104327D01*
Y115276D01*
X1755907Y122009D01*
Y124444D01*
X1756943Y125480D01*
X1769120D01*
X1780930Y137290D01*
X1805721D01*
X1807607Y139176D01*
X1820778D01*
X1822563Y140961D01*
X1831032D01*
X1837756Y147685D01*
X1839425D01*
X1843856Y152116D01*
Y159194D01*
X1846135Y161473D01*
X1855293D01*
X1857904Y164084D01*
Y170033D01*
X1860895Y173024D01*
X1865825D01*
X1868725Y175924D01*
Y199519D01*
X1866383Y201861D01*
X1864637D01*
G01X1594452Y111377D02*
Y109152D01*
X1595966Y107638D01*
X1601632D01*
X1606775Y102495D01*
X1609395D01*
X1612315Y99575D01*
X1632869D01*
X1637519Y94925D01*
X1656197D01*
X1657999Y96727D01*
X1678440D01*
X1679741Y95426D01*
X1688353D01*
X1690850Y97923D01*
X1693507D01*
X1695142Y96288D01*
X1695953D01*
X1696040Y96201D01*
X1699569D01*
X1700098Y96730D01*
X1703852D01*
X1711072Y89510D01*
Y86728D01*
X1712728Y85072D01*
X1750387D01*
X1760790Y95475D01*
Y96246D01*
X1765819Y101275D01*
X1769643D01*
X1782228Y113860D01*
X1799203D01*
X1802366Y117023D01*
X1807700D01*
X1810377Y119700D01*
X1816845D01*
X1828738Y131593D01*
X1835219D01*
X1841237Y137611D01*
X1850600D01*
X1855545Y142556D01*
X1863243D01*
X1863255Y142568D01*
X1864561D01*
X1864573Y142556D01*
X1870337D01*
X1872400Y144619D01*
G01X1857919Y156123D02*
Y158518D01*
X1855964Y160473D01*
X1846593D01*
X1844925Y158805D01*
Y151766D01*
X1839566Y146407D01*
X1837851D01*
X1831453Y140009D01*
X1822958D01*
X1821173Y138224D01*
X1816766D01*
X1816765Y138223D01*
X1815977D01*
X1815976Y138224D01*
X1808044D01*
X1806080Y136260D01*
X1781811D01*
X1767897Y122346D01*
X1757587D01*
X1750614Y115373D01*
Y97552D01*
X1746343Y93281D01*
X1741153D01*
X1738058Y96376D01*
X1723753D01*
X1722800Y95423D01*
X1716996D01*
X1713834Y98585D01*
Y98909D01*
X1705387Y107356D01*
X1700168D01*
X1692658Y114866D01*
X1675712D01*
X1673413Y117165D01*
X1669821D01*
X1668759Y116103D01*
Y114879D01*
X1667896Y114016D01*
X1663523D01*
X1662660Y114879D01*
Y116181D01*
X1661676Y117165D01*
X1660326D01*
X1659396Y118095D01*
Y119412D01*
X1658693Y120115D01*
X1653488D01*
X1652937Y119564D01*
X1650505D01*
X1648276Y121793D01*
X1633082D01*
X1628460Y126415D01*
X1615115D01*
X1613690Y124990D01*
G01X1607441Y143837D02*
Y141752D01*
X1609980Y139213D01*
X1617410D01*
X1618368Y140171D01*
Y141101D01*
X1622622Y145355D01*
X1624100D01*
X1624703Y145958D01*
Y151160D01*
X1625313Y151770D01*
X1651081D01*
X1654074Y154763D01*
X1666998D01*
X1674418Y147343D01*
X1708171D01*
X1713478Y152650D01*
X1743015D01*
X1745365Y150300D01*
X1753460D01*
X1761740Y142020D01*
X1796126D01*
X1796741Y141405D01*
X1804463D01*
X1813211Y150153D01*
X1822881D01*
X1822928Y150200D01*
X1823096D01*
X1825812Y147484D01*
X1828285D01*
X1830910Y150109D01*
Y154361D01*
X1831702Y155153D01*
X1840738D01*
X1841655Y156070D01*
Y158669D01*
X1841951Y158965D01*
Y161292D01*
X1846959Y166300D01*
X1851477D01*
X1860148Y174971D01*
X1861102D01*
X1861103Y174972D01*
X1861725D01*
X1861727Y174970D01*
X1861865D01*
X1865576Y178681D01*
Y197354D01*
X1864464Y198466D01*
G01X1607441Y106042D02*
X1608021Y105462D01*
X1610108D01*
X1613358Y102212D01*
X1642724D01*
X1645914Y99022D01*
X1653489D01*
X1656940Y102473D01*
X1666414D01*
X1668616Y104675D01*
X1688526D01*
X1695661Y97540D01*
X1696472D01*
X1696559Y97453D01*
X1699050D01*
X1699579Y97982D01*
X1704371D01*
X1712324Y90029D01*
Y87247D01*
X1713247Y86324D01*
X1749681D01*
X1759538Y96181D01*
Y96765D01*
X1765300Y102527D01*
X1769124D01*
X1781865Y115268D01*
X1798840D01*
X1801931Y118359D01*
X1807195D01*
X1812732Y123896D01*
X1817718D01*
X1826667Y132845D01*
X1834700D01*
X1841055Y139200D01*
X1850418D01*
X1855026Y143808D01*
X1862724D01*
X1862736Y143820D01*
X1865080D01*
X1865092Y143808D01*
X1866726D01*
X1869668Y146750D01*
G01X1593500Y137800D02*
X1594155Y137145D01*
X1601456D01*
X1603504Y139193D01*
X1607872D01*
X1609116Y137949D01*
Y136927D01*
X1609980Y136063D01*
X1622332D01*
X1625334Y139065D01*
Y143481D01*
X1632843Y150990D01*
X1639900D01*
X1642370Y148520D01*
X1649620D01*
X1652900Y151800D01*
X1668600D01*
X1673881Y146519D01*
X1708411D01*
X1713542Y151650D01*
X1742952D01*
X1745239Y149363D01*
X1753098D01*
X1761309Y141152D01*
X1795930D01*
X1796429Y140653D01*
X1804775D01*
X1809964Y145842D01*
X1822320D01*
X1824509Y143653D01*
G01X1821348Y143437D02*
Y143616D01*
X1819874Y145090D01*
X1810276D01*
X1805087Y139901D01*
X1761439D01*
X1752891Y148449D01*
X1745090D01*
X1742739Y150800D01*
X1713756D01*
X1708723Y145767D01*
X1669333D01*
X1666523Y148577D01*
X1651027D01*
X1649650Y147200D01*
X1630116D01*
X1626741Y143825D01*
Y135853D01*
X1623801Y132913D01*
X1609981D01*
X1609116Y133778D01*
Y134800D01*
X1607853Y136063D01*
X1594719D01*
X1594715Y136059D01*
X1592541D01*
X1590800Y137800D01*
G01X1876832Y173919D02*
X1877967Y172784D01*
Y164478D01*
X1883672Y158773D01*
Y155735D01*
X1883862Y155545D01*
Y152068D01*
X1879733Y147939D01*
X1873948D01*
X1873043Y148844D01*
X1862116D01*
X1858457Y145185D01*
X1851012D01*
X1849972Y146225D01*
X1847831D01*
X1842321Y140715D01*
X1842239D01*
X1841976Y140452D01*
X1840536D01*
X1834181Y134097D01*
X1825956D01*
X1817007Y125148D01*
X1812213D01*
X1806676Y119611D01*
X1801412D01*
X1798501Y116700D01*
X1781526D01*
X1778048Y113222D01*
X1771614D01*
X1758286Y99894D01*
Y97002D01*
X1748860Y87576D01*
X1719574D01*
X1717584Y89566D01*
X1714558D01*
X1703048Y101076D01*
X1700268D01*
X1700267Y101075D01*
X1697249D01*
X1691595Y106729D01*
X1667339D01*
X1665070Y104460D01*
X1664448D01*
X1664447Y104459D01*
X1663825D01*
X1663823Y104461D01*
X1658353D01*
X1657264Y105550D01*
X1650938D01*
X1649386Y107102D01*
Y108192D01*
X1648387Y109191D01*
G01X1875066Y175782D02*
X1875110D01*
Y173262D01*
X1877167Y171205D01*
Y164147D01*
X1882920Y158394D01*
Y155423D01*
X1883015Y155328D01*
Y152285D01*
X1879535Y148805D01*
X1879482D01*
X1879414Y148737D01*
X1874214D01*
X1873038Y149913D01*
X1869995D01*
X1869963Y149945D01*
X1862153D01*
X1858145Y145937D01*
X1851324D01*
X1850284Y146977D01*
X1847437D01*
X1841664Y141204D01*
X1840224D01*
X1833869Y134849D01*
X1825644D01*
X1816695Y125900D01*
X1811901D01*
X1806364Y120363D01*
X1801100D01*
X1798209Y117472D01*
X1781234D01*
X1777736Y113974D01*
X1771302D01*
X1757534Y100206D01*
Y97314D01*
X1748548Y88328D01*
X1719886D01*
X1717896Y90318D01*
X1714870D01*
X1703360Y101828D01*
X1697560D01*
X1691907Y107481D01*
X1678938D01*
X1678937Y107480D01*
X1667027D01*
X1664758Y105211D01*
X1664136D01*
X1664135Y105212D01*
X1658665D01*
X1657377Y106500D01*
X1651332D01*
X1650336Y107496D01*
Y107991D01*
X1651536Y109191D01*
G01X1648387Y159585D02*
X1649130D01*
X1650744Y161199D01*
X1652087D01*
X1653210Y162322D01*
Y163593D01*
X1653889Y164272D01*
X1658542D01*
X1659318Y163496D01*
Y161974D01*
X1660093Y161199D01*
X1663798D01*
X1666784Y158213D01*
X1674137D01*
X1683906Y148444D01*
X1704792D01*
X1710080Y153732D01*
X1743569D01*
X1745664Y151637D01*
X1747911D01*
X1748494Y152220D01*
X1756838D01*
X1765958Y143100D01*
X1796110D01*
X1797053Y142157D01*
X1804151D01*
X1812899Y150905D01*
X1822569D01*
X1829653Y157989D01*
X1830702D01*
X1831871Y159158D01*
X1835497D01*
X1837797Y156858D01*
X1839941D01*
G01X1613053Y184949D02*
X1614669Y183333D01*
X1614899D01*
X1614900Y183332D01*
X1616206D01*
X1616207Y183333D01*
X1622719D01*
X1627735Y178317D01*
X1649032D01*
X1650382Y176967D01*
X1654033D01*
X1655307Y175693D01*
X1666191D01*
X1666832Y175052D01*
X1668968D01*
X1670540Y173480D01*
Y172858D01*
X1670539Y172857D01*
Y169857D01*
X1672189Y168207D01*
X1678703D01*
X1683410Y163500D01*
X1691805D01*
X1694929Y166624D01*
X1712400D01*
X1713386Y165638D01*
X1775538D01*
X1780200Y170300D01*
X1787400D01*
X1791192Y174092D01*
X1826932D01*
X1830405Y177565D01*
Y180591D01*
X1844100Y194286D01*
Y198950D01*
X1847200Y202050D01*
G01X1610591Y159585D02*
X1612141Y161135D01*
X1629975D01*
X1630099Y161259D01*
X1630101D01*
X1630965Y162123D01*
Y162125D01*
X1631200Y162360D01*
Y165302D01*
X1635530Y169632D01*
X1649608D01*
X1650233Y170257D01*
X1660826D01*
X1668964Y162119D01*
X1676380D01*
X1683862Y154637D01*
X1693514D01*
X1695079Y156202D01*
X1705012D01*
X1706740Y157930D01*
X1752319D01*
X1754622Y160233D01*
X1773019D01*
X1775676Y157576D01*
X1790885D01*
X1794500Y153961D01*
X1821301D01*
X1830140Y162800D01*
X1837136D01*
X1841860Y167524D01*
Y169634D01*
X1844555Y172329D01*
X1845509D01*
X1845510Y172328D01*
X1847869D01*
X1852172Y176631D01*
Y177031D01*
X1853769Y178628D01*
X1854169D01*
X1860335Y184794D01*
Y207314D01*
X1864203Y211182D01*
Y211818D01*
X1864155Y211866D01*
Y211869D01*
X1864170D01*
G01X1778900Y165800D02*
X1777986Y164886D01*
X1711086D01*
X1709570Y163370D01*
X1706605D01*
X1704929Y165046D01*
X1699396D01*
X1695300Y160950D01*
X1693445D01*
X1691657Y159162D01*
X1686199D01*
X1678044Y167317D01*
X1671421D01*
X1669788Y168950D01*
Y173169D01*
X1668656Y174301D01*
X1666520D01*
X1665987Y174834D01*
X1655103D01*
X1653721Y176216D01*
X1650070D01*
X1648721Y177565D01*
X1627423D01*
X1624884Y180104D01*
X1616795D01*
X1613854Y183045D01*
X1607808D01*
X1606262Y181499D01*
Y179064D01*
X1602219Y175021D01*
X1600479D01*
X1597642Y172184D01*
G01X1861243Y183100D02*
Y180621D01*
X1858675Y178053D01*
X1855418D01*
X1854841Y177476D01*
X1854247D01*
X1853324Y176553D01*
Y175959D01*
X1848541Y171176D01*
X1845032D01*
X1843012Y169156D01*
Y166966D01*
X1837368Y161322D01*
X1830292D01*
X1821779Y152809D01*
X1807446D01*
X1801237Y146600D01*
X1766368D01*
X1756978Y155990D01*
X1713744D01*
X1713743Y155989D01*
X1709643D01*
X1704338Y150684D01*
X1685427D01*
X1675601Y160510D01*
X1667227D01*
X1662460Y165277D01*
Y166496D01*
X1660236Y168720D01*
X1650869D01*
X1649708Y167559D01*
X1647974D01*
X1646712Y166297D01*
Y165273D01*
X1645848Y164409D01*
X1644825D01*
X1643676Y163260D01*
Y162238D01*
X1642698Y161260D01*
X1631165D01*
X1629490Y159585D01*
X1629489D01*
G01X1864000Y184900D02*
Y181748D01*
X1859100Y176848D01*
Y174987D01*
X1854137Y170024D01*
X1845510D01*
X1844164Y168678D01*
Y166405D01*
X1837929Y160170D01*
X1830770D01*
X1822257Y151657D01*
X1807924D01*
X1801715Y145448D01*
X1765496D01*
X1756107Y154837D01*
X1710121D01*
X1704816Y149532D01*
X1684949D01*
X1675026Y159455D01*
X1666850D01*
X1662095Y164210D01*
X1660040D01*
X1659310Y164940D01*
Y166597D01*
X1658318Y167589D01*
X1650895D01*
X1649997Y166691D01*
Y165071D01*
X1649136Y164210D01*
X1647776D01*
X1646627Y163061D01*
Y162039D01*
X1645762Y161174D01*
X1643676D01*
X1642087Y159585D01*
G01X1595042Y172184D02*
X1596517Y170709D01*
X1598253D01*
X1599667Y172123D01*
Y172797D01*
X1600884Y174014D01*
X1602275D01*
X1607237Y178976D01*
Y181411D01*
X1608120Y182294D01*
X1612242D01*
X1615234Y179302D01*
X1624622D01*
X1627111Y176813D01*
X1648410D01*
X1649758Y175465D01*
X1653409D01*
X1654791Y174083D01*
X1665675D01*
X1666538Y173220D01*
Y171996D01*
X1666485Y171943D01*
Y170686D01*
X1670687Y166484D01*
X1677813D01*
X1685567Y158730D01*
G01X1695680Y159990D02*
X1699984Y164294D01*
X1704617D01*
X1706339Y162572D01*
X1710208D01*
X1711770Y164134D01*
X1779634D01*
X1783250Y167750D01*
X1785250D01*
X1785500Y168000D01*
G01X1635788Y162735D02*
X1637300Y164247D01*
Y167500D01*
X1638681Y168881D01*
X1649934D01*
X1650559Y169506D01*
X1660514D01*
X1668652Y161368D01*
X1675861D01*
X1684074Y153155D01*
X1693662D01*
X1695807Y155300D01*
X1705580D01*
X1707021Y156741D01*
X1758829D01*
X1767330Y148240D01*
X1800420D01*
G01X1626401Y256900D02*
X1627043D01*
G01X1804388Y249904D02*
Y250248D01*
X1800179Y254457D01*
X1676824D01*
X1674213Y251846D01*
X1666757D01*
X1664015Y254588D01*
X1658087D01*
X1648177Y264498D01*
Y270162D01*
X1641719Y276620D01*
Y307929D01*
X1639413Y310235D01*
G01X1662000Y399300D02*
X1660520D01*
X1659200Y397980D01*
Y394650D01*
X1640150Y375600D01*
X1630900D01*
G01X1660834Y404934D02*
X1656439Y409329D01*
X1634015D01*
X1631962Y411382D01*
Y414595D01*
X1631039Y415518D01*
X1627017D01*
X1618673Y407174D01*
X1611316D01*
X1608154Y410336D01*
X1594815D01*
X1589396Y415755D01*
Y425674D01*
G01X1639271Y491135D02*
X1638611Y490475D01*
Y487660D01*
X1640447Y485824D01*
X1641165D01*
X1644889Y482100D01*
X1647229D01*
X1650175Y479154D01*
Y429225D01*
X1666413Y412987D01*
X1667946D01*
G01X1595200Y412700D02*
X1596300Y413800D01*
X1610500D01*
X1612500Y411800D01*
G01X1640781Y487760D02*
X1640743D01*
Y487838D01*
X1641357Y487224D01*
Y486696D01*
X1645200Y482853D01*
X1647540D01*
X1650403Y479990D01*
X1656311D01*
X1657900Y478401D01*
Y463935D01*
X1654771Y460806D01*
Y428390D01*
X1662789Y420372D01*
X1669733D01*
X1671915Y418190D01*
Y408843D01*
X1671904Y408832D01*
Y372017D01*
X1671905Y372016D01*
Y371228D01*
X1671904Y371227D01*
Y278258D01*
X1676262Y273900D01*
X1679100D01*
G01X1799438Y44328D02*
X1796406D01*
X1794478Y42400D01*
X1779018D01*
X1765041Y28423D01*
X1764353D01*
X1764352Y28424D01*
X1763186D01*
X1761035Y26273D01*
X1665173D01*
X1653100Y14200D01*
Y11500D01*
G01X1851341Y106358D02*
X1850991Y106008D01*
X1842772D01*
X1828986Y92222D01*
X1823686D01*
X1814512Y83048D01*
X1805288D01*
X1802072Y86264D01*
X1795357D01*
X1790764Y81671D01*
X1782582D01*
X1772572Y71661D01*
Y69260D01*
X1766460Y63148D01*
X1753388D01*
X1750288Y66248D01*
X1683522D01*
X1680124Y69646D01*
X1678754D01*
X1673800Y74600D01*
Y75200D01*
G01X1697800Y94612D02*
Y94551D01*
X1705442Y86909D01*
X1709051D01*
X1712140Y83820D01*
X1751305D01*
X1754639Y87154D01*
X1760233D01*
X1761290Y88211D01*
Y93561D01*
X1765553Y97824D01*
X1768719D01*
X1783195Y112300D01*
X1807718D01*
X1808313Y111705D01*
G01X1692285Y94612D02*
Y94603D01*
X1692647D01*
X1694938Y92312D01*
X1698616D01*
X1707922Y83006D01*
X1752750D01*
X1753279Y82477D01*
X1759934D01*
X1762042Y84585D01*
Y92718D01*
X1766152Y96828D01*
X1768794D01*
X1783397Y111431D01*
X1792850D01*
X1794203Y110078D01*
X1811440D01*
X1814900Y113538D01*
Y116900D01*
G01X1676428Y74646D02*
Y74406D01*
X1683834Y67000D01*
X1750600D01*
X1753700Y63900D01*
X1766148D01*
X1771819Y69571D01*
Y71972D01*
X1782270Y82423D01*
X1790452D01*
X1795045Y87016D01*
X1802384D01*
X1805600Y83800D01*
X1814200D01*
X1823374Y92974D01*
X1828674D01*
X1842460Y106760D01*
X1847860D01*
X1862400Y121300D01*
Y124500D01*
G01X1883539Y199813D02*
X1886038Y197314D01*
Y190270D01*
X1889901Y186407D01*
Y151977D01*
X1886500Y148576D01*
X1884747D01*
X1876365Y140194D01*
X1868730D01*
X1867200Y138664D01*
X1861035D01*
X1859347Y136976D01*
Y130585D01*
X1859348Y130584D01*
Y129278D01*
X1859349Y129277D01*
Y128655D01*
X1859347Y128653D01*
Y127585D01*
X1859348Y127584D01*
Y125654D01*
X1858250Y124556D01*
Y123934D01*
X1858251Y123933D01*
Y120495D01*
X1846987Y109231D01*
X1821331D01*
X1813900Y101800D01*
X1793699D01*
X1791981Y103518D01*
X1787868D01*
X1775440Y91090D01*
Y81546D01*
X1769466Y75572D01*
X1765600D01*
X1761337Y71309D01*
X1732797D01*
X1729058Y75048D01*
X1704284D01*
X1702864Y76468D01*
X1702338D01*
X1696962Y81844D01*
X1684343D01*
X1680099Y77600D01*
X1653000D01*
G01X1691655Y77991D02*
X1694715Y74931D01*
X1701769D01*
X1703357Y73343D01*
X1726826D01*
X1730364Y69805D01*
X1762958D01*
X1766592Y73439D01*
X1769750D01*
X1782000Y85689D01*
Y92200D01*
X1784800Y95000D01*
X1790100D01*
X1791800Y96700D01*
X1804637D01*
X1807937Y100000D01*
X1814999D01*
X1822537Y107538D01*
X1847548D01*
X1859755Y119745D01*
Y123933D01*
X1860861Y125039D01*
Y126561D01*
X1866818Y132518D01*
X1885203D01*
X1890448Y137763D01*
Y139957D01*
X1898466Y147975D01*
Y158755D01*
X1893650Y163571D01*
Y191329D01*
X1889870Y195109D01*
Y203634D01*
X1884883Y208621D01*
X1882732D01*
X1881784Y209569D01*
Y218644D01*
X1878846Y221582D01*
Y243187D01*
X1872051Y249982D01*
X1860438D01*
X1857670Y247214D01*
X1844555D01*
X1835056Y256713D01*
X1675888D01*
X1675819Y256644D01*
X1671043D01*
X1670140Y257547D01*
G01X1694155Y77991D02*
Y77283D01*
X1695755Y75683D01*
X1702585D01*
X1704172Y74096D01*
X1727420D01*
X1730959Y70557D01*
X1762139D01*
X1765973Y74391D01*
X1769355D01*
X1781000Y86036D01*
Y92700D01*
X1784300Y96000D01*
X1789900D01*
X1791455Y97555D01*
X1804145D01*
X1807490Y100900D01*
X1814500D01*
X1821890Y108290D01*
X1847110D01*
X1859003Y120183D01*
Y124245D01*
X1860109Y125351D01*
Y126873D01*
X1866506Y133270D01*
X1884891D01*
X1889696Y138075D01*
Y140269D01*
X1897376Y147949D01*
Y158524D01*
X1892700Y163200D01*
Y190915D01*
X1889117Y194498D01*
Y203323D01*
X1884771Y207669D01*
X1882517D01*
X1880655Y209531D01*
Y218709D01*
X1878028Y221336D01*
Y242941D01*
X1871739Y249230D01*
X1860750D01*
X1857503Y245983D01*
X1844722D01*
X1834744Y255961D01*
X1676200D01*
X1676131Y255892D01*
X1672023D01*
X1670822Y254691D01*
G01X1810245Y104500D02*
X1808645Y106100D01*
X1787228D01*
X1769400Y88272D01*
Y82072D01*
X1765423Y78095D01*
X1764801D01*
X1764800Y78096D01*
X1757681D01*
X1754173Y74588D01*
X1735409D01*
X1730751Y79246D01*
X1706265D01*
X1697767Y87744D01*
X1684480D01*
X1680132Y83396D01*
X1674796D01*
X1673000Y81600D01*
G01X1651536Y112341D02*
X1652139D01*
X1653630Y110850D01*
X1655113D01*
X1656200Y109763D01*
Y108740D01*
X1658977Y105963D01*
X1664447D01*
X1666715Y108231D01*
X1678625D01*
X1678626Y108232D01*
X1678937D01*
X1678938Y108233D01*
X1692219D01*
X1697872Y102580D01*
X1703672D01*
X1715182Y91070D01*
X1718208D01*
X1720198Y89080D01*
X1748236D01*
X1756782Y97626D01*
Y100518D01*
X1774488Y118224D01*
X1782496D01*
X1788539Y124267D01*
X1804267D01*
X1805972Y125972D01*
X1808557D01*
X1808602Y126017D01*
X1808662D01*
X1812360Y129715D01*
X1814679D01*
X1816418Y127976D01*
G01X1875425Y152925D02*
X1874549Y152049D01*
X1872206D01*
X1872174Y152017D01*
X1870868D01*
X1870836Y152049D01*
X1857110D01*
X1854226Y149165D01*
X1846648D01*
X1840834Y143351D01*
X1839394D01*
X1832996Y136953D01*
X1824226D01*
X1822439Y135166D01*
X1818032D01*
X1818031Y135165D01*
X1816121D01*
X1816120Y135166D01*
X1815498D01*
X1815497Y135167D01*
X1815118D01*
X1810715Y130764D01*
X1809761D01*
X1809760Y130765D01*
X1803545D01*
X1799508Y126728D01*
X1779034D01*
X1754100Y101794D01*
Y97849D01*
X1747279Y91028D01*
X1740217D01*
X1737122Y94123D01*
X1724689D01*
X1723640Y93074D01*
X1715872D01*
X1704462Y104484D01*
X1698662D01*
X1692905Y110241D01*
X1669377D01*
X1669251Y110115D01*
X1663211D01*
X1663085Y110241D01*
X1662169D01*
X1661744Y110666D01*
X1660574D01*
X1659310Y111930D01*
Y112952D01*
X1658246Y114016D01*
X1656159D01*
X1654684Y115491D01*
X1651536D01*
G01X1856874Y219443D02*
X1858738Y221307D01*
X1865560D01*
X1867805Y219062D01*
Y218177D01*
X1867876Y218106D01*
Y211853D01*
X1867883Y211846D01*
Y209189D01*
X1867267Y208573D01*
Y202324D01*
X1869677Y199914D01*
Y175529D01*
X1866220Y172072D01*
X1861750D01*
X1860624Y170946D01*
Y155743D01*
X1859300Y154419D01*
X1855833D01*
X1852883Y151469D01*
X1845692D01*
X1839878Y145655D01*
X1838293D01*
X1831892Y139257D01*
X1823270D01*
X1821485Y137472D01*
X1817078D01*
X1817076Y137470D01*
X1816454D01*
X1816453Y137471D01*
X1815665D01*
X1815664Y137472D01*
X1814163D01*
X1810068Y133377D01*
X1804145D01*
X1803319Y134203D01*
X1782831D01*
X1769323Y120695D01*
X1764215D01*
X1763305Y119785D01*
Y118593D01*
X1760679Y115967D01*
X1757247D01*
X1752516Y111236D01*
Y97328D01*
X1746967Y91779D01*
X1740529D01*
X1737434Y94874D01*
X1724377D01*
X1723328Y93825D01*
X1716468D01*
X1704857Y105436D01*
X1699057D01*
X1693300Y111193D01*
X1693262D01*
X1692255Y112200D01*
X1672200D01*
G01X1653091Y326500D02*
X1655524Y324067D01*
Y318324D01*
X1652600Y315400D01*
Y300009D01*
X1662022Y290587D01*
Y257645D01*
X1667069Y252598D01*
X1673901D01*
X1676512Y255209D01*
X1830992D01*
X1834000Y252201D01*
Y228275D01*
X1839816Y222459D01*
X1847047D01*
X1847699Y223111D01*
Y232919D01*
X1861706Y246926D01*
X1870783D01*
X1875519Y242190D01*
Y215083D01*
X1874236Y213800D01*
G01X1864305Y253825D02*
X1859113Y259017D01*
X1673607D01*
X1672144Y260480D01*
X1667099D01*
X1666968Y260611D01*
G01X1857108Y552708D02*
X1854000Y549600D01*
Y542710D01*
X1851840Y540550D01*
Y527430D01*
X1854820Y524450D01*
Y500080D01*
X1857670Y497230D01*
X1861200D01*
X1862060Y496370D01*
Y494180D01*
X1858333Y490453D01*
X1847492D01*
X1845385Y488346D01*
Y472620D01*
X1843465Y470700D01*
X1830780D01*
X1821940Y461860D01*
X1744770D01*
X1741585Y465045D01*
X1720585D01*
X1709577Y476053D01*
X1686157D01*
X1686156Y476054D01*
X1683330D01*
X1683329Y476053D01*
X1671137D01*
X1669937Y474853D01*
Y471564D01*
X1671803Y469698D01*
Y464161D01*
X1668991Y461349D01*
X1659480D01*
X1657200Y459069D01*
Y430253D01*
X1664487Y422966D01*
X1670399D01*
X1673330Y420035D01*
Y282170D01*
X1679100Y276400D01*
G01X1667667Y257920D02*
X1667921D01*
X1669329Y259328D01*
X1671666D01*
X1673129Y257865D01*
X1857665D01*
X1861605Y253925D01*
G01X1679100Y271300D02*
X1677515D01*
X1670952Y277863D01*
Y412695D01*
X1669084Y414563D01*
X1667125D01*
X1653819Y427869D01*
Y474622D01*
X1655790Y476593D01*
G01X1847000Y487500D02*
Y465792D01*
X1846416Y465208D01*
X1828754D01*
X1824254Y460708D01*
X1744292D01*
X1741500Y463500D01*
X1720500D01*
X1708699Y475301D01*
X1685845D01*
X1685844Y475302D01*
X1683642D01*
X1683641Y475301D01*
X1671449D01*
X1670689Y474541D01*
Y471876D01*
X1672555Y470010D01*
Y463849D01*
X1669303Y460597D01*
X1668961D01*
X1668960Y460596D01*
X1668338D01*
X1668337Y460597D01*
X1659792D01*
X1658500Y459305D01*
Y437320D01*
X1660632Y435188D01*
X1665511D01*
X1666278Y435955D01*
X1668668D01*
X1670357Y434266D01*
Y427217D01*
X1674082Y423492D01*
Y283942D01*
X1679100Y278924D01*
G01X1859530Y516430D02*
Y507076D01*
X1867248Y499358D01*
Y490312D01*
X1851468Y474532D01*
Y466088D01*
X1847132Y461752D01*
X1830188D01*
X1825688Y457252D01*
X1745054D01*
X1740710Y461596D01*
X1720334D01*
X1720333Y461595D01*
X1719711D01*
X1707509Y473797D01*
X1685221D01*
X1685220Y473798D01*
X1684266D01*
X1670313Y459845D01*
X1669273D01*
X1669272Y459844D01*
X1668026D01*
X1668025Y459845D01*
X1660104D01*
X1659700Y459441D01*
Y437881D01*
X1661641Y435940D01*
X1665199D01*
X1665966Y436707D01*
X1668980D01*
X1671109Y434578D01*
Y427529D01*
X1674834Y423804D01*
Y285859D01*
X1679100Y281593D01*
G01X1653091Y326500D02*
X1655005Y328414D01*
Y377485D01*
X1662900Y385380D01*
Y398400D01*
X1662000Y399300D01*
G01X1957212Y479521D02*
Y478141D01*
X1958032Y477321D01*
X1959302D01*
X1960932Y475691D01*
Y470260D01*
X1968730Y462462D01*
Y447183D01*
X1959323Y437776D01*
X1935215D01*
X1933621Y439370D01*
X1912160D01*
X1910566Y437776D01*
X1857002D01*
X1853800Y434574D01*
X1682928D01*
X1679903Y431549D01*
Y307732D01*
X1677524Y305353D01*
Y291076D01*
X1679100Y289500D01*
G01X1957063Y474769D02*
Y475448D01*
X1958184Y476569D01*
X1958990D01*
X1960180Y475379D01*
Y469877D01*
X1967778Y462279D01*
Y447578D01*
X1958928Y438728D01*
X1935610D01*
X1934016Y440322D01*
X1911765D01*
X1910171Y438728D01*
X1856607D01*
X1853405Y435526D01*
X1682445D01*
X1679151Y432232D01*
Y308044D01*
X1676772Y305665D01*
Y288921D01*
X1679100Y286593D01*
G01X1968375Y509375D02*
Y507495D01*
X1953200Y492320D01*
Y473700D01*
X1945600Y466100D01*
Y447900D01*
X1938896Y441196D01*
X1855018D01*
X1850570Y436748D01*
X1682603D01*
X1678399Y432544D01*
Y309256D01*
X1676020Y306877D01*
Y287173D01*
X1679100Y284093D01*
G01X1673074Y453185D02*
Y460976D01*
X1684743Y472645D01*
X1707031D01*
X1719233Y460443D01*
X1720811D01*
X1720812Y460444D01*
X1740232D01*
X1744576Y456100D01*
X1826166D01*
X1830666Y460600D01*
X1847610D01*
X1852988Y465978D01*
Y474422D01*
X1868400Y489834D01*
Y499836D01*
X1861120Y507116D01*
Y515070D01*
X1862310Y516260D01*
Y522628D01*
X1866450Y526771D01*
Y538562D01*
X1865209Y539803D01*
Y549791D01*
X1860500Y554500D01*
X1856300D01*
X1854508Y552708D01*
G01X1676287Y447244D02*
Y447533D01*
X1674728Y449092D01*
Y450447D01*
X1675651Y451370D01*
X1676073D01*
X1678201Y453498D01*
Y458669D01*
X1682367Y462835D01*
Y465190D01*
X1689070Y471893D01*
X1703789D01*
X1716401Y459281D01*
X1738684D01*
X1742617Y455348D01*
X1827684D01*
X1832184Y459848D01*
X1851761D01*
X1856011Y464098D01*
X1860827D01*
X1865385Y468656D01*
Y485168D01*
X1869152Y488935D01*
Y500148D01*
X1862011Y507289D01*
Y514897D01*
X1863062Y515948D01*
Y522316D01*
X1869686Y528944D01*
Y537624D01*
X1865961Y541349D01*
Y581012D01*
X1856693Y590280D01*
X1851923D01*
X1831493Y610710D01*
X1817618D01*
X1809665Y618663D01*
G01X1676304Y449794D02*
X1678953Y452443D01*
Y458053D01*
X1683412Y462512D01*
Y465171D01*
X1689382Y471141D01*
X1703194D01*
X1716006Y458329D01*
X1738289D01*
X1742022Y454596D01*
X1828279D01*
X1832579Y458896D01*
X1852156D01*
X1856606Y463346D01*
X1861139D01*
X1866337Y468544D01*
Y484773D01*
X1869904Y488340D01*
Y500584D01*
X1862763Y507725D01*
Y514395D01*
X1864011Y515643D01*
Y521578D01*
X1870438Y528011D01*
Y538384D01*
X1867084Y541738D01*
Y580953D01*
X1856660Y591377D01*
X1855799D01*
X1832724Y614452D01*
Y615604D01*
X1829665Y618663D01*
G01X1875973Y499838D02*
Y485808D01*
X1878983Y482798D01*
Y471125D01*
X1870052Y462194D01*
X1857084D01*
X1852290Y457400D01*
X1834200D01*
X1830244Y453444D01*
X1741544D01*
X1737812Y457176D01*
X1715529D01*
X1704353Y468352D01*
X1693813D01*
X1689516Y464055D01*
X1686585D01*
X1682604Y460074D01*
Y456434D01*
X1683500Y455538D01*
Y448500D01*
X1682020Y447020D01*
X1679822D01*
X1675469Y442667D01*
X1673579D01*
X1673550Y442696D01*
G01X1869914Y517225D02*
X1868743Y516054D01*
Y514245D01*
X1880450Y502538D01*
Y487194D01*
X1884665Y482979D01*
Y465485D01*
X1877952Y458772D01*
X1857975D01*
X1842577Y443374D01*
X1734282D01*
X1730506Y447150D01*
X1715450D01*
X1710500Y452100D01*
Y458950D01*
X1703200Y466250D01*
X1695286D01*
X1686761Y457725D01*
X1685775D01*
X1684833Y456832D01*
X1684435D01*
G01X1866688Y517128D02*
X1867924Y515892D01*
Y514000D01*
X1879500Y502424D01*
Y486800D01*
X1883913Y482387D01*
Y465797D01*
X1877838Y459722D01*
X1857581D01*
X1842183Y444324D01*
X1734676D01*
X1730900Y448100D01*
X1715844D01*
X1711450Y452494D01*
Y459344D01*
X1703594Y467200D01*
X1695448D01*
X1695250Y467002D01*
X1694974D01*
X1686647Y458675D01*
X1685672D01*
X1684843Y459421D01*
X1684435D01*
G01X1858528Y544528D02*
X1856100Y542100D01*
Y541400D01*
X1852920Y538220D01*
Y528710D01*
X1856100Y525530D01*
Y500200D01*
X1858318Y497982D01*
X1861512D01*
X1862812Y496682D01*
Y487506D01*
X1850446Y475140D01*
Y466980D01*
X1846370Y462904D01*
X1829710D01*
X1825210Y458404D01*
X1744966D01*
X1741022Y462348D01*
X1720022D01*
X1707821Y474549D01*
X1685533D01*
X1685532Y474550D01*
X1683954D01*
X1678648Y469244D01*
X1675659D01*
X1672265Y472638D01*
Y473600D01*
G01X1759093Y9310D02*
Y10297D01*
X1755175Y14215D01*
Y20853D01*
X1756637Y22315D01*
X1759153D01*
X1762624Y25786D01*
X1764543D01*
X1779447Y40690D01*
X1786952D01*
X1789356Y38286D01*
G01X1824240Y83680D02*
X1823977Y83943D01*
X1820229D01*
X1814550Y78264D01*
X1794218D01*
X1793055Y77101D01*
X1784434D01*
X1776361Y69028D01*
Y68755D01*
X1776362Y68754D01*
Y66776D01*
X1765426Y55840D01*
X1737460D01*
X1735150Y58150D01*
G01X1788216Y59197D02*
Y57940D01*
X1771459Y41183D01*
X1748835D01*
X1746552Y38900D01*
G01X1767250Y94500D02*
X1769309Y92441D01*
X1770323D01*
X1786456Y108574D01*
X1813846D01*
X1821416Y116144D01*
Y120256D01*
X1821415Y120257D01*
Y121435D01*
X1829569Y129589D01*
X1849006D01*
X1850113Y128482D01*
X1855883D01*
X1857020Y129619D01*
G01X1767250Y89500D02*
X1769383Y91633D01*
X1770599D01*
X1786788Y107822D01*
X1814258D01*
X1822168Y115732D01*
Y121124D01*
X1829881Y128837D01*
X1848694D01*
X1849801Y127730D01*
X1855909D01*
X1857020Y126619D01*
G01X1765015Y119100D02*
X1765065Y119150D01*
X1769408D01*
X1781309Y131051D01*
X1800653D01*
X1801519Y131917D01*
X1810238D01*
X1814641Y136320D01*
X1815186D01*
X1815187Y136319D01*
X1815975D01*
X1815976Y136318D01*
X1816598D01*
X1816599Y136317D01*
X1817553D01*
X1817556Y136320D01*
X1821963D01*
X1823748Y138105D01*
X1832518D01*
X1838916Y144503D01*
X1840356D01*
X1846170Y150317D01*
X1853361D01*
X1856311Y153267D01*
X1859778D01*
X1862767Y156256D01*
X1875556D01*
X1875600Y156300D01*
G01X1727896Y246175D02*
X1728581Y245490D01*
X1799131D01*
X1801004Y243617D01*
X1822015D01*
X1827851Y237781D01*
Y235571D01*
X1826047Y233767D01*
X1826009D01*
X1825086Y232844D01*
Y231538D01*
X1827850Y228774D01*
Y215833D01*
X1832168Y211515D01*
X1835615D01*
X1840069Y215969D01*
X1862247D01*
X1864771Y213445D01*
X1864823D01*
X1865746Y212522D01*
Y212470D01*
X1865772Y212444D01*
Y210980D01*
X1865779Y210973D01*
Y210927D01*
X1862636Y207784D01*
Y200466D01*
X1862988Y200114D01*
X1865715D01*
X1866730Y199099D01*
Y178770D01*
X1862178Y174218D01*
X1861415D01*
X1861414Y174219D01*
X1860460D01*
X1856752Y170511D01*
Y166200D01*
X1853177Y162625D01*
X1846613D01*
X1846612Y162626D01*
X1845658D01*
X1842703Y159671D01*
Y158717D01*
X1842704Y158716D01*
Y158654D01*
X1842664Y158614D01*
Y152565D01*
X1840517Y150418D01*
X1839014D01*
X1838091Y151341D01*
Y151388D01*
X1837761D01*
X1837743Y151406D01*
X1836437D01*
X1836419Y151388D01*
X1833728D01*
X1827500Y145160D01*
Y144900D01*
G01X1886299Y153928D02*
Y154172D01*
X1884424Y156047D01*
Y159932D01*
X1880005Y164351D01*
Y173107D01*
X1878148Y174964D01*
Y188346D01*
X1873676Y192818D01*
Y208553D01*
X1872753Y209476D01*
X1870989D01*
X1868635Y211830D01*
Y212158D01*
X1868628Y212165D01*
Y219303D01*
X1865837Y222094D01*
X1850172D01*
X1847033Y218955D01*
X1841991D01*
X1835303Y212267D01*
X1832480D01*
X1828602Y216145D01*
Y217524D01*
X1828603Y217525D01*
Y238707D01*
X1822652Y244658D01*
X1801027D01*
X1799443Y246242D01*
X1732669D01*
X1730681Y248230D01*
X1722740D01*
X1720651Y246141D01*
G01X1730996Y442804D02*
X1733442Y440358D01*
X1847002D01*
X1850744Y444100D01*
X1928188D01*
X1928264Y444024D01*
X1933324D01*
X1944192Y454892D01*
Y466684D01*
X1951792Y474284D01*
Y492372D01*
X1966730Y507310D01*
Y511130D01*
X1969329Y513729D01*
Y561729D01*
X1972800Y565200D01*
G01X1939845Y445055D02*
X1936938Y442148D01*
X1854623D01*
X1850815Y438340D01*
X1732130D01*
X1728869Y441601D01*
X1724369D01*
G01X1743500Y564500D02*
X1744499D01*
X1758299Y578300D01*
X1770271D01*
X1772578Y575993D01*
G01X1750399Y603201D02*
X1757752Y595848D01*
X1779122D01*
X1783020Y591950D01*
X1803950D01*
X1806700Y594700D01*
X1814138D01*
X1816138Y596700D01*
X1824300D01*
X1829051Y591949D01*
Y591299D01*
G01X1795000Y599600D02*
X1791826Y602774D01*
X1762748D01*
X1758569Y606953D01*
X1757319D01*
G01X1820457Y39128D02*
X1821576Y38009D01*
Y34764D01*
X1820533Y33721D01*
X1813284D01*
X1811398Y31835D01*
Y18750D01*
X1813178Y16970D01*
X1815566D01*
X1819118Y13418D01*
Y5017D01*
X1814406Y305D01*
X1812005D01*
X1809504Y-2196D01*
Y-5000D01*
G01X1824130Y39703D02*
Y39181D01*
X1823650Y38701D01*
Y34643D01*
X1821179Y32172D01*
X1820848D01*
X1820845Y32169D01*
X1813927D01*
X1812765Y31007D01*
Y19578D01*
X1813821Y18522D01*
X1816209D01*
X1821005Y13726D01*
Y3124D01*
X1821376Y2753D01*
Y477D01*
X1819504Y-1395D01*
Y-5000D01*
G01X1794100Y70898D02*
X1796891D01*
X1797973Y69816D01*
X1818015D01*
X1821071Y66760D01*
G01X1834178Y58304D02*
X1857826D01*
X1876010Y76488D01*
Y82329D01*
X1882481Y88800D01*
X1888844D01*
X1896985Y96941D01*
Y103696D01*
X1899914Y106625D01*
Y115915D01*
X1899913Y115916D01*
Y117082D01*
X1899914Y117083D01*
Y117382D01*
X1903956Y121424D01*
X1914537D01*
X1914956Y121843D01*
Y122467D01*
X1914957Y122468D01*
Y138934D01*
X1922423Y146400D01*
X1928188D01*
X1937164Y155376D01*
X1948305D01*
X1949389Y154292D01*
Y152083D01*
G01X1966700Y152400D02*
X1957797D01*
X1955704Y150307D01*
X1948653D01*
X1945484Y153476D01*
X1942280D01*
X1940604Y151800D01*
X1935580D01*
X1928632Y144852D01*
X1922953D01*
X1916365Y138264D01*
Y121884D01*
X1916364Y121883D01*
Y121259D01*
X1915121Y120016D01*
X1904839D01*
X1901322Y116499D01*
Y106041D01*
X1898393Y103112D01*
Y96357D01*
X1889419Y87383D01*
X1883363D01*
X1877610Y81630D01*
Y76096D01*
X1856114Y54600D01*
X1835562D01*
G01X1820969Y64870D02*
X1817431Y68408D01*
X1796492D01*
X1796100Y68800D01*
G01X1834400Y216900D02*
X1833009Y218291D01*
Y250963D01*
X1831700Y252272D01*
G01X1793900Y550100D02*
X1793551Y549751D01*
Y546173D01*
X1792000Y544622D01*
Y519678D01*
X1793878Y517800D01*
Y512800D01*
X1795378Y511300D01*
X1797500D01*
X1798883Y512683D01*
Y515636D01*
G01X1829176Y584287D02*
X1828834D01*
X1826252Y581705D01*
Y540653D01*
X1822400Y536801D01*
Y514747D01*
X1834195Y502952D01*
X1843195D01*
X1846552Y499595D01*
Y491305D01*
X1844100Y488853D01*
Y479400D01*
X1842452Y477752D01*
Y477022D01*
X1843750Y475724D01*
G01X1840750D02*
X1841500Y476474D01*
Y478147D01*
X1843148Y479795D01*
Y489248D01*
X1845600Y491700D01*
Y499200D01*
X1842800Y502000D01*
X1833800D01*
X1821448Y514352D01*
Y537196D01*
X1825300Y541048D01*
Y577807D01*
X1818182Y584925D01*
X1816876D01*
X1816052Y584101D01*
G01X1795200Y525700D02*
X1796153Y524747D01*
Y514200D01*
G01X1828200Y519000D02*
Y532000D01*
X1835000Y538800D01*
Y550300D01*
G01X1779000Y585500D02*
X1781177D01*
X1781809Y584868D01*
Y584651D01*
X1781808Y584650D01*
Y583614D01*
X1784470Y580952D01*
X1811202D01*
X1811671Y581421D01*
X1815055D01*
X1822528Y573948D01*
Y543298D01*
X1819909Y540679D01*
Y529293D01*
X1818509Y527893D01*
G01X1776500Y621200D02*
X1777348Y622048D01*
X1797380D01*
X1815556Y603872D01*
X1834875D01*
X1847997Y590750D01*
X1848900D01*
G01X1778400Y618900D02*
X1780648Y621148D01*
X1797192D01*
X1815420Y602920D01*
X1834480D01*
X1845000Y592400D01*
Y590800D01*
G01X1895100Y201770D02*
X1897469D01*
X1909666Y189573D01*
X1935192D01*
X1947154Y177611D01*
Y167647D01*
X1951749Y163052D01*
X1967112D01*
X1969228Y160936D01*
Y116293D01*
X1960484Y107549D01*
X1936609D01*
X1929780Y100720D01*
Y93904D01*
X1923576Y87700D01*
Y68676D01*
X1921200Y66300D01*
X1919900D01*
X1918600Y67600D01*
X1907280D01*
X1891131Y51451D01*
Y-4874D01*
X1898472Y-12215D01*
X1900313D01*
X1903160Y-15062D01*
Y-19416D01*
G01X1925358Y140685D02*
X1926743Y139300D01*
X1930100D01*
X1932108Y137292D01*
Y124708D01*
X1928700Y121300D01*
Y114849D01*
X1915104Y101253D01*
Y76924D01*
X1908744Y70564D01*
X1905818D01*
X1901837Y66583D01*
X1891783D01*
X1886000Y60800D01*
Y51900D01*
X1880888Y46788D01*
X1878668D01*
X1876116Y44236D01*
Y40766D01*
X1867446Y32096D01*
X1854895D01*
X1853467Y33524D01*
Y35000D01*
G01X1934000Y147100D02*
Y146800D01*
X1929700Y142500D01*
X1924600D01*
X1923500Y141400D01*
Y138300D01*
X1923630Y138170D01*
Y123780D01*
X1922029Y122179D01*
Y114832D01*
X1910399Y103202D01*
Y101254D01*
X1910400Y101253D01*
Y81800D01*
X1899887Y71287D01*
X1888720D01*
X1879400Y61967D01*
Y57940D01*
X1869170Y47710D01*
Y46344D01*
X1867026Y44200D01*
X1854300D01*
X1851448Y41348D01*
X1850600D01*
G01X1855400Y40800D02*
X1857486Y38714D01*
Y36803D01*
X1858147Y36142D01*
X1867872D01*
X1873680Y41950D01*
Y45990D01*
X1876830Y49140D01*
X1879913D01*
X1882800Y52027D01*
Y60927D01*
X1890808Y68935D01*
X1900862D01*
X1904844Y72917D01*
X1907770D01*
X1912572Y77719D01*
Y80645D01*
X1912752Y80825D01*
Y102228D01*
X1925613Y115089D01*
Y119970D01*
X1925116Y120467D01*
Y121939D01*
X1925982Y122805D01*
Y127263D01*
X1929756Y131037D01*
G01X1844444Y224035D02*
X1846547Y226138D01*
Y233397D01*
X1861228Y248078D01*
X1871261D01*
X1876672Y242667D01*
Y241713D01*
X1876671Y241712D01*
Y221063D01*
X1879093Y218641D01*
Y217027D01*
X1877027Y214961D01*
Y211207D01*
X1881904Y206330D01*
X1884270D01*
X1887790Y202810D01*
Y190360D01*
X1891053Y187097D01*
Y145597D01*
X1888544Y143088D01*
Y139102D01*
X1884605Y135163D01*
X1875709D01*
X1872254Y138618D01*
G01X1864904Y114735D02*
X1867412Y117243D01*
Y127948D01*
X1869704Y130240D01*
X1884928D01*
X1890787Y136099D01*
X1895060D01*
G01X1892791Y200069D02*
X1897871D01*
X1909119Y188821D01*
X1934691D01*
X1946326Y177186D01*
Y167411D01*
X1951437Y162300D01*
X1966076D01*
X1968476Y159900D01*
Y116605D01*
X1960172Y108301D01*
X1936297D01*
X1928548Y100552D01*
Y94248D01*
X1922524Y88224D01*
Y70524D01*
X1920300Y68300D01*
G01X1895614Y204785D02*
X1909975Y190424D01*
X1940205D01*
X1948299Y182330D01*
Y167566D01*
X1952013Y163852D01*
X1967677D01*
X1972776Y158753D01*
Y151847D01*
X1970127Y149198D01*
Y116128D01*
X1960796Y106797D01*
X1944600D01*
X1939703Y101900D01*
X1933000D01*
X1931329Y100229D01*
Y93601D01*
X1924328Y86600D01*
Y68364D01*
X1921512Y65548D01*
X1918052D01*
X1917600Y66000D01*
G01X1891880Y204370D02*
X1891150Y203640D01*
Y195910D01*
X1899120Y187940D01*
X1927550D01*
X1933850Y181640D01*
Y164830D01*
X1929990Y160970D01*
X1923870D01*
X1916310Y153410D01*
Y149676D01*
G01X1837200Y525700D02*
X1839100Y523800D01*
Y510870D01*
X1842450Y507520D01*
G01X1860000Y495500D02*
X1856600D01*
X1850476Y501624D01*
Y549724D01*
X1848800Y551400D01*
G01X1844490Y509230D02*
X1848860Y513600D01*
Y541340D01*
X1846650Y543550D01*
Y545950D01*
X1848900Y548200D01*
G01X1895523Y586365D02*
X1905315D01*
X1911750Y592800D01*
G01X1866800Y588000D02*
X1867392Y588592D01*
X1871092D01*
X1879850Y597350D01*
X1905650D01*
X1922800Y614500D01*
X1927000D01*
G01X1854530Y533132D02*
Y533180D01*
X1861631Y540281D01*
Y550785D01*
X1859708Y552708D01*
G01X1918352Y89300D02*
Y91452D01*
X1920665Y93765D01*
Y100668D01*
X1938235Y118238D01*
Y127615D01*
X1950000Y139380D01*
Y142553D01*
X1950934Y143487D01*
Y143730D01*
G01X1923300Y94300D02*
Y96900D01*
X1921655Y98545D01*
Y100143D01*
X1939356Y117844D01*
Y126996D01*
X1951700Y139340D01*
Y141000D01*
G01X1937100Y146900D02*
X1938000Y146000D01*
Y129926D01*
X1937139Y129065D01*
Y118523D01*
X1919689Y101073D01*
Y97582D01*
X1918210Y96103D01*
G01X1918002Y98902D02*
Y100824D01*
X1936187Y119009D01*
Y144013D01*
G01X1962800Y149300D02*
X1960065Y146565D01*
Y140735D01*
X1967250Y133550D01*
Y116830D01*
X1961200Y110780D01*
X1936229D01*
X1924924Y99475D01*
X1923329D01*
G01X1963092Y167936D02*
X1959900Y171128D01*
Y176900D01*
X1946600Y190200D01*
X1944300D01*
G01X1945000Y474000D02*
X1945400D01*
X1946247Y474847D01*
Y476311D01*
X1949196Y479260D01*
Y486830D01*
X1936126Y499900D01*
X1922636D01*
X1919500Y503036D01*
Y509100D01*
X1915900Y512700D01*
X1912500D01*
X1911800Y512000D01*
Y511200D01*
X1912300Y510700D01*
X1912800D01*
G01X1948200Y474300D02*
X1947700D01*
X1946999Y475001D01*
Y475999D01*
X1949948Y478948D01*
Y487142D01*
X1936438Y500652D01*
X1922948D01*
X1920252Y503348D01*
Y509412D01*
X1916212Y513452D01*
X1912188D01*
X1911018Y512282D01*
Y511318D01*
X1910400Y510700D01*
X1909800D01*
G01X1908469Y525415D02*
X1910700Y527646D01*
Y547800D01*
X1907200Y551300D01*
Y551600D01*
G01X1973000Y597200D02*
X1972100D01*
X1969300Y594400D01*
X1942512D01*
X1940210Y592098D01*
X1933908D01*
X1931606Y594400D01*
X1923175D01*
X1913350Y584575D01*
Y569100D01*
X1902400Y558150D01*
Y527220D01*
X1900595Y525415D01*
G01X1934600Y561900D02*
X1958250D01*
X1962950Y566600D01*
G01X1944882Y597834D02*
X1939898Y592850D01*
X1934220D01*
X1929720Y597350D01*
X1922450D01*
X1917900Y592800D01*
X1911750D01*
G54D29*
G01X618430Y491550D02*
Y510900D01*
X616334Y512996D01*
Y515668D01*
X617700Y517034D01*
Y534540D01*
X621017Y537857D01*
Y594800D01*
X619417Y596400D01*
X487349D01*
X482937Y591988D01*
Y587844D01*
X483791Y586990D01*
Y584246D01*
X479405Y579860D01*
X381395D01*
X377824Y583431D01*
X373898D01*
X372422Y581955D01*
X361348D01*
X359168Y584135D01*
Y596613D01*
X354609Y601172D01*
Y604239D01*
X350009Y608839D01*
Y613270D01*
X348727Y614552D01*
X344006D01*
X341958Y616600D01*
X340590D01*
G01X109800Y506556D02*
X106692Y503448D01*
Y495050D01*
X94998Y483356D01*
Y481612D01*
G54D39*
G01X146299Y-42355D02*
X443146D01*
G02Y-45915I0J-1780D01*
G01X145585D01*
X144200Y-47300D01*
X85550D01*
X80500Y-42250D01*
G01X160431Y27899D02*
Y29453D01*
X162678Y31700D01*
X163902D01*
X165478Y33276D01*
Y34900D01*
X164703Y35675D01*
Y48688D01*
X163477Y49914D01*
G01X132959D02*
X134432Y48441D01*
Y35316D01*
X135048Y34700D01*
Y33356D01*
X133592Y31900D01*
X132192D01*
X130313Y30021D01*
Y27899D01*
G01X153738D02*
X154985Y29146D01*
Y30400D01*
X156285Y31700D01*
X157285D01*
X159085Y33500D01*
Y34900D01*
X158473Y35512D01*
Y48525D01*
X157084Y49914D01*
G01X123620Y27899D02*
Y29453D01*
X125867Y31700D01*
X127091D01*
X128667Y33276D01*
Y34900D01*
X127892Y35675D01*
Y48688D01*
X126666Y49914D01*
G01X150391D02*
X151780Y48525D01*
Y35512D01*
X152392Y34900D01*
Y33500D01*
X150592Y31700D01*
X149592D01*
X148292Y30400D01*
Y29146D01*
X147045Y27899D01*
G01X167124D02*
Y30021D01*
X169003Y31900D01*
X170403D01*
X171859Y33356D01*
Y34700D01*
X171243Y35316D01*
Y48441D01*
X169770Y49914D01*
G01X141880Y30540D02*
X145072Y33732D01*
Y49122D01*
X141880Y52314D01*
G01X136806Y30750D02*
X137576Y31520D01*
X138558D01*
X139886Y32848D01*
Y48994D01*
X136780Y52100D01*
G01Y33399D02*
X137599Y32580D01*
X138115D01*
X138826Y33291D01*
Y36580D01*
X136906Y38500D01*
Y39500D01*
X137506Y40100D01*
X138006D01*
X138826Y40920D01*
Y41880D01*
X138106Y42600D01*
X137394D01*
X136892Y43102D01*
Y44434D01*
X137508Y45050D01*
X137856D01*
X138826Y46020D01*
Y48553D01*
X137879Y49500D01*
X136780D01*
G01X130313Y54957D02*
X129192Y53836D01*
Y50900D01*
X132092Y48000D01*
Y46032D01*
X130559Y44499D01*
Y43300D01*
X131809Y42050D01*
Y41150D01*
X130459Y39800D01*
Y38501D01*
X132092Y36868D01*
Y34567D01*
X132959Y33700D01*
G01X130313Y54957D02*
Y62821D01*
X132292Y64800D01*
Y66150D01*
X130992Y67450D01*
Y72000D01*
X132192Y73200D01*
Y85300D01*
X131092Y86400D01*
Y91000D01*
X132380Y92288D01*
Y94212D01*
X130992Y95600D01*
Y98934D01*
X131602Y99544D01*
X133182D01*
X133792Y100154D01*
Y101544D01*
X133182Y102154D01*
X131602D01*
X130992Y102764D01*
Y104154D01*
X131602Y104764D01*
X133182D01*
X133792Y105374D01*
Y106764D01*
X133182Y107374D01*
X132392D01*
X131892Y107874D01*
Y125402D01*
X130742Y126552D01*
Y128012D01*
X131892Y129162D01*
Y130622D01*
X130742Y131772D01*
Y133232D01*
X131892Y134382D01*
Y135842D01*
X130742Y136992D01*
Y138452D01*
X131892Y139602D01*
Y141062D01*
X130742Y142212D01*
Y143672D01*
X131892Y144822D01*
Y147150D01*
X144692Y159950D01*
X147942D01*
X151067Y163075D01*
Y166325D01*
X212142Y227400D01*
X213442D01*
X255363Y269321D01*
X261898D01*
G01X163391Y33700D02*
X162303Y34788D01*
Y36668D01*
X160870Y38101D01*
Y39300D01*
X162370Y40800D01*
Y42000D01*
X160920Y43450D01*
Y44849D01*
X162303Y46232D01*
Y48101D01*
X159503Y50901D01*
Y54029D01*
X160431Y54957D01*
G01D02*
Y56258D01*
X161492Y57319D01*
Y64099D01*
X162391Y64998D01*
Y66301D01*
X161491Y67201D01*
Y72103D01*
X162491Y73103D01*
Y85418D01*
X161491Y86418D01*
Y91218D01*
X162391Y92118D01*
Y95074D01*
X164939Y97622D01*
Y107997D01*
X167892Y110950D01*
Y143608D01*
X245342Y221058D01*
Y225658D01*
X259525Y239841D01*
X260278D01*
G01X163477Y49914D02*
X161627Y51764D01*
Y53454D01*
X163432Y55259D01*
X165191Y64199D01*
Y73003D01*
X165174Y73020D01*
Y86301D01*
X165277Y86404D01*
Y93272D01*
X167648Y97488D01*
Y107406D01*
X170392Y110150D01*
Y142572D01*
X247842Y220022D01*
Y224622D01*
X259720Y236500D01*
X260489D01*
X261473Y237484D01*
G01X132959Y49914D02*
X130886Y51987D01*
Y53094D01*
X132380Y54588D01*
Y61488D01*
X134880Y63988D01*
Y93688D01*
X135992Y94800D01*
Y107600D01*
X133942Y109650D01*
Y146350D01*
X145067Y157475D01*
X148267D01*
X153067Y162275D01*
Y165475D01*
X213042Y225450D01*
X214392D01*
X255763Y266821D01*
X261898D01*
G01X153738Y54957D02*
Y55577D01*
X155980Y57819D01*
Y66003D01*
X155180Y66803D01*
Y72587D01*
X155680Y73087D01*
Y85818D01*
X155080Y86418D01*
Y91118D01*
X156030Y92068D01*
Y93463D01*
X153892Y95601D01*
Y108700D01*
X155542Y110350D01*
Y130350D01*
X156042Y130850D01*
X160992D01*
X161792Y131650D01*
Y133401D01*
X161182Y134011D01*
X157352D01*
X156742Y134621D01*
Y136011D01*
X157352Y136621D01*
X161182D01*
X161792Y137231D01*
Y145950D01*
X205660Y189818D01*
Y190680D01*
X203397Y192943D01*
Y193805D01*
X204381Y194789D01*
X205243D01*
X207506Y192526D01*
X208368D01*
X209352Y193510D01*
Y194372D01*
X207089Y196635D01*
Y197497D01*
X208073Y198481D01*
X208935D01*
X211198Y196218D01*
X212060D01*
X213044Y197202D01*
Y198064D01*
X210781Y200327D01*
Y201189D01*
X211765Y202173D01*
X212627D01*
X214890Y199910D01*
X215752D01*
X216736Y200894D01*
Y201756D01*
X214473Y204019D01*
Y204881D01*
X215457Y205865D01*
X216319D01*
X218582Y203602D01*
X219444D01*
X220428Y204586D01*
Y205448D01*
X218165Y207711D01*
Y208573D01*
X219149Y209557D01*
X220011D01*
X222274Y207294D01*
X223136D01*
X238792Y222950D01*
Y227590D01*
X256241Y245039D01*
G01X157084Y34100D02*
X155517Y35667D01*
Y36868D01*
X154159Y38226D01*
Y39599D01*
X155359Y40799D01*
Y41925D01*
X154159Y43125D01*
Y44700D01*
X155959Y46500D01*
Y47558D01*
X152617Y50900D01*
Y53836D01*
X153738Y54957D01*
G01X157084Y49914D02*
X155180Y51818D01*
Y53418D01*
X158530Y56768D01*
Y66503D01*
X159080Y67053D01*
Y72511D01*
X158480Y73111D01*
Y85918D01*
X159180Y86618D01*
Y91018D01*
X158530Y91668D01*
Y96089D01*
X160142Y97701D01*
Y99326D01*
X159532Y99936D01*
X157102D01*
X156492Y100546D01*
Y101936D01*
X157102Y102546D01*
X160282D01*
X160892Y103156D01*
Y104546D01*
X160282Y105156D01*
X157102D01*
X156492Y105766D01*
Y107156D01*
X157102Y107766D01*
X160282D01*
X160892Y108376D01*
Y111275D01*
X161392Y111775D01*
X163518D01*
X164642Y112899D01*
Y115098D01*
X164032Y115708D01*
X159652D01*
X159042Y116318D01*
Y117708D01*
X159652Y118318D01*
X164032D01*
X164642Y118928D01*
Y120318D01*
X164032Y120928D01*
X159652D01*
X159042Y121538D01*
Y122928D01*
X159652Y123538D01*
X164032D01*
X164642Y124148D01*
Y125538D01*
X164032Y126148D01*
X159652D01*
X159042Y126758D01*
Y128148D01*
X159652Y128758D01*
X164032D01*
X164642Y129368D01*
Y145100D01*
X242092Y222550D01*
Y227354D01*
X258409Y243671D01*
G01X123620Y54957D02*
X122692Y54029D01*
Y50901D01*
X125492Y48101D01*
Y46232D01*
X124109Y44849D01*
Y43450D01*
X125559Y42000D01*
Y40800D01*
X124059Y39300D01*
Y38101D01*
X125492Y36668D01*
Y34788D01*
X126580Y33700D01*
G01X123620Y54957D02*
Y59128D01*
X125492Y61000D01*
Y66300D01*
X124592Y67200D01*
Y72100D01*
X125492Y73000D01*
Y85700D01*
X124792Y86400D01*
Y91200D01*
X125492Y91900D01*
Y146500D01*
X210992Y232000D01*
X212042D01*
X255442Y275400D01*
X265039D01*
X266178Y274261D01*
G01X126666Y49914D02*
X124680Y51900D01*
Y53318D01*
X127892Y56530D01*
Y66500D01*
X128392Y67000D01*
Y72300D01*
X128292Y72400D01*
Y86200D01*
X128492Y86400D01*
Y146550D01*
X211392Y229450D01*
X212492D01*
X254692Y271650D01*
X265411D01*
X266290Y272529D01*
G01X147045Y54957D02*
X146117Y54029D01*
Y50901D01*
X149159Y47859D01*
Y46474D01*
X147484Y44799D01*
Y43676D01*
X148984Y42176D01*
Y40824D01*
X147484Y39324D01*
Y38101D01*
X148917Y36668D01*
Y35574D01*
X150391Y34100D01*
G01X147045Y54957D02*
Y57183D01*
X149080Y59218D01*
Y66303D01*
X148480Y66903D01*
Y72487D01*
X149280Y73287D01*
Y85718D01*
X148480Y86518D01*
Y91218D01*
X148880Y91618D01*
Y111738D01*
X150792Y113650D01*
Y119341D01*
X150182Y119951D01*
X147952D01*
X147342Y120561D01*
Y121951D01*
X147952Y122561D01*
X150182D01*
X150792Y123171D01*
Y124561D01*
X150182Y125171D01*
X147952D01*
X147342Y125781D01*
Y127171D01*
X147952Y127781D01*
X150182D01*
X150792Y128391D01*
Y129781D01*
X150182Y130391D01*
X147952D01*
X147342Y131001D01*
Y132391D01*
X147952Y133001D01*
X150182D01*
X150792Y133611D01*
Y135001D01*
X150182Y135611D01*
X148052D01*
X147442Y136221D01*
Y137611D01*
X148052Y138221D01*
X150182D01*
X150792Y138831D01*
Y142774D01*
X167747Y159729D01*
Y160591D01*
X165219Y163119D01*
Y163827D01*
X166357Y164965D01*
X167065D01*
X169593Y162437D01*
X170455D01*
X171439Y163421D01*
Y164283D01*
X168886Y166836D01*
Y167544D01*
X170024Y168682D01*
X170732D01*
X173285Y166129D01*
X174147D01*
X175301Y167283D01*
Y167991D01*
X172896Y170396D01*
Y171104D01*
X217692Y215900D01*
X220010D01*
X224076Y219966D01*
X226958D01*
X229676Y222684D01*
Y225566D01*
X253695Y249585D01*
G01X150391Y49914D02*
X148580Y51725D01*
Y53558D01*
X150030Y55008D01*
Y56632D01*
X151580Y58182D01*
Y66153D01*
X152680Y67253D01*
Y72111D01*
X151780Y73011D01*
Y85718D01*
X152580Y86518D01*
Y91018D01*
X151392Y92206D01*
Y110250D01*
X152942Y111800D01*
Y141388D01*
X180392Y168838D01*
Y169700D01*
X178948Y171144D01*
Y172006D01*
X179932Y172990D01*
X180794D01*
X182238Y171546D01*
X183100D01*
X184084Y172530D01*
Y173392D01*
X182640Y174836D01*
Y175698D01*
X183624Y176682D01*
X184486D01*
X185930Y175238D01*
X186792D01*
X187776Y176222D01*
Y177084D01*
X186332Y178528D01*
Y179390D01*
X187316Y180374D01*
X188178D01*
X189622Y178930D01*
X190484D01*
X191468Y179914D01*
Y180776D01*
X190024Y182220D01*
Y183082D01*
X191008Y184066D01*
X191870D01*
X193314Y182622D01*
X194176D01*
X195160Y183606D01*
Y184468D01*
X193716Y185912D01*
Y186774D01*
X194700Y187758D01*
X195562D01*
X197006Y186314D01*
X197868D01*
X199532Y187978D01*
Y189810D01*
X197721Y191621D01*
Y192329D01*
X217442Y212050D01*
X224992D01*
X235529Y222587D01*
Y227863D01*
X255673Y248007D01*
G01X167124Y54957D02*
X166003Y53836D01*
Y50900D01*
X168903Y48000D01*
Y46032D01*
X167370Y44499D01*
Y43300D01*
X168620Y42050D01*
Y41150D01*
X167270Y39800D01*
Y38501D01*
X168903Y36868D01*
Y34567D01*
X169770Y33700D01*
G01X167124Y54957D02*
Y62831D01*
X168991Y64698D01*
Y66251D01*
X167841Y67401D01*
Y72149D01*
X169191Y73499D01*
Y85368D01*
X167841Y86718D01*
Y90998D01*
X169182Y92339D01*
Y94990D01*
X170392Y96200D01*
Y106400D01*
X172892Y108900D01*
Y128651D01*
X175042Y130801D01*
Y136050D01*
X176092Y137100D01*
X180392D01*
X180992Y137700D01*
Y139040D01*
X180382Y139650D01*
X176052D01*
X175442Y140260D01*
Y141890D01*
X176052Y142500D01*
X180382D01*
X180992Y143110D01*
Y149636D01*
X250342Y218986D01*
Y223586D01*
X261299Y234543D01*
X262082D01*
X263924Y236385D01*
G01X169770Y49914D02*
X167892Y51792D01*
Y53199D01*
X169191Y54498D01*
Y60766D01*
X171691Y63266D01*
Y92964D01*
X172892Y96164D01*
Y104600D01*
X175392Y107100D01*
Y126851D01*
X179362Y130821D01*
Y131683D01*
X178276Y132770D01*
Y133632D01*
X179260Y134616D01*
X180122D01*
X181208Y133529D01*
X182070D01*
X183042Y134501D01*
Y148150D01*
X252842Y217950D01*
Y222550D01*
X262567Y232275D01*
X263364D01*
X264964Y233875D01*
G01X141880Y52314D02*
X143706Y54140D01*
Y56286D01*
X143192Y56800D01*
X141892D01*
X141235Y57457D01*
Y59176D01*
X144960Y62901D01*
Y97250D01*
X146642Y98932D01*
Y102400D01*
X144960Y104082D01*
Y108600D01*
X146342Y109982D01*
Y114568D01*
X144960Y115950D01*
Y134047D01*
X143468Y135539D01*
X141944D01*
X141072Y136411D01*
Y138907D01*
X141944Y139779D01*
X143471D01*
X144960Y141268D01*
Y143101D01*
X142705Y145356D01*
Y146062D01*
X143822Y147178D01*
X145758Y149115D01*
X154057D01*
X160642Y155700D01*
Y163100D01*
X215942Y218400D01*
X218592D01*
X244092Y243900D01*
Y245230D01*
X245420Y246558D01*
X246056D01*
X247011Y247513D01*
Y248149D01*
X247965Y249103D01*
X248601D01*
X249556Y250058D01*
Y250694D01*
X250509Y251647D01*
X251145D01*
X252100Y252602D01*
Y253238D01*
X253053Y254191D01*
X253689D01*
X254644Y255146D01*
Y255782D01*
X255598Y256736D01*
X256234D01*
X257189Y257691D01*
Y258327D01*
X258142Y259280D01*
X261755D01*
G01X136780Y52100D02*
X138556Y53876D01*
Y55850D01*
X137706Y56700D01*
X136706D01*
X135986Y57420D01*
Y59488D01*
X139860Y63362D01*
Y77580D01*
X140480Y78200D01*
Y79200D01*
X139860Y79820D01*
Y80580D01*
X140480Y81200D01*
Y82200D01*
X139860Y82820D01*
Y93480D01*
X140480Y94100D01*
Y95100D01*
X139860Y95720D01*
Y109463D01*
X137672Y111651D01*
Y113481D01*
X141072Y116881D01*
Y119763D01*
X139283Y121552D01*
X138144D01*
X137272Y122424D01*
Y124920D01*
X138144Y125792D01*
X139283D01*
X140772Y127281D01*
Y130663D01*
X137272Y134163D01*
Y145329D01*
X141472Y149528D01*
X145393Y153450D01*
X153093D01*
X156318Y156675D01*
Y164375D01*
X214193Y222250D01*
X215941D01*
X218704Y225013D01*
X219340D01*
X220295Y225968D01*
Y226604D01*
X221248Y227557D01*
X221884D01*
X222839Y228512D01*
Y229148D01*
X223793Y230102D01*
X224429D01*
X225384Y231057D01*
Y231693D01*
X226337Y232646D01*
X226973D01*
X227928Y233601D01*
Y234237D01*
X228882Y235191D01*
X229518D01*
X230473Y236146D01*
Y236782D01*
X231426Y237735D01*
X232062D01*
X233017Y238690D01*
Y239326D01*
X233971Y240280D01*
X234607D01*
X235562Y241235D01*
Y241871D01*
X236515Y242824D01*
X237151D01*
X238106Y243779D01*
Y244415D01*
X239060Y245369D01*
X239696D01*
X240651Y246324D01*
Y246960D01*
X241604Y247913D01*
X242240D01*
X243195Y248868D01*
Y249504D01*
X244149Y250458D01*
X244785D01*
X245740Y251413D01*
Y252049D01*
X246693Y253002D01*
X247329D01*
X248284Y253957D01*
Y254593D01*
X249238Y255547D01*
X249874D01*
X250829Y256502D01*
Y257138D01*
X251782Y258091D01*
X252418D01*
X253373Y259046D01*
Y259682D01*
X254327Y260636D01*
X254963D01*
X255918Y261591D01*
Y262227D01*
X256871Y263180D01*
X258392D01*
G01X141880Y49714D02*
X140175Y51419D01*
Y59616D01*
X143900Y63341D01*
Y97690D01*
X145582Y99372D01*
Y101960D01*
X143900Y103642D01*
Y109040D01*
X145282Y110422D01*
Y114128D01*
X143900Y115510D01*
Y133607D01*
X143028Y134479D01*
X141501D01*
X140012Y135968D01*
Y139350D01*
X141501Y140839D01*
X143028D01*
X143900Y141711D01*
Y142661D01*
X141645Y144916D01*
Y146502D01*
X143072Y147928D01*
X145318Y150175D01*
X153617D01*
X159582Y156140D01*
Y163540D01*
X215502Y219460D01*
X218152D01*
X243032Y244340D01*
Y245670D01*
X257702Y260340D01*
X261755D01*
G01X141880Y33149D02*
X142989D01*
X144012Y34172D01*
Y36793D01*
X143305Y37500D01*
X142507D01*
X141906Y38101D01*
Y39299D01*
X142507Y39900D01*
X143205D01*
X144012Y40707D01*
Y42080D01*
X143292Y42800D01*
X142792D01*
X142112Y43480D01*
Y44520D01*
X142792Y45200D01*
X143306D01*
X144012Y45906D01*
Y48681D01*
X142978Y49715D01*
X141880D01*
Y49714D01*
G01X136780Y49500D02*
X134926Y51354D01*
Y59928D01*
X138800Y63802D01*
Y109020D01*
X136612Y111208D01*
Y113924D01*
X140012Y117324D01*
Y119320D01*
X138840Y120492D01*
X137701D01*
X136212Y121981D01*
Y125363D01*
X137701Y126852D01*
X138840D01*
X139712Y127724D01*
Y130223D01*
X136212Y133723D01*
Y145769D01*
X140722Y150278D01*
X144953Y154510D01*
X152653D01*
X155258Y157115D01*
Y164815D01*
X213753Y223310D01*
X215501D01*
X256431Y264240D01*
X258392D01*
G01X130313Y555957D02*
Y555891D01*
X129350Y554928D01*
Y551398D01*
X132166Y548582D01*
Y546974D01*
X131992Y546800D01*
Y538074D01*
X132166Y537900D01*
Y536475D01*
X131066Y535375D01*
Y530581D01*
X132366Y529281D01*
Y528274D01*
X131192Y527100D01*
Y520674D01*
X132366Y519500D01*
Y517774D01*
X131066Y516474D01*
Y511952D01*
X131963Y511055D01*
Y509272D01*
X130466Y507775D01*
Y456325D01*
X140191Y446600D01*
X143791D01*
X165791Y424600D01*
X170191D01*
X214143Y380648D01*
Y362850D01*
X249613Y327380D01*
X259088D01*
G01X132959Y550914D02*
Y550564D01*
X134866Y548657D01*
Y546826D01*
X135392Y546300D01*
Y538226D01*
X134866Y537700D01*
Y528626D01*
X136592Y526900D01*
Y525748D01*
X135982Y525138D01*
X134202D01*
X133492Y524428D01*
Y522448D01*
X134002Y521938D01*
X135982D01*
X136592Y521328D01*
Y520400D01*
X134866Y518674D01*
Y509170D01*
X132992Y507296D01*
Y456499D01*
X133651Y455840D01*
X134441Y455841D01*
X136999Y458399D01*
X137791D01*
X138810Y457380D01*
X138811Y456588D01*
X136253Y454030D01*
Y453238D01*
X137273Y452218D01*
X138063Y452219D01*
X140621Y454777D01*
X141413D01*
X142392Y453798D01*
Y450599D01*
X166291Y426700D01*
X170791D01*
X216028Y381463D01*
Y364501D01*
X250649Y329880D01*
X259208D01*
G01X153738Y555957D02*
X152380Y554599D01*
Y552107D01*
X155780Y548707D01*
Y547388D01*
X155392Y547000D01*
Y538190D01*
X155780Y537802D01*
Y536242D01*
X154880Y535342D01*
Y530319D01*
X155980Y529219D01*
Y527888D01*
X155414Y527322D01*
Y519566D01*
X155980Y519000D01*
Y517857D01*
X155180Y517057D01*
Y511657D01*
X155680Y511157D01*
Y508600D01*
X154692Y507612D01*
Y485300D01*
X155492Y484500D01*
X157092D01*
X157892Y485300D01*
Y493400D01*
X158692Y494200D01*
X160292D01*
X161092Y493400D01*
Y456100D01*
X161892Y455300D01*
X163492D01*
X164292Y456100D01*
Y464100D01*
X165092Y464900D01*
X166692D01*
X167492Y464100D01*
Y449407D01*
X180159Y436740D01*
Y433932D01*
X227573Y386518D01*
Y372885D01*
X252358Y348100D01*
G01X259818Y321780D02*
X248141D01*
X210373Y359548D01*
Y374807D01*
X209406Y377142D01*
X207466Y381825D01*
X174208Y415083D01*
X160647Y420700D01*
X125778Y455569D01*
Y510417D01*
X125537Y511000D01*
X125371Y511400D01*
X124766Y512861D01*
Y516130D01*
X125420Y517709D01*
Y529124D01*
X124666Y530946D01*
Y534890D01*
X125499Y536902D01*
Y548134D01*
X124516Y550508D01*
X123191Y551833D01*
Y555528D01*
X123620Y555957D01*
G01X259818Y324280D02*
X249177D01*
X212258Y361199D01*
Y379833D01*
X169491Y422600D01*
X165090D01*
X149613Y438077D01*
X148822D01*
X147764Y437019D01*
X146972D01*
X145952Y438039D01*
X145953Y438829D01*
X147011Y439887D01*
Y440679D01*
X145992Y441698D01*
X145200Y441699D01*
X144142Y440641D01*
X143350D01*
X142330Y441661D01*
X142331Y442451D01*
X142881Y443001D01*
Y443709D01*
X141870Y444720D01*
X140978Y444721D01*
X140520Y444263D01*
X139728D01*
X127966Y456025D01*
Y510952D01*
X128666Y511652D01*
Y516352D01*
X127692Y517326D01*
Y529193D01*
X128732Y530233D01*
Y535301D01*
X128166Y535867D01*
Y537500D01*
X128692Y538026D01*
Y546200D01*
X128166Y546726D01*
Y549414D01*
X126666Y550914D01*
G01X255448Y340941D02*
X253752D01*
X223803Y370890D01*
Y384788D01*
X175159Y433432D01*
Y434668D01*
X174312Y435515D01*
X173180D01*
X172544Y434879D01*
X171412D01*
X170281Y436010D01*
Y437142D01*
X170917Y437778D01*
Y438910D01*
X169786Y440041D01*
X168654D01*
X168018Y439405D01*
X166886D01*
X165755Y440536D01*
Y441668D01*
X166391Y442304D01*
Y443436D01*
X165260Y444567D01*
X164128D01*
X163492Y443931D01*
X162360D01*
X161229Y445062D01*
Y446194D01*
X161865Y446830D01*
Y447962D01*
X160734Y449093D01*
X159602D01*
X158966Y448457D01*
X157834D01*
X156703Y449588D01*
Y450720D01*
X157339Y451356D01*
Y452488D01*
X149692Y460135D01*
Y501044D01*
X148892Y501844D01*
X147292D01*
X146492Y501044D01*
Y496700D01*
X145692Y495900D01*
X144092D01*
X143292Y496700D01*
Y502399D01*
X148845Y507952D01*
Y511692D01*
X148480Y512057D01*
Y516957D01*
X149080Y517557D01*
Y519000D01*
X148692Y519388D01*
Y527600D01*
X149080Y527988D01*
Y529475D01*
X148007Y530548D01*
Y535169D01*
X149280Y536442D01*
Y537600D01*
X148714Y538166D01*
Y546822D01*
X149280Y547388D01*
Y548557D01*
X146380Y551457D01*
Y555292D01*
X147045Y555957D01*
G01X150391Y550914D02*
X151737Y549568D01*
X151780D01*
Y547012D01*
X152092Y546700D01*
Y538000D01*
X151780Y537688D01*
Y536411D01*
X152446Y535745D01*
Y530249D01*
X151880Y529683D01*
Y527912D01*
X152092Y527700D01*
Y519612D01*
X151580Y519100D01*
Y517657D01*
X152680Y516557D01*
Y512157D01*
X151780Y511257D01*
Y509200D01*
X152192Y508788D01*
Y482490D01*
X152752Y481930D01*
X158632D01*
X159192Y481370D01*
Y479930D01*
X158632Y479370D01*
X152752D01*
X152192Y478810D01*
Y477370D01*
X152752Y476810D01*
X158632D01*
X159192Y476250D01*
Y474810D01*
X158632Y474250D01*
X152752D01*
X152192Y473690D01*
Y472250D01*
X152752Y471690D01*
X158632D01*
X159192Y471130D01*
Y469690D01*
X158632Y469130D01*
X152752D01*
X152192Y468570D01*
Y467130D01*
X152752Y466570D01*
X158632D01*
X159192Y466010D01*
Y464570D01*
X158632Y464010D01*
X152752D01*
X152192Y463450D01*
Y461171D01*
X153028Y460335D01*
X155556D01*
X158492Y457399D01*
Y454871D01*
X160627Y452736D01*
X163356D01*
X164992Y451100D01*
Y448371D01*
X177659Y435704D01*
Y433632D01*
X225688Y385603D01*
Y372105D01*
X254352Y343441D01*
X255448D01*
G01X141880Y550714D02*
X142845D01*
X143900Y549659D01*
Y546920D01*
X143280Y546300D01*
Y545300D01*
X143900Y544680D01*
Y543680D01*
X143280Y543060D01*
Y542060D01*
X143900Y541440D01*
Y540440D01*
X143280Y539820D01*
Y538820D01*
X143900Y538200D01*
Y536424D01*
X143400Y535924D01*
Y534924D01*
X143900Y534424D01*
Y531267D01*
X143413Y530780D01*
Y529780D01*
X143900Y529293D01*
Y527920D01*
X143280Y527300D01*
Y526300D01*
X143900Y525680D01*
Y524680D01*
X143280Y524060D01*
Y523060D01*
X143900Y522440D01*
Y521440D01*
X143280Y520820D01*
Y519820D01*
X143900Y519200D01*
Y508579D01*
X142919Y507598D01*
X142041D01*
X141334Y506891D01*
Y506013D01*
X139512Y504191D01*
Y493309D01*
X141001Y491820D01*
X145201D01*
X145912Y491109D01*
Y488730D01*
X145040Y487858D01*
X140896D01*
X139434Y486396D01*
Y483814D01*
X140950Y482298D01*
X145040D01*
X145912Y481426D01*
Y479730D01*
X145040Y478858D01*
X141401D01*
X139912Y477369D01*
Y474787D01*
X141401Y473298D01*
X145040D01*
X145912Y472426D01*
Y468712D01*
X142948Y465748D01*
Y461416D01*
X152931Y451433D01*
Y448129D01*
X169220Y431840D01*
X172552D01*
X220858Y383534D01*
Y368834D01*
X252763Y336929D01*
X255384D01*
G01X136780Y553100D02*
X136809D01*
X139860Y550049D01*
Y546800D01*
X140480Y546180D01*
Y545180D01*
X139860Y544560D01*
Y543414D01*
X140334Y542940D01*
Y541940D01*
X139860Y541466D01*
Y509033D01*
X136672Y505845D01*
Y472336D01*
X137544Y471464D01*
X139885D01*
X141374Y469975D01*
Y467393D01*
X139885Y465904D01*
X137328D01*
X136672Y465248D01*
Y463752D01*
X150141Y450283D01*
Y447022D01*
X167363Y429800D01*
X171891D01*
X218973Y382718D01*
Y367189D01*
X252182Y333980D01*
X260505D01*
G01X141880Y553314D02*
X141916D01*
X144960Y550270D01*
Y508136D01*
X140572Y503748D01*
Y493749D01*
X141441Y492880D01*
X145641D01*
X146972Y491549D01*
Y488290D01*
X145480Y486798D01*
X141336D01*
X140494Y485956D01*
Y484254D01*
X141390Y483358D01*
X145480D01*
X146972Y481866D01*
Y479287D01*
X145483Y477798D01*
X141844D01*
X140972Y476926D01*
Y475230D01*
X141844Y474358D01*
X145480D01*
X146972Y472866D01*
Y468272D01*
X144008Y465308D01*
Y461856D01*
X153991Y451873D01*
Y448569D01*
X169660Y432900D01*
X172992D01*
X221918Y383974D01*
Y369274D01*
X253203Y337989D01*
X255384D01*
G01X136780Y550500D02*
X137761D01*
X138800Y549461D01*
Y509473D01*
X135612Y506285D01*
Y471896D01*
X137104Y470404D01*
X139445D01*
X140314Y469535D01*
Y467836D01*
X139442Y466964D01*
X136888D01*
X135612Y465688D01*
Y463312D01*
X149081Y449843D01*
Y446582D01*
X166923Y428740D01*
X171451D01*
X217913Y382278D01*
Y366749D01*
X251742Y332920D01*
X260505D01*
G01X160431Y555957D02*
X160051Y555577D01*
Y550947D01*
X162341Y548657D01*
Y536142D01*
X161642Y535443D01*
Y530150D01*
X162391Y529401D01*
Y517451D01*
X161669Y516729D01*
Y511579D01*
X162598Y510650D01*
Y501194D01*
X173992Y489800D01*
Y452100D01*
X209292Y416800D01*
Y411840D01*
X233492Y387640D01*
Y377700D01*
X251592Y359600D01*
X252428D01*
X255287Y356741D01*
G01X163477Y550914D02*
X164991Y549400D01*
Y547001D01*
X166492Y545500D01*
Y539001D01*
X164991Y537500D01*
Y535456D01*
X165591Y534856D01*
Y530697D01*
X164693Y529799D01*
Y525713D01*
X165303Y525103D01*
X166470D01*
X167080Y524493D01*
Y523103D01*
X166470Y522493D01*
X165303D01*
X164693Y521883D01*
Y517855D01*
X165292Y517256D01*
Y511400D01*
X164992Y511100D01*
Y508025D01*
X165602Y507415D01*
X167105D01*
X167715Y506805D01*
Y505415D01*
X167105Y504805D01*
X165602D01*
X164992Y504195D01*
Y502700D01*
X176592Y491100D01*
Y452200D01*
X211177Y417615D01*
Y412621D01*
X235377Y388421D01*
Y380187D01*
X256948Y358616D01*
G01X253108Y350017D02*
X229458Y373667D01*
Y387417D01*
X196394Y420481D01*
Y421343D01*
X197341Y422290D01*
Y423152D01*
X195940Y424553D01*
X195078D01*
X194131Y423606D01*
X193269D01*
X191868Y425007D01*
Y425869D01*
X192815Y426816D01*
Y427678D01*
X191414Y429079D01*
X190552D01*
X189605Y428132D01*
X188743D01*
X187342Y429533D01*
Y430395D01*
X188289Y431342D01*
Y432204D01*
X186888Y433605D01*
X186026D01*
X185079Y432658D01*
X184217D01*
X182692Y434183D01*
Y437743D01*
X169992Y450443D01*
Y487900D01*
X169192Y488700D01*
X167592D01*
X166792Y487900D01*
Y468200D01*
X165992Y467400D01*
X164392D01*
X163592Y468200D01*
Y494543D01*
X158592Y499543D01*
Y511101D01*
X159492Y512001D01*
Y516099D01*
X158192Y517399D01*
Y519700D01*
X158792Y520300D01*
Y527700D01*
X158154Y528338D01*
Y529471D01*
X159380Y530697D01*
Y535612D01*
X158008Y536984D01*
Y538316D01*
X158792Y539100D01*
Y546300D01*
X158292Y546800D01*
Y549758D01*
X157084Y550966D01*
Y550914D01*
G01X167124Y555957D02*
X165691Y554524D01*
Y552007D01*
X169041Y548657D01*
Y547149D01*
X168792Y546900D01*
Y538249D01*
X169041Y538000D01*
Y536449D01*
X167822Y535230D01*
Y530636D01*
X168991Y529467D01*
Y528099D01*
X168792Y527900D01*
Y519599D01*
X168992Y519399D01*
Y517458D01*
X167841Y516307D01*
Y511851D01*
X169836Y509856D01*
Y501756D01*
X179092Y492500D01*
Y462868D01*
X179976Y461984D01*
Y461024D01*
X179092Y460140D01*
Y452400D01*
X213062Y418430D01*
Y413402D01*
X237262Y389202D01*
Y381838D01*
X258459Y360641D01*
G01X130313Y555957D02*
X128608Y557662D01*
Y569315D01*
X131793Y572500D01*
X132959D01*
G01X163391D02*
X162403D01*
X159348Y569445D01*
Y568257D01*
X158726Y567635D01*
Y557662D01*
X160431Y555957D01*
G01X163477Y550914D02*
X163389D01*
X161703Y552600D01*
Y554800D01*
X162203Y555300D01*
Y557199D01*
X161066Y558336D01*
Y559664D01*
X162003Y560601D01*
Y561999D01*
X161066Y562936D01*
Y564164D01*
X162103Y565201D01*
Y566099D01*
X161503Y566699D01*
X160431D01*
G01X132959Y550914D02*
X132871D01*
X131185Y552600D01*
Y554292D01*
X132092Y555199D01*
Y556792D01*
X130948Y557936D01*
Y559356D01*
X131792Y560200D01*
Y561900D01*
X130948Y562744D01*
Y563956D01*
X131892Y564900D01*
Y566100D01*
X131293Y566699D01*
X130313D01*
G01X153738Y555957D02*
X152033Y557662D01*
Y567849D01*
X157084Y572900D01*
G01X153738Y566699D02*
X154810D01*
X155510Y565999D01*
Y564725D01*
X154373Y563588D01*
Y562512D01*
X155385Y561500D01*
Y560300D01*
X154373Y559288D01*
Y558212D01*
X155485Y557100D01*
Y554467D01*
X155310Y554292D01*
Y552600D01*
X156996Y550914D01*
X157084D01*
G01X123620Y555957D02*
X121915Y557662D01*
Y567835D01*
X126580Y572500D01*
G01X126666Y550914D02*
X126578D01*
X124892Y552600D01*
Y554800D01*
X125392Y555300D01*
Y557199D01*
X124255Y558336D01*
Y559664D01*
X125192Y560601D01*
Y561999D01*
X124255Y562936D01*
Y564164D01*
X125292Y565201D01*
Y566099D01*
X124692Y566699D01*
X123620D01*
G01X150391Y572900D02*
X145340Y567849D01*
Y557662D01*
X147045Y555957D01*
G01Y566699D02*
X148117D01*
X148817Y565999D01*
Y564725D01*
X147680Y563588D01*
Y562512D01*
X148692Y561500D01*
Y560300D01*
X147680Y559288D01*
Y558212D01*
X148792Y557100D01*
Y554467D01*
X148617Y554292D01*
Y552600D01*
X150303Y550914D01*
X150391D01*
G01X169770Y572500D02*
X168604D01*
X165419Y569315D01*
Y557662D01*
X167124Y555957D01*
G01Y566699D02*
X168104D01*
X168703Y566100D01*
Y564900D01*
X167759Y563956D01*
Y562744D01*
X168603Y561900D01*
Y560200D01*
X167759Y559356D01*
Y557936D01*
X168903Y556792D01*
Y555199D01*
X167996Y554292D01*
Y552600D01*
X169682Y550914D01*
X169770D01*
G01X141880Y550714D02*
X141592D01*
X140175Y552131D01*
Y557100D01*
X139345Y557930D01*
Y564470D01*
X140175Y565300D01*
Y570244D01*
X141880Y571949D01*
G01X136780Y553100D02*
X138492Y554812D01*
Y556400D01*
X137392Y557500D01*
X136442D01*
X135852Y558090D01*
Y559460D01*
X136372Y559980D01*
X136982D01*
X137592Y560590D01*
Y561980D01*
X136982Y562590D01*
X136402D01*
X135852Y563140D01*
Y564560D01*
X136492Y565200D01*
X137772D01*
X138511Y565939D01*
Y567845D01*
X136806Y569550D01*
G01X141880Y553314D02*
X143592Y555026D01*
Y556700D01*
X142592Y557700D01*
X141076D01*
X140405Y558371D01*
Y559648D01*
X140857Y560100D01*
X141192D01*
X141890Y560798D01*
Y561890D01*
X141182Y562598D01*
X140945D01*
X140405Y563138D01*
Y564029D01*
X141176Y564800D01*
X142692D01*
X143692Y565800D01*
Y567528D01*
X141880Y569340D01*
G01X136780Y550500D02*
X136492D01*
X134792Y552200D01*
Y570211D01*
X136780Y572199D01*
G01X190549Y27899D02*
X191796Y29146D01*
Y30400D01*
X193096Y31700D01*
X194096D01*
X195896Y33500D01*
Y34900D01*
X195284Y35512D01*
Y48525D01*
X193895Y49914D01*
G01X187202D02*
X188591Y48525D01*
Y35512D01*
X189203Y34900D01*
Y33500D01*
X187403Y31700D01*
X186403D01*
X185103Y30400D01*
Y29146D01*
X183856Y27899D01*
G01X203935D02*
Y30021D01*
X205814Y31900D01*
X207214D01*
X208670Y33356D01*
Y34700D01*
X208054Y35316D01*
Y48441D01*
X206581Y49914D01*
G01X227360Y27899D02*
X228607Y29146D01*
Y30400D01*
X229907Y31700D01*
X230907D01*
X232707Y33500D01*
Y34900D01*
X232095Y35512D01*
Y48525D01*
X230706Y49914D01*
G01X197242Y27899D02*
Y29453D01*
X199489Y31700D01*
X200713D01*
X202289Y33276D01*
Y34900D01*
X201514Y35675D01*
Y48688D01*
X200288Y49914D01*
G01X220667Y27899D02*
X221914Y29146D01*
Y30400D01*
X223214Y31700D01*
X224214D01*
X226014Y33500D01*
Y34900D01*
X225402Y35512D01*
Y48525D01*
X224013Y49914D01*
G01X173591Y52100D02*
X176697Y48994D01*
Y32848D01*
X175369Y31520D01*
X174387D01*
X173617Y30750D01*
G01X210402Y52100D02*
X213508Y48994D01*
Y32848D01*
X212180Y31520D01*
X211198D01*
X210428Y30750D01*
G01X178691Y52314D02*
X181883Y49122D01*
Y33732D01*
X178691Y30540D01*
G01X215502Y52314D02*
X218694Y49122D01*
Y33732D01*
X215502Y30540D01*
G01X173591Y49500D02*
X174690D01*
X175637Y48553D01*
Y46020D01*
X174667Y45050D01*
X174319D01*
X173703Y44434D01*
Y43102D01*
X174205Y42600D01*
X174917D01*
X175637Y41880D01*
Y40920D01*
X174817Y40100D01*
X174317D01*
X173717Y39500D01*
Y38500D01*
X175637Y36580D01*
Y33291D01*
X174926Y32580D01*
X174410D01*
X173591Y33399D01*
G01X210402Y49500D02*
X211501D01*
X212448Y48553D01*
Y46020D01*
X211478Y45050D01*
X211130D01*
X210514Y44434D01*
Y43102D01*
X211016Y42600D01*
X211728D01*
X212448Y41880D01*
Y40920D01*
X211628Y40100D01*
X211128D01*
X210528Y39500D01*
Y38500D01*
X212448Y36580D01*
Y33291D01*
X211737Y32580D01*
X211221D01*
X210402Y33399D01*
G01X275397Y215000D02*
X271092D01*
X265692Y209600D01*
Y209037D01*
X235992Y179337D01*
Y164900D01*
X233460Y162368D01*
X232598D01*
X229360Y165606D01*
X228498D01*
X227514Y164622D01*
Y163760D01*
X230752Y160522D01*
Y159660D01*
X229768Y158676D01*
X228906D01*
X226719Y160863D01*
X225857D01*
X224873Y159879D01*
Y159017D01*
X227060Y156830D01*
Y155968D01*
X226076Y154984D01*
X225214D01*
X223027Y157171D01*
X222165D01*
X221181Y156187D01*
Y155325D01*
X223368Y153138D01*
Y152276D01*
X222384Y151292D01*
X221522D01*
X219335Y153479D01*
X218473D01*
X217489Y152495D01*
Y151633D01*
X219676Y149446D01*
Y148584D01*
X218692Y147600D01*
X217830D01*
X215643Y149787D01*
X214781D01*
X213797Y148803D01*
Y147941D01*
X215984Y145754D01*
Y144892D01*
X190492Y119400D01*
Y95548D01*
X192366Y93674D01*
Y91593D01*
X191891Y91118D01*
Y86418D01*
X192491Y85818D01*
Y73099D01*
X191991Y72599D01*
Y66803D01*
X192392Y66402D01*
Y64800D01*
X190549Y62957D01*
Y54957D01*
G01D02*
X189428Y53836D01*
Y50900D01*
X192770Y47558D01*
Y46500D01*
X190970Y44700D01*
Y43125D01*
X192170Y41925D01*
Y40799D01*
X190970Y39599D01*
Y38226D01*
X192328Y36868D01*
Y35667D01*
X193895Y34100D01*
G01Y49914D02*
X191991Y51818D01*
Y53418D01*
X193482Y54909D01*
Y62241D01*
X195341Y64100D01*
Y66503D01*
X195891Y67053D01*
Y72401D01*
X195291Y73001D01*
Y85918D01*
X195991Y86618D01*
Y91018D01*
X195341Y91668D01*
Y99920D01*
X194841Y100420D01*
X193602D01*
X192992Y101030D01*
Y102420D01*
X193602Y103030D01*
X195232D01*
X195842Y103640D01*
Y105030D01*
X195232Y105640D01*
X193602D01*
X192992Y106250D01*
Y107640D01*
X193602Y108250D01*
X196082D01*
X196692Y108860D01*
Y110250D01*
X196082Y110860D01*
X193602D01*
X192992Y111470D01*
Y112860D01*
X193602Y113470D01*
X195792D01*
X196292Y113970D01*
Y115580D01*
X195792Y116080D01*
X193602D01*
X192992Y116690D01*
Y118850D01*
X197101Y122959D01*
X197963D01*
X199226Y121696D01*
X200088D01*
X201072Y122680D01*
Y123542D01*
X199809Y124805D01*
Y125667D01*
X200793Y126651D01*
X201655D01*
X202918Y125388D01*
X203780D01*
X204764Y126372D01*
Y127234D01*
X203501Y128497D01*
Y129359D01*
X238542Y164400D01*
Y178351D01*
X241146Y180955D01*
X242008D01*
X243220Y179742D01*
X244082D01*
X245066Y180726D01*
Y181588D01*
X243854Y182801D01*
Y183663D01*
X244838Y184647D01*
X245700D01*
X246912Y183434D01*
X247774D01*
X248758Y184418D01*
Y185280D01*
X247546Y186493D01*
Y187355D01*
X251692Y191501D01*
Y191590D01*
X252302Y192200D01*
X253392D01*
X270192Y209000D01*
X271692D01*
X273692Y211000D01*
X275292D01*
X277092Y212800D01*
X278392D01*
X279792Y214200D01*
Y215365D01*
X279799Y215372D01*
G01X272608Y220111D02*
X269513D01*
X216237Y166835D01*
Y165973D01*
X219570Y162640D01*
Y161778D01*
X218586Y160794D01*
X217724D01*
X214391Y164127D01*
X213529D01*
X212545Y163143D01*
Y162281D01*
X215878Y158948D01*
Y158086D01*
X214894Y157102D01*
X214032D01*
X210699Y160435D01*
X209837D01*
X208853Y159451D01*
Y158589D01*
X212186Y155256D01*
Y154394D01*
X211202Y153410D01*
X210340D01*
X207007Y156743D01*
X206145D01*
X204492Y155090D01*
Y153150D01*
X207199Y150443D01*
Y144757D01*
X185492Y123050D01*
Y93999D01*
X185691Y93800D01*
Y91618D01*
X185291Y91218D01*
Y86518D01*
X186091Y85718D01*
Y73499D01*
X185291Y72699D01*
Y66903D01*
X185891Y66303D01*
Y59218D01*
X183856Y57183D01*
Y54957D01*
G01D02*
X182928Y54029D01*
Y50901D01*
X185970Y47859D01*
Y46474D01*
X184295Y44799D01*
Y43676D01*
X185795Y42176D01*
Y40824D01*
X184295Y39324D01*
Y38101D01*
X185728Y36668D01*
Y35574D01*
X187202Y34100D01*
G01X272608Y217611D02*
X270702D01*
X231749Y178658D01*
Y177796D01*
X233812Y175734D01*
Y174872D01*
X232828Y173888D01*
X231966D01*
X230353Y175500D01*
X229903Y175950D01*
X229041D01*
X228057Y174966D01*
Y174104D01*
X230120Y172042D01*
Y171180D01*
X229136Y170196D01*
X228274D01*
X226211Y172258D01*
X225349D01*
X224365Y171274D01*
Y170412D01*
X226428Y168350D01*
Y167488D01*
X225444Y166504D01*
X224582D01*
X222519Y168566D01*
X221657D01*
X219983Y166892D01*
Y165659D01*
X223015Y162627D01*
Y161495D01*
X211756Y150236D01*
Y145114D01*
X187992Y121350D01*
Y93499D01*
X188691Y92800D01*
Y91718D01*
X189391Y91018D01*
Y86518D01*
X188591Y85718D01*
Y73101D01*
X189491Y72201D01*
Y67253D01*
X188391Y66153D01*
Y58182D01*
X185866Y55657D01*
Y54145D01*
X185391Y53670D01*
Y51725D01*
X187202Y49914D01*
G01X260786Y187856D02*
X259742Y186812D01*
Y183961D01*
X247492Y171711D01*
Y161337D01*
X228048Y141893D01*
Y137757D01*
X226190Y135899D01*
X225327D01*
X224380Y136846D01*
X223588D01*
X222534Y135792D01*
Y135000D01*
X223482Y134052D01*
Y133191D01*
X222498Y132207D01*
X221636D01*
X220224Y133618D01*
X219362D01*
X218378Y132634D01*
Y131772D01*
X219790Y130361D01*
Y129499D01*
X218806Y128515D01*
X217943D01*
X216979Y129479D01*
X216271D01*
X215133Y128341D01*
Y127633D01*
X216098Y126668D01*
Y125807D01*
X207392Y117101D01*
Y105036D01*
X203702Y101346D01*
Y96090D01*
X205892Y93900D01*
Y92200D01*
X204652Y90960D01*
Y86718D01*
X206002Y85368D01*
Y73409D01*
X204652Y72059D01*
Y67417D01*
X205802Y66267D01*
Y64710D01*
X203935Y62843D01*
Y54957D01*
G01D02*
X202814Y53836D01*
Y50900D01*
X205714Y48000D01*
Y46032D01*
X204181Y44499D01*
Y43300D01*
X205431Y42050D01*
Y41150D01*
X204081Y39800D01*
Y38501D01*
X205714Y36868D01*
Y34567D01*
X206581Y33700D01*
G01Y49914D02*
X204508Y51987D01*
Y53116D01*
X206002Y54610D01*
Y61610D01*
X208502Y64110D01*
Y95744D01*
X206642Y97604D01*
Y99804D01*
X209592Y102754D01*
Y115949D01*
X231116Y137473D01*
Y141425D01*
X249992Y160301D01*
Y170675D01*
X262544Y183227D01*
Y186099D01*
G01X283417Y184392D02*
X281942Y182917D01*
Y181120D01*
X269392Y168570D01*
Y142700D01*
X262629Y135937D01*
X261767D01*
X260779Y136925D01*
X259917D01*
X258933Y135941D01*
Y135079D01*
X259921Y134091D01*
Y133229D01*
X258937Y132245D01*
X258075D01*
X257087Y133233D01*
X256225D01*
X255241Y132249D01*
Y131387D01*
X256229Y130399D01*
Y129537D01*
X255245Y128553D01*
X254383D01*
X253710Y129226D01*
X252918D01*
X251864Y128172D01*
Y127380D01*
X252537Y126707D01*
Y125845D01*
X250292Y123600D01*
X237816D01*
X229652Y115436D01*
Y92068D01*
X228702Y91118D01*
Y86418D01*
X229302Y85818D01*
Y73111D01*
X228802Y72611D01*
Y66803D01*
X229602Y66003D01*
Y58411D01*
X227360Y56169D01*
Y54957D01*
G01D02*
X226239Y53836D01*
Y50900D01*
X229581Y47558D01*
Y46500D01*
X227781Y44700D01*
Y43125D01*
X228981Y41925D01*
Y40799D01*
X227781Y39599D01*
Y38226D01*
X229139Y36868D01*
Y35667D01*
X230706Y34100D01*
G01Y49914D02*
X228802Y51818D01*
Y53418D01*
X232152Y56768D01*
Y66503D01*
X232702Y67053D01*
Y72491D01*
X232102Y73091D01*
Y85918D01*
X232802Y86618D01*
Y91018D01*
X232152Y91668D01*
Y114400D01*
X235531Y117779D01*
X242273D01*
X242883Y118389D01*
Y120690D01*
X243493Y121300D01*
X244883D01*
X245493Y120690D01*
Y118389D01*
X246103Y117779D01*
X247771D01*
X272792Y142800D01*
Y168434D01*
X285119Y180761D01*
Y182551D01*
G01X255292Y190501D02*
Y186583D01*
X242492Y173783D01*
Y163409D01*
X208192Y129109D01*
Y125065D01*
X201782Y118655D01*
X200252D01*
X199642Y118045D01*
Y116655D01*
X200252Y116045D01*
X201782D01*
X202392Y115435D01*
Y114045D01*
X201782Y113435D01*
X200602D01*
X200042Y112875D01*
Y111385D01*
X200602Y110825D01*
X201782D01*
X202392Y110215D01*
Y108764D01*
X198892Y105264D01*
Y93900D01*
X199202Y93590D01*
Y92118D01*
X198302Y91218D01*
Y86418D01*
X199302Y85418D01*
Y82490D01*
X200592Y81200D01*
Y77190D01*
X199302Y75900D01*
Y73103D01*
X198302Y72103D01*
Y67191D01*
X199202Y66291D01*
Y63710D01*
X197242Y61750D01*
Y59450D01*
X198276Y58416D01*
Y57283D01*
X197242Y56249D01*
Y54957D01*
G01D02*
X196314Y54029D01*
Y50901D01*
X199114Y48101D01*
Y46232D01*
X197731Y44849D01*
Y43450D01*
X199181Y42000D01*
Y40800D01*
X197681Y39300D01*
Y38101D01*
X199114Y36668D01*
Y34788D01*
X200202Y33700D01*
G01X200288Y49914D02*
X198302Y51900D01*
Y53318D01*
X200922Y55938D01*
Y59170D01*
X199992Y60100D01*
Y61356D01*
X201902Y63266D01*
Y66403D01*
X202152Y66653D01*
Y72853D01*
X201802Y73203D01*
Y74709D01*
X203192Y76099D01*
Y82301D01*
X201802Y83691D01*
Y86118D01*
X202152Y86468D01*
Y91418D01*
X201902Y91668D01*
Y94590D01*
X201492Y95000D01*
Y104450D01*
X205042Y108000D01*
Y117650D01*
X211342Y123950D01*
Y128723D01*
X244992Y162373D01*
Y172747D01*
X257342Y185097D01*
Y187500D01*
X258209Y188367D01*
G01X279911Y187958D02*
X276642Y184689D01*
Y182892D01*
X263692Y169942D01*
Y156548D01*
X241866Y134722D01*
Y133860D01*
X242578Y133148D01*
Y132286D01*
X241594Y131302D01*
X240732D01*
X240020Y132014D01*
X239158D01*
X222092Y114948D01*
Y112949D01*
X222652Y112389D01*
X223692D01*
X224492Y111589D01*
Y109989D01*
X223692Y109189D01*
X222192D01*
X221392Y108389D01*
Y106789D01*
X222192Y105989D01*
X223692D01*
X224492Y105189D01*
Y103589D01*
X223692Y102789D01*
X222192D01*
X221392Y101989D01*
Y100389D01*
X222192Y99589D01*
X223692D01*
X224492Y98789D01*
Y97189D01*
X223503Y96200D01*
X222924D01*
X222124Y95400D01*
Y94268D01*
X222502Y93890D01*
Y91618D01*
X222102Y91218D01*
Y86518D01*
X222492Y86128D01*
Y81104D01*
X223292Y80304D01*
X223792D01*
X224592Y79504D01*
Y77904D01*
X223792Y77104D01*
X223292D01*
X222492Y76304D01*
Y73001D01*
X222102Y72611D01*
Y66903D01*
X222702Y66303D01*
Y62690D01*
X223792Y61600D01*
Y59900D01*
X221842Y57950D01*
X220342D01*
X219574Y57182D01*
Y56050D01*
X220667Y54957D01*
G01D02*
X219739Y54029D01*
Y50901D01*
X222781Y47859D01*
Y46474D01*
X221106Y44799D01*
Y43676D01*
X222606Y42176D01*
Y40824D01*
X221106Y39324D01*
Y38101D01*
X222539Y36668D01*
Y35574D01*
X224013Y34100D01*
G01Y49914D02*
X222202Y51725D01*
Y53580D01*
X223652Y55030D01*
Y56160D01*
X226692Y59200D01*
Y63500D01*
X225492Y64700D01*
Y66443D01*
X226302Y67253D01*
Y72291D01*
X225402Y73191D01*
Y74700D01*
X226892Y76190D01*
Y82500D01*
X225402Y83990D01*
Y85718D01*
X226202Y86518D01*
Y91018D01*
X225502Y91718D01*
Y93610D01*
X227092Y95200D01*
Y116413D01*
X237529Y126850D01*
X242392D01*
X261033Y145491D01*
X261895D01*
X263258Y144128D01*
X264120D01*
X265104Y145112D01*
Y145974D01*
X263741Y147337D01*
Y148199D01*
X266142Y150600D01*
Y168856D01*
X279442Y182156D01*
Y183953D01*
X281634Y186145D01*
G01X173591Y52100D02*
X175277Y53786D01*
Y55940D01*
X174517Y56700D01*
X173517D01*
X172797Y57420D01*
Y58488D01*
X173751Y59442D01*
X174387D01*
X175342Y60397D01*
Y61033D01*
X176671Y62362D01*
Y74025D01*
X177121Y74475D01*
Y75824D01*
X176671Y76274D01*
Y78380D01*
X177291Y79000D01*
Y80000D01*
X176671Y80620D01*
Y93480D01*
X177291Y94100D01*
Y95100D01*
X176671Y95720D01*
Y96480D01*
X177291Y97100D01*
Y98100D01*
X176671Y98720D01*
Y99480D01*
X177291Y100100D01*
Y101100D01*
X176671Y101720D01*
Y103048D01*
X179072Y105449D01*
Y125430D01*
X186192Y132550D01*
Y145929D01*
X188503Y148240D01*
X191405D01*
X193801Y145844D01*
X195386D01*
X197149Y147607D01*
Y149192D01*
X193733Y152608D01*
Y153470D01*
X223893Y183630D01*
X224529D01*
X225484Y184585D01*
Y185221D01*
X226437Y186174D01*
X227073D01*
X228028Y187129D01*
Y187765D01*
X228982Y188719D01*
X229618D01*
X230573Y189674D01*
Y190310D01*
X231526Y191263D01*
X232162D01*
X233117Y192218D01*
Y192854D01*
X234071Y193808D01*
X234707D01*
X235662Y194763D01*
Y195399D01*
X236615Y196352D01*
X237251D01*
X238206Y197307D01*
Y197943D01*
X239160Y198897D01*
X239796D01*
X240751Y199852D01*
Y200488D01*
X241704Y201441D01*
X242340D01*
X243295Y202396D01*
Y203032D01*
X244249Y203986D01*
X244885D01*
X245840Y204941D01*
Y205577D01*
X246793Y206530D01*
X247429D01*
X248384Y207485D01*
Y208121D01*
X249338Y209075D01*
X249974D01*
X250929Y210030D01*
Y210666D01*
X251882Y211619D01*
X252518D01*
X253473Y212573D01*
Y213210D01*
X254682Y214419D01*
X255319D01*
X256273Y215374D01*
Y216010D01*
X257242Y216979D01*
Y220565D01*
X260284Y223607D01*
G01X268964Y187316D02*
X266592Y184944D01*
Y182068D01*
X265638Y181114D01*
Y180478D01*
X264683Y179523D01*
X264047D01*
X263094Y178570D01*
Y177934D01*
X262139Y176979D01*
X261503D01*
X260549Y176025D01*
Y175389D01*
X259594Y174434D01*
X258958D01*
X258005Y173481D01*
Y172845D01*
X257050Y171890D01*
X256414D01*
X253672Y169148D01*
Y167799D01*
X254122Y167349D01*
Y165999D01*
X253672Y165549D01*
Y164201D01*
X254122Y163751D01*
Y162401D01*
X253672Y161951D01*
Y160602D01*
X254122Y160152D01*
Y158802D01*
X253672Y158352D01*
Y155748D01*
X252477Y154553D01*
X249515D01*
X248119Y153157D01*
Y150195D01*
X246110Y148186D01*
X243148D01*
X241752Y146790D01*
Y143828D01*
X239743Y141819D01*
X236781D01*
X235385Y140423D01*
Y137461D01*
X213482Y115558D01*
Y105818D01*
X213932Y105368D01*
Y104018D01*
X213482Y103568D01*
Y102220D01*
X214102Y101600D01*
Y100600D01*
X213482Y99980D01*
Y99220D01*
X214102Y98600D01*
Y97600D01*
X213482Y96980D01*
Y96220D01*
X214102Y95600D01*
Y94600D01*
X213482Y93980D01*
Y80275D01*
X213932Y79825D01*
Y78476D01*
X213482Y78026D01*
Y76524D01*
X213932Y76074D01*
Y74725D01*
X213482Y74275D01*
Y63162D01*
X212153Y61833D01*
Y61197D01*
X211198Y60242D01*
X210562D01*
X209608Y59288D01*
Y57420D01*
X210328Y56700D01*
X210992D01*
X212092Y55600D01*
Y53790D01*
X210402Y52100D01*
G01X178691Y52314D02*
X180517Y54140D01*
Y55700D01*
X178497Y57720D01*
Y58588D01*
X179471Y59562D01*
X180347D01*
X181055Y60270D01*
Y61146D01*
X182391Y62482D01*
Y63314D01*
X181771Y63934D01*
Y74580D01*
X182391Y75200D01*
Y76200D01*
X181771Y76820D01*
Y77580D01*
X182391Y78200D01*
Y79200D01*
X181771Y79820D01*
Y93547D01*
X182872Y94648D01*
Y123781D01*
X192740Y133649D01*
Y135391D01*
X189916Y138215D01*
Y139074D01*
X190906Y140064D01*
X191763D01*
X194588Y137239D01*
X196330D01*
X202672Y143581D01*
Y152052D01*
X200872Y153852D01*
Y155174D01*
X269175Y223477D01*
X269811D01*
X270766Y224432D01*
Y225068D01*
X272703Y227005D01*
Y230644D01*
G01X273519Y185209D02*
X270602Y182292D01*
Y180578D01*
X269648Y179624D01*
Y178988D01*
X268693Y178033D01*
X268057D01*
X267104Y177080D01*
Y176444D01*
X266149Y175489D01*
X265513D01*
X264559Y174535D01*
Y174017D01*
X263486Y172944D01*
X262968D01*
X257472Y167448D01*
Y154148D01*
X218582Y115258D01*
Y61862D01*
X215308Y58588D01*
Y57684D01*
X217328Y55664D01*
Y54140D01*
X215502Y52314D01*
G01X173591Y49500D02*
X171737Y51354D01*
Y58931D01*
X175611Y62805D01*
Y103488D01*
X178012Y105889D01*
Y125870D01*
X185132Y132990D01*
Y146369D01*
X188063Y149300D01*
X191845D01*
X194241Y146904D01*
X194946D01*
X196089Y148047D01*
Y148752D01*
X192673Y152168D01*
Y153910D01*
X256182Y217419D01*
Y221005D01*
X259534Y224357D01*
G01X268213Y188065D02*
X265532Y185384D01*
Y182508D01*
X265529D01*
X252612Y169591D01*
Y156191D01*
X252034Y155613D01*
X249072D01*
X247059Y153600D01*
Y150638D01*
X245667Y149246D01*
X242705D01*
X240692Y147233D01*
Y144271D01*
X239300Y142879D01*
X236338D01*
X236030Y142571D01*
Y142568D01*
X234325Y140863D01*
Y137901D01*
X212422Y115998D01*
Y63605D01*
X208548Y59731D01*
Y51354D01*
X210402Y49500D01*
G01X178691Y49714D02*
Y49715D01*
X179789D01*
X180823Y48681D01*
Y45906D01*
X180117Y45200D01*
X179603D01*
X178903Y44500D01*
Y43500D01*
X179603Y42800D01*
X180103D01*
X180823Y42080D01*
Y40707D01*
X180016Y39900D01*
X179318D01*
X178717Y39299D01*
Y38101D01*
X179318Y37500D01*
X180116D01*
X180823Y36793D01*
Y34172D01*
X179800Y33149D01*
X178691D01*
G01Y49714D02*
X176967Y51438D01*
Y57729D01*
X177437Y58199D01*
Y59031D01*
X180711Y62305D01*
Y93987D01*
X181812Y95088D01*
Y124221D01*
X191680Y134089D01*
Y134951D01*
X188856Y137775D01*
Y139514D01*
X190466Y141124D01*
X192203D01*
X195028Y138299D01*
X195890D01*
X201612Y144021D01*
Y151612D01*
X199812Y153412D01*
Y155617D01*
X199814Y155616D01*
X271643Y227445D01*
Y230644D01*
G01X215502Y49714D02*
Y49715D01*
X216600D01*
X217634Y48681D01*
Y45906D01*
X216928Y45200D01*
X216414D01*
X215714Y44500D01*
Y43500D01*
X216414Y42800D01*
X216914D01*
X217634Y42080D01*
Y40707D01*
X216827Y39900D01*
X216129D01*
X215528Y39299D01*
Y38101D01*
X216129Y37500D01*
X216927D01*
X217634Y36793D01*
Y34172D01*
X216611Y33149D01*
X215502D01*
G01X272769Y185959D02*
X269542Y182732D01*
Y181018D01*
X256414Y167890D01*
X256412Y167891D01*
Y154591D01*
X217522Y115701D01*
Y62305D01*
X214248Y59031D01*
Y58199D01*
X213778Y57729D01*
Y51438D01*
X215502Y49714D01*
G01X169770Y550914D02*
Y550564D01*
X171691Y548643D01*
Y546901D01*
X172192Y546400D01*
Y544656D01*
X170892Y543356D01*
Y541756D01*
X172192Y540456D01*
Y538201D01*
X171691Y537700D01*
Y528201D01*
X172492Y527400D01*
Y526245D01*
X171882Y525635D01*
X171102D01*
X170492Y525025D01*
Y523045D01*
X171102Y522435D01*
X171882D01*
X172492Y521825D01*
Y519601D01*
X171691Y518800D01*
Y508900D01*
X172301Y508290D01*
X173592D01*
X174092Y507790D01*
Y505590D01*
X173592Y505090D01*
X172301D01*
X171691Y504480D01*
Y503401D01*
X181592Y493500D01*
Y463904D01*
X182392Y463104D01*
X184692D01*
X185492Y462304D01*
Y460704D01*
X184692Y459904D01*
X182392D01*
X181592Y459104D01*
Y457100D01*
X214947Y423745D01*
Y420445D01*
X215892Y419500D01*
X218292D01*
X219192Y418600D01*
Y417400D01*
X218492Y416700D01*
X215447D01*
X214947Y416200D01*
Y414183D01*
X239147Y389983D01*
Y383489D01*
X260192Y362444D01*
G01X173591Y553100D02*
X173620D01*
X176671Y550049D01*
Y546445D01*
X177121Y545995D01*
Y544995D01*
X176671Y544545D01*
Y543452D01*
X177015Y543108D01*
Y542108D01*
X176671Y541764D01*
Y511153D01*
X177572Y510252D01*
Y503152D01*
X185272Y495452D01*
Y467841D01*
X188444Y464669D01*
X190723D01*
X192492Y462900D01*
Y460518D01*
X190283Y458309D01*
X188072D01*
X187088Y457325D01*
Y455872D01*
X222652Y420308D01*
Y410644D01*
X242852Y390444D01*
Y384975D01*
X252625Y375202D01*
X252627D01*
X262404Y365426D01*
G01X261653Y364674D02*
X241792Y384535D01*
Y390004D01*
X221592Y410204D01*
Y419868D01*
X186028Y455432D01*
Y457765D01*
X187632Y459369D01*
X189843D01*
X191432Y460958D01*
Y462460D01*
X190283Y463609D01*
X188004D01*
X184212Y467401D01*
Y495009D01*
X176512Y502709D01*
Y509809D01*
X175611Y510710D01*
Y549608D01*
X174719Y550500D01*
X173591D01*
G01X263179Y380873D02*
X258792Y385260D01*
Y387632D01*
X233506Y412918D01*
Y421658D01*
X236795Y424947D01*
Y427320D01*
X236185Y427930D01*
X233479D01*
X232869Y428540D01*
Y429930D01*
X233479Y430540D01*
X236185D01*
X236795Y431150D01*
Y433599D01*
X216697Y453697D01*
Y454405D01*
X217375Y455083D01*
X218507D01*
X225275Y448315D01*
X226407D01*
X227538Y449446D01*
Y450578D01*
X196692Y481424D01*
Y501164D01*
X192692Y505164D01*
Y510956D01*
X191292Y512356D01*
Y515900D01*
X193192Y517800D01*
Y519099D01*
X192224Y520067D01*
Y527832D01*
X192791Y528399D01*
Y529347D01*
X191691Y530447D01*
Y535342D01*
X192591Y536242D01*
Y537700D01*
X192192Y538099D01*
Y546700D01*
X192591Y547099D01*
Y548707D01*
X189191Y552107D01*
Y554599D01*
X190549Y555957D01*
G01X264958Y382652D02*
X261292Y386318D01*
Y389300D01*
X239692Y410900D01*
Y412872D01*
X239082Y413482D01*
X236556D01*
X235946Y414092D01*
Y415482D01*
X236556Y416092D01*
X239082D01*
X239692Y416702D01*
Y418092D01*
X239082Y418702D01*
X236556D01*
X235946Y419312D01*
Y420702D01*
X236556Y421312D01*
X239082D01*
X239692Y421922D01*
Y433747D01*
X228811Y444628D01*
Y445760D01*
X229942Y446891D01*
X231074D01*
X237738Y440227D01*
X238870D01*
X240001Y441358D01*
Y442490D01*
X201492Y480999D01*
Y481893D01*
X200692Y482693D01*
X199461D01*
X198635Y483519D01*
Y485119D01*
X199409Y485893D01*
X200692D01*
X201492Y486693D01*
Y488293D01*
X200692Y489093D01*
X199514D01*
X198714Y489893D01*
Y491493D01*
X199514Y492293D01*
X200692D01*
X201492Y493093D01*
Y494693D01*
X200692Y495493D01*
X198945D01*
X198317Y496121D01*
Y497721D01*
X199022Y498426D01*
X200519D01*
X201062Y498969D01*
Y500330D01*
X195192Y506200D01*
Y511558D01*
X195891Y512257D01*
Y516401D01*
X195341Y516951D01*
Y519300D01*
X195592Y519551D01*
Y527800D01*
X195341Y528051D01*
Y529697D01*
X196191Y530547D01*
Y535302D01*
X195191Y536302D01*
Y537500D01*
X195592Y537901D01*
Y546400D01*
X195191Y546801D01*
Y549670D01*
X193895Y550966D01*
Y550914D01*
G01X257339Y379641D02*
X248592Y388388D01*
Y392500D01*
X228092Y413000D01*
Y424175D01*
X212473Y439794D01*
Y441026D01*
X213604Y442157D01*
X214636D01*
X222975Y433818D01*
X224107D01*
X225238Y434949D01*
Y436754D01*
X200992Y461000D01*
Y463236D01*
X197931Y466297D01*
Y467329D01*
X199181Y468579D01*
Y469711D01*
X198050Y470842D01*
X196918D01*
X195668Y469592D01*
X194636D01*
X191692Y472536D01*
Y499092D01*
X185792Y504992D01*
Y511556D01*
X184892Y512456D01*
Y516558D01*
X185891Y517557D01*
Y519200D01*
X185492Y519599D01*
Y527700D01*
X185891Y528099D01*
Y529497D01*
X184818Y530570D01*
Y535169D01*
X186091Y536442D01*
Y537500D01*
X185492Y538099D01*
Y546500D01*
X186091Y547099D01*
Y548557D01*
X183191Y551457D01*
Y555292D01*
X183856Y555957D01*
G01X259048Y381468D02*
X250477Y390039D01*
Y393281D01*
X230792Y412966D01*
Y428646D01*
X230182Y429256D01*
X227539D01*
X226929Y429866D01*
Y431256D01*
X227539Y431866D01*
X230182D01*
X230792Y432476D01*
Y434736D01*
X203492Y462036D01*
Y463168D01*
X204623Y464299D01*
X205755D01*
X213557Y456497D01*
X214689D01*
X215820Y457628D01*
Y458760D01*
X205943Y468637D01*
X205081D01*
X203549Y467105D01*
X202687D01*
X201286Y468506D01*
Y469368D01*
X202818Y470900D01*
Y471762D01*
X199152Y475428D01*
X198290D01*
X196058Y473196D01*
X195196D01*
X193795Y474597D01*
Y475459D01*
X196027Y477691D01*
Y478553D01*
X194192Y480388D01*
Y500128D01*
X188591Y505729D01*
Y511257D01*
X189491Y512157D01*
Y516301D01*
X188391Y517401D01*
Y519500D01*
X188892Y520001D01*
Y528000D01*
X188691Y528201D01*
Y529697D01*
X189257Y530263D01*
Y535635D01*
X188591Y536301D01*
Y537699D01*
X188892Y538000D01*
Y546399D01*
X188591Y546700D01*
Y549568D01*
X188548D01*
X187202Y550914D01*
G01X266925Y403235D02*
X259016Y411144D01*
Y417577D01*
X248692Y427901D01*
Y446605D01*
X210492Y484805D01*
Y503500D01*
X205984Y508008D01*
Y510725D01*
X204492Y512217D01*
Y516299D01*
X205768Y517575D01*
Y519534D01*
X205291Y520011D01*
Y527499D01*
X205802Y528010D01*
Y529467D01*
X204652Y530617D01*
Y535354D01*
X205847Y536549D01*
Y537805D01*
X205105Y538547D01*
Y545513D01*
X205635Y546043D01*
Y548874D01*
X203142Y551367D01*
Y555164D01*
X203935Y555957D01*
G01X262350Y398644D02*
X251692Y409302D01*
Y416899D01*
X243692Y424899D01*
Y444533D01*
X205492Y482733D01*
Y501900D01*
X199166Y508226D01*
Y510893D01*
X198370Y511689D01*
Y516557D01*
X199202Y517389D01*
Y529489D01*
X198154Y530537D01*
Y535144D01*
X199152Y536142D01*
Y548441D01*
X196699Y550894D01*
Y555414D01*
X197242Y555957D01*
G01X264218Y400312D02*
X254295Y410235D01*
Y411410D01*
X254905Y412020D01*
X256496D01*
X257106Y412630D01*
Y414020D01*
X256496Y414630D01*
X254905D01*
X254295Y415240D01*
Y416996D01*
X253075Y418216D01*
Y419078D01*
X253513Y419516D01*
Y420378D01*
X252112Y421779D01*
X251250D01*
X250813Y421343D01*
X249951D01*
X248550Y422744D01*
Y423605D01*
X248987Y424042D01*
Y424904D01*
X246192Y427699D01*
Y445569D01*
X207992Y483769D01*
Y502400D01*
X201692Y508700D01*
Y510799D01*
X202692Y511799D01*
Y516099D01*
X201597Y517194D01*
Y518895D01*
X202292Y519590D01*
Y527600D01*
X201902Y527990D01*
Y530197D01*
X202402Y530697D01*
Y534856D01*
X201802Y535456D01*
Y537500D01*
X202292Y537990D01*
Y546300D01*
X200992Y547600D01*
Y550210D01*
X200288Y550914D01*
G01X259997Y371718D02*
X245292Y386423D01*
Y391401D01*
X225092Y411601D01*
Y421968D01*
X207631Y439429D01*
Y441541D01*
X210693Y444602D01*
Y445826D01*
X208917Y447602D01*
X207691D01*
X204629Y444541D01*
X202519D01*
X200131Y446929D01*
Y449041D01*
X203193Y452102D01*
Y453326D01*
X201417Y455102D01*
X200192D01*
X197410Y452320D01*
X194740D01*
X192812Y454248D01*
Y456752D01*
X196812Y460752D01*
Y462209D01*
X188012Y471009D01*
Y496909D01*
X180711Y504210D01*
Y526103D01*
X180316Y526498D01*
Y527498D01*
X180711Y527893D01*
Y538279D01*
X180197Y538793D01*
Y539793D01*
X180711Y540307D01*
Y541374D01*
X180091Y541994D01*
Y542994D01*
X180711Y543614D01*
Y544614D01*
X180091Y545234D01*
Y546234D01*
X180711Y546854D01*
Y549648D01*
X179645Y550714D01*
X178691D01*
G01Y553314D02*
X178716D01*
X181771Y550259D01*
Y504650D01*
X189072Y497349D01*
Y471452D01*
X197872Y462652D01*
Y460309D01*
X193872Y456309D01*
Y454691D01*
X195183Y453380D01*
X196967D01*
X199749Y456162D01*
X201860D01*
X204253Y453769D01*
Y451659D01*
X201191Y448598D01*
Y447372D01*
X202962Y445601D01*
X204189D01*
X207251Y448662D01*
X209360D01*
X211753Y446269D01*
Y444159D01*
X208691Y441098D01*
Y439869D01*
X226152Y422408D01*
Y412041D01*
X246352Y391841D01*
Y386865D01*
X249652Y383565D01*
Y383564D01*
X260747Y372469D01*
G01X268748Y404948D02*
X263683Y410013D01*
Y411250D01*
X263073Y411860D01*
X261774D01*
X261164Y412470D01*
Y413860D01*
X261774Y414470D01*
X263179D01*
X263789Y415080D01*
Y416404D01*
X251192Y429001D01*
Y447641D01*
X212992Y485841D01*
Y488601D01*
X214492Y490101D01*
Y490801D01*
X212992Y492301D01*
Y493601D01*
X214492Y495101D01*
Y496241D01*
X212992Y497741D01*
Y499441D01*
X214492Y500941D01*
Y502800D01*
X208502Y508790D01*
Y518910D01*
X209992Y520400D01*
Y521465D01*
X209382Y522075D01*
X207902D01*
X207292Y522685D01*
Y524665D01*
X207902Y525275D01*
X209382D01*
X209992Y525885D01*
Y527100D01*
X208502Y528590D01*
Y537810D01*
X209292Y538600D01*
Y540327D01*
X208682Y540937D01*
X207602D01*
X206992Y541547D01*
Y543527D01*
X207602Y544137D01*
X208682D01*
X209292Y544747D01*
Y546100D01*
X208502Y546890D01*
Y548993D01*
X206581Y550914D01*
G01X293707Y405382D02*
X291192Y407897D01*
Y410601D01*
X266292Y435501D01*
Y452461D01*
X261244Y457509D01*
Y464825D01*
X240180Y485889D01*
X235680D01*
X229592Y491977D01*
Y510867D01*
X228802Y511657D01*
Y517009D01*
X229602Y517809D01*
Y519400D01*
X229036Y519966D01*
Y527844D01*
X229465Y528273D01*
Y529406D01*
X228502Y530369D01*
Y535342D01*
X229402Y536242D01*
Y537600D01*
X229092Y537910D01*
Y546800D01*
X229402Y547110D01*
Y548707D01*
X226002Y552107D01*
Y554599D01*
X227360Y555957D01*
G01X280998Y408201D02*
X280192Y409007D01*
Y414476D01*
X261292Y433376D01*
Y451520D01*
X249046Y463766D01*
Y470623D01*
X238780Y480889D01*
X233080D01*
X224592Y489377D01*
Y506901D01*
X222902Y508591D01*
Y511257D01*
X222102Y512057D01*
Y516957D01*
X222702Y517557D01*
Y519600D01*
X222292Y520010D01*
Y527800D01*
X222702Y528210D01*
Y529597D01*
X221629Y530670D01*
Y535169D01*
X222902Y536442D01*
Y537600D01*
X222292Y538210D01*
Y546800D01*
X222902Y547410D01*
Y548557D01*
X220002Y551457D01*
Y555292D01*
X220667Y555957D01*
G01X282953Y409796D02*
Y415304D01*
X263792Y434465D01*
Y452043D01*
X251093Y464742D01*
Y465604D01*
X252077Y466588D01*
X252939D01*
X257275Y462252D01*
X258137D01*
X259121Y463236D01*
Y464098D01*
X239830Y483389D01*
X234380D01*
X227092Y490677D01*
Y507500D01*
X225402Y509190D01*
Y511257D01*
X226302Y512157D01*
Y516489D01*
X225202Y517589D01*
Y519500D01*
X225692Y519990D01*
Y527900D01*
X225502Y528090D01*
Y529797D01*
X226068Y530363D01*
Y535425D01*
X225402Y536091D01*
Y537710D01*
X225692Y538000D01*
Y546600D01*
X225402Y546890D01*
Y549568D01*
X225359D01*
X224013Y550914D01*
G01X269663Y409283D02*
X267852Y411094D01*
Y417572D01*
X254872Y430552D01*
Y449329D01*
X218172Y486029D01*
Y504049D01*
X213482Y508739D01*
Y550020D01*
X210402Y553100D01*
G01X273493Y409313D02*
X271949Y410857D01*
Y417515D01*
X257615Y431849D01*
X257612D01*
Y450625D01*
X245546Y462691D01*
Y467569D01*
X244028Y469087D01*
X242782D01*
X242020Y468325D01*
X239912D01*
X237525Y470712D01*
Y472826D01*
X238835Y474136D01*
Y475361D01*
X237059Y477137D01*
X235835D01*
X234998Y476300D01*
X231937D01*
X221018Y487219D01*
Y492516D01*
X220398Y493136D01*
Y494136D01*
X221018Y494756D01*
Y495756D01*
X220398Y496376D01*
Y497376D01*
X221018Y497996D01*
Y498996D01*
X220398Y499616D01*
Y500616D01*
X221018Y501236D01*
Y502236D01*
X220398Y502856D01*
Y503856D01*
X221018Y504476D01*
Y505741D01*
X219859Y506900D01*
X218981D01*
X218274Y507607D01*
Y508485D01*
X217522Y509237D01*
Y510553D01*
X217049Y511026D01*
Y512026D01*
X217522Y512499D01*
Y515936D01*
X217128Y516330D01*
Y517330D01*
X217522Y517724D01*
Y518987D01*
X216902Y519607D01*
Y520607D01*
X217522Y521227D01*
Y522227D01*
X216902Y522847D01*
Y523847D01*
X217522Y524467D01*
Y525467D01*
X216902Y526087D01*
Y527087D01*
X217522Y527707D01*
Y529337D01*
X217086Y529773D01*
Y530773D01*
X217522Y531209D01*
Y534496D01*
X217107Y534911D01*
Y535911D01*
X217522Y536326D01*
Y538160D01*
X216902Y538780D01*
Y539780D01*
X217522Y540400D01*
Y541400D01*
X216902Y542020D01*
Y543020D01*
X217522Y543640D01*
Y544640D01*
X216902Y545260D01*
Y546260D01*
X217522Y546880D01*
Y549795D01*
X216603Y550714D01*
X215502D01*
G01X268913Y408533D02*
X266792Y410654D01*
Y417129D01*
X253812Y430109D01*
Y448889D01*
X217112Y485589D01*
Y503609D01*
X212422Y508299D01*
Y541494D01*
X211896Y542020D01*
Y543020D01*
X212422Y543546D01*
Y544719D01*
X211868Y545273D01*
Y546273D01*
X212422Y546827D01*
Y549580D01*
X211502Y550500D01*
X210402D01*
G01X274243Y410063D02*
X273009Y411297D01*
Y417955D01*
X258672Y432292D01*
Y451065D01*
X246606Y463131D01*
Y468009D01*
X244468Y470147D01*
X242342D01*
X241580Y469385D01*
X240355D01*
X238585Y471155D01*
Y472383D01*
X239895Y473693D01*
Y475804D01*
X237502Y478197D01*
X235395D01*
X234558Y477360D01*
X232377D01*
X229945Y479792D01*
Y480358D01*
X228650Y481653D01*
X228084D01*
X222078Y487659D01*
Y506181D01*
X218582Y509677D01*
Y550235D01*
X215503Y553314D01*
X215502D01*
G01X190549Y555957D02*
X188844Y557662D01*
Y567849D01*
X193895Y572900D01*
G01Y550914D02*
X193807D01*
X192121Y552600D01*
Y554292D01*
X192296Y554467D01*
Y557100D01*
X191184Y558212D01*
Y559288D01*
X192196Y560300D01*
Y561500D01*
X191184Y562512D01*
Y563588D01*
X192321Y564725D01*
Y565999D01*
X191621Y566699D01*
X190549D01*
G01X183856Y555957D02*
X182151Y557662D01*
Y567849D01*
X187202Y572900D01*
G01Y550914D02*
X187114D01*
X185428Y552600D01*
Y554292D01*
X185603Y554467D01*
Y557100D01*
X184491Y558212D01*
Y559288D01*
X185503Y560300D01*
Y561500D01*
X184491Y562512D01*
Y563588D01*
X185628Y564725D01*
Y565999D01*
X184928Y566699D01*
X183856D01*
G01X203935Y555957D02*
X202230Y557662D01*
Y569315D01*
X205415Y572500D01*
X206581D01*
G01Y550914D02*
X206493D01*
X204807Y552600D01*
Y554292D01*
X205714Y555199D01*
Y556792D01*
X204570Y557936D01*
Y559356D01*
X205414Y560200D01*
Y561900D01*
X204570Y562744D01*
Y563956D01*
X205514Y564900D01*
Y566100D01*
X204915Y566699D01*
X203935D01*
G01X227360Y555957D02*
X225655Y557662D01*
Y567849D01*
X230706Y572900D01*
G01X295173Y407266D02*
Y410156D01*
X268792Y436537D01*
Y462679D01*
X268182Y463289D01*
X266792D01*
X266182Y462679D01*
Y457933D01*
X265572Y457323D01*
X264182D01*
X263572Y457933D01*
Y465787D01*
X246477Y482882D01*
Y483744D01*
X248134Y485401D01*
Y486263D01*
X247150Y487247D01*
X246288D01*
X244631Y485590D01*
X243769D01*
X240859Y488500D01*
X235892D01*
X231492Y492900D01*
Y511047D01*
X232702Y512257D01*
Y516807D01*
X232152Y517357D01*
Y519300D01*
X232392Y519540D01*
Y527600D01*
X232152Y527840D01*
Y529847D01*
X233002Y530697D01*
Y535390D01*
X232002Y536390D01*
Y537510D01*
X232392Y537900D01*
Y546400D01*
X232002Y546790D01*
Y549670D01*
X230706Y550966D01*
Y550914D01*
G01D02*
X230618D01*
X228932Y552600D01*
Y554292D01*
X229107Y554467D01*
Y557100D01*
X227995Y558212D01*
Y559288D01*
X229007Y560300D01*
Y561500D01*
X227995Y562512D01*
Y563588D01*
X229132Y564725D01*
Y565999D01*
X228432Y566699D01*
X227360D01*
G01X197242Y555957D02*
X195537Y557662D01*
Y567635D01*
X196159Y568257D01*
Y569445D01*
X199214Y572500D01*
X200202D01*
G01X200288Y550914D02*
X200200D01*
X198514Y552600D01*
Y554800D01*
X199014Y555300D01*
Y557199D01*
X197877Y558336D01*
Y559664D01*
X198814Y560601D01*
Y561999D01*
X197877Y562936D01*
Y564164D01*
X198914Y565201D01*
Y566099D01*
X198314Y566699D01*
X197242D01*
G01X224013Y572900D02*
X218962Y567849D01*
Y557662D01*
X220667Y555957D01*
G01D02*
Y555961D01*
G01X224013Y550914D02*
X223925D01*
X222239Y552600D01*
Y554292D01*
X222414Y554467D01*
Y557100D01*
X221302Y558212D01*
Y559288D01*
X222314Y560300D01*
Y561500D01*
X221302Y562512D01*
Y563588D01*
X222439Y564725D01*
Y565999D01*
X221739Y566699D01*
X220667D01*
G01X173617Y569550D02*
X175322Y567845D01*
Y565939D01*
X174583Y565200D01*
X173303D01*
X172663Y564560D01*
Y563140D01*
X173213Y562590D01*
X173793D01*
X174403Y561980D01*
Y560590D01*
X173793Y559980D01*
X173183D01*
X172663Y559460D01*
Y558090D01*
X173253Y557500D01*
X174203D01*
X175303Y556400D01*
Y554812D01*
X173591Y553100D01*
G01X210402D02*
X212114Y554812D01*
Y556400D01*
X211014Y557500D01*
X210064D01*
X209474Y558090D01*
Y559460D01*
X209994Y559980D01*
X210604D01*
X211214Y560590D01*
Y561980D01*
X210604Y562590D01*
X210024D01*
X209474Y563140D01*
Y564560D01*
X210114Y565200D01*
X211394D01*
X212133Y565939D01*
Y567845D01*
X210428Y569550D01*
G01X178691Y550714D02*
X178403D01*
X176986Y552131D01*
Y557100D01*
X176156Y557930D01*
Y564470D01*
X176986Y565300D01*
Y570244D01*
X178691Y571949D01*
G01X215502Y550714D02*
X215214D01*
X213797Y552131D01*
Y557100D01*
X212967Y557930D01*
Y564470D01*
X213797Y565300D01*
Y570244D01*
X215502Y571949D01*
G01X173591Y550500D02*
X173303D01*
X171603Y552200D01*
Y570211D01*
X173591Y572199D01*
G01X210402Y550500D02*
X210114D01*
X208414Y552200D01*
Y570211D01*
X210402Y572199D01*
G01X178691Y569340D02*
X180503Y567528D01*
Y565800D01*
X179503Y564800D01*
X177987D01*
X177216Y564029D01*
Y563138D01*
X177756Y562598D01*
X177993D01*
X178703Y561888D01*
Y560800D01*
X178003Y560100D01*
X177668D01*
X177216Y559648D01*
Y558371D01*
X177887Y557700D01*
X179403D01*
X180403Y556700D01*
Y555026D01*
X178691Y553314D01*
G01X215502D02*
X217214Y555026D01*
Y556700D01*
X216214Y557700D01*
X214698D01*
X214027Y558371D01*
Y559648D01*
X214479Y560100D01*
X214814D01*
X215514Y560800D01*
Y561888D01*
X214804Y562598D01*
X214567D01*
X214027Y563138D01*
Y564029D01*
X214798Y564800D01*
X216314D01*
X217314Y565800D01*
Y567528D01*
X215502Y569340D01*
G01X243392Y49914D02*
X244865Y48441D01*
Y35316D01*
X245481Y34700D01*
Y33356D01*
X244025Y31900D01*
X242625D01*
X240746Y30021D01*
Y27899D01*
G01X264171D02*
X265418Y29146D01*
Y30400D01*
X266718Y31700D01*
X267718D01*
X269518Y33500D01*
Y34900D01*
X268906Y35512D01*
Y48525D01*
X267517Y49914D01*
G01X237099D02*
X238325Y48688D01*
Y35675D01*
X239100Y34900D01*
Y33276D01*
X237524Y31700D01*
X236300D01*
X234053Y29453D01*
Y27899D01*
G01X257478D02*
X258725Y29146D01*
Y30400D01*
X260025Y31700D01*
X261025D01*
X262825Y33500D01*
Y34900D01*
X262213Y35512D01*
Y48525D01*
X260824Y49914D01*
G01X247239Y30750D02*
X248009Y31520D01*
X248991D01*
X250319Y32848D01*
Y48994D01*
X247213Y52100D01*
G01Y33399D02*
X248032Y32580D01*
X248548D01*
X249259Y33291D01*
Y36580D01*
X247339Y38500D01*
Y39500D01*
X247939Y40100D01*
X248439D01*
X249259Y40920D01*
Y41880D01*
X248539Y42600D01*
X247827D01*
X247325Y43102D01*
Y44434D01*
X247941Y45050D01*
X248289D01*
X249259Y46020D01*
Y48553D01*
X248312Y49500D01*
X247213D01*
G01X252313Y52314D02*
X255505Y49122D01*
Y33732D01*
X252313Y30540D01*
G01X314973Y194250D02*
Y193050D01*
X315473Y192550D01*
Y191650D01*
X314973Y191150D01*
Y188881D01*
X314337Y188245D01*
Y187537D01*
X313701Y186901D01*
X312993D01*
X312289Y186197D01*
Y185489D01*
X311653Y184853D01*
X310945D01*
X310309Y184217D01*
Y183509D01*
X309673Y182873D01*
X308965D01*
X308329Y182237D01*
Y181529D01*
X307693Y180893D01*
X306985D01*
X306314Y180222D01*
Y179514D01*
X305678Y178878D01*
X304970D01*
X304334Y178242D01*
Y177534D01*
X303698Y176898D01*
X302990D01*
X302354Y176262D01*
Y175554D01*
X301718Y174918D01*
X301010D01*
X300374Y174282D01*
Y173574D01*
X299738Y172938D01*
X299030D01*
X298052Y171960D01*
Y137042D01*
X296960Y135950D01*
X293124D01*
X292652Y135478D01*
Y133732D01*
X293124Y133260D01*
X296960D01*
X298052Y132168D01*
Y128240D01*
X287104Y117292D01*
Y60920D01*
X287724Y60300D01*
Y59300D01*
X287104Y58680D01*
Y57920D01*
X287724Y57300D01*
Y56300D01*
X287104Y55680D01*
Y25442D01*
X283230Y21568D01*
Y19620D01*
X283950Y18900D01*
X284950D01*
X285750Y18100D01*
Y16026D01*
X284024Y14300D01*
G01X320441Y196613D02*
Y185399D01*
X319092Y184050D01*
X316390D01*
X302392Y170052D01*
Y126590D01*
X292204Y116402D01*
Y24062D01*
X291488Y23346D01*
Y22470D01*
X290780Y21762D01*
X289904D01*
X288930Y20788D01*
Y19920D01*
X290950Y17900D01*
Y16340D01*
X289124Y14514D01*
G01X313913Y194250D02*
Y189321D01*
X296992Y172400D01*
Y137482D01*
X296520Y137010D01*
X292684D01*
X291592Y135918D01*
Y133292D01*
X292684Y132200D01*
X296520D01*
X296992Y131728D01*
Y128680D01*
X286044Y117732D01*
Y25885D01*
X282170Y22011D01*
Y13554D01*
X284024Y11700D01*
G01X319381Y196613D02*
Y185839D01*
X318652Y185110D01*
X315950D01*
X301332Y170492D01*
Y127030D01*
X291144Y116842D01*
Y24505D01*
X287870Y21231D01*
Y18479D01*
X287400Y18009D01*
Y13638D01*
X289124Y11914D01*
G01X308448Y197341D02*
Y191006D01*
X292242Y174800D01*
Y160695D01*
X291192Y159645D01*
Y157915D01*
X292242Y156865D01*
Y155475D01*
X291632Y154865D01*
X289852D01*
X289242Y154255D01*
Y152865D01*
X289852Y152255D01*
X291632D01*
X292242Y151645D01*
Y150255D01*
X291632Y149645D01*
X289852D01*
X289242Y149035D01*
Y147645D01*
X289852Y147035D01*
X291632D01*
X292242Y146425D01*
Y144499D01*
X286492Y138749D01*
Y126701D01*
X279592Y119801D01*
Y111642D01*
X278266Y110316D01*
Y106174D01*
X279624Y104816D01*
Y92332D01*
X278274Y90982D01*
Y86714D01*
X279624Y85364D01*
Y73433D01*
X278274Y72083D01*
Y67417D01*
X279624Y66067D01*
Y54532D01*
X278274Y53182D01*
Y48914D01*
X279624Y47564D01*
Y35533D01*
X278274Y34183D01*
Y29617D01*
X279424Y28467D01*
Y26633D01*
X277124Y24333D01*
Y17590D01*
X277557Y17157D01*
G01X310948Y197341D02*
Y189193D01*
X294742Y172987D01*
Y142499D01*
X288892Y136649D01*
Y125600D01*
X282124Y118832D01*
Y26033D01*
X279624Y23533D01*
Y16732D01*
X278130Y15238D01*
Y14187D01*
X280203Y12114D01*
G01X303448Y197341D02*
X303542Y197247D01*
Y193100D01*
X282192Y171750D01*
Y162971D01*
X282752Y162411D01*
X284132D01*
X284692Y161851D01*
Y160411D01*
X284132Y159851D01*
X282752D01*
X282192Y159291D01*
Y157851D01*
X282752Y157291D01*
X284132D01*
X284692Y156731D01*
Y155291D01*
X284132Y154731D01*
X282752D01*
X282192Y154171D01*
Y143799D01*
X281542Y143149D01*
Y129999D01*
X273392Y121849D01*
Y114700D01*
X272824Y114132D01*
Y111674D01*
X271866Y110716D01*
Y106274D01*
X272824Y105316D01*
Y102744D01*
X271992Y101912D01*
Y99544D01*
X272824Y98712D01*
Y92114D01*
X271924Y91214D01*
Y86414D01*
X272924Y85414D01*
Y82409D01*
X272092Y81577D01*
Y79209D01*
X272924Y78377D01*
Y73099D01*
X271924Y72099D01*
Y67167D01*
X272824Y66267D01*
Y63885D01*
X271992Y63053D01*
Y60685D01*
X272824Y59853D01*
Y54314D01*
X271924Y53414D01*
Y48614D01*
X272924Y47614D01*
Y45014D01*
X271992Y44082D01*
Y41814D01*
X272924Y40882D01*
Y35299D01*
X271924Y34299D01*
Y29267D01*
X272692Y28499D01*
Y27100D01*
X270864Y25272D01*
Y17157D01*
G01X305948Y197341D02*
Y191856D01*
X287092Y173000D01*
Y169654D01*
X286532Y169094D01*
X284852D01*
X284292Y168534D01*
Y167094D01*
X284852Y166534D01*
X286532D01*
X287092Y165974D01*
Y144200D01*
X284292Y141400D01*
Y128301D01*
X275892Y119901D01*
Y113668D01*
X275424Y113200D01*
Y111074D01*
X275766Y110732D01*
Y105674D01*
X275424Y105332D01*
Y91764D01*
X275774Y91414D01*
Y86464D01*
X275424Y86114D01*
Y73199D01*
X275774Y72849D01*
Y66649D01*
X275524Y66399D01*
Y53864D01*
X275774Y53614D01*
Y48664D01*
X275424Y48314D01*
Y35399D01*
X275774Y35049D01*
Y28849D01*
X275524Y28599D01*
Y26232D01*
X274192Y24900D01*
Y17800D01*
X271992Y15600D01*
Y14032D01*
X273910Y12114D01*
G01X240746Y112327D02*
X241455Y111618D01*
Y106124D01*
X242555Y105024D01*
Y92062D01*
X241155Y90662D01*
Y86874D01*
X242666Y85363D01*
Y73357D01*
X241466Y72157D01*
Y67414D01*
X242655Y66225D01*
Y64863D01*
X240746Y62954D01*
Y54957D01*
G01D02*
X239625Y53836D01*
Y50900D01*
X242525Y48000D01*
Y46032D01*
X240992Y44499D01*
Y43300D01*
X242242Y42050D01*
Y41150D01*
X240892Y39800D01*
Y38501D01*
X242525Y36868D01*
Y34567D01*
X243392Y33700D01*
G01Y106934D02*
X245305Y105021D01*
Y64313D01*
X242766Y61774D01*
Y54474D01*
X241366Y53074D01*
Y51940D01*
X243392Y49914D01*
G01X267517Y34100D02*
X265950Y35667D01*
Y36868D01*
X264592Y38226D01*
Y39599D01*
X265792Y40799D01*
Y41925D01*
X264592Y43125D01*
Y44700D01*
X266392Y46500D01*
Y47558D01*
X263050Y50900D01*
Y53836D01*
X264171Y54957D01*
G01D02*
Y59379D01*
X266066Y61274D01*
Y66460D01*
X265455Y67071D01*
Y72463D01*
X266255Y73263D01*
Y85774D01*
X265566Y86463D01*
Y91285D01*
X266155Y91874D01*
Y105286D01*
X264171Y107270D01*
Y112327D01*
G01X267517Y49914D02*
X269655Y52052D01*
Y53344D01*
X268855Y54144D01*
Y66359D01*
X269466Y66970D01*
Y72526D01*
X268755Y73237D01*
Y85862D01*
X269455Y86562D01*
Y91286D01*
X268755Y91986D01*
Y106046D01*
X267517Y107284D01*
G01X234053Y112327D02*
X235055Y111325D01*
Y106186D01*
X235955Y105286D01*
Y92062D01*
X235066Y91173D01*
Y86463D01*
X235955Y85574D01*
Y72959D01*
X235066Y72070D01*
Y67126D01*
X235955Y66237D01*
Y63359D01*
X234053Y61457D01*
Y54957D01*
G01D02*
X233125Y54029D01*
Y50901D01*
X235925Y48101D01*
Y46232D01*
X234542Y44849D01*
Y43450D01*
X235992Y42000D01*
Y40800D01*
X234492Y39300D01*
Y38101D01*
X235925Y36668D01*
Y34788D01*
X237013Y33700D01*
G01X237099Y107284D02*
X238755Y105628D01*
Y91474D01*
X239055Y91174D01*
Y86474D01*
X238655Y86074D01*
Y72959D01*
X238955Y72659D01*
Y67359D01*
X238655Y67059D01*
Y56833D01*
X235066Y53244D01*
Y51443D01*
X236595Y49914D01*
X237099D01*
G01X257478Y112327D02*
X258855Y110950D01*
Y105675D01*
X259755Y104775D01*
Y92174D01*
X258655Y91074D01*
Y86774D01*
X259466Y85963D01*
Y73174D01*
X258655Y72363D01*
Y67071D01*
X259455Y66271D01*
Y56934D01*
X257478Y54957D01*
G01D02*
X256550Y54029D01*
Y50901D01*
X259592Y47859D01*
Y46474D01*
X257917Y44799D01*
Y43676D01*
X259417Y42176D01*
Y40824D01*
X257917Y39324D01*
Y38101D01*
X259350Y36668D01*
Y35574D01*
X260824Y34100D01*
G01Y49914D02*
X259024Y51714D01*
Y53701D01*
X261655Y56332D01*
Y65747D01*
X262855Y66947D01*
Y72537D01*
X262266Y73126D01*
Y85985D01*
X262955Y86674D01*
Y91012D01*
X262255Y91712D01*
Y105853D01*
X260824Y107284D01*
G01X247213Y52100D02*
X248939Y53826D01*
Y56072D01*
X248230Y56781D01*
Y59747D01*
X250230Y61747D01*
Y107497D01*
X247213Y110514D01*
G01X252313Y107655D02*
X253337D01*
X254270Y106722D01*
Y60092D01*
X252370Y58192D01*
Y57520D01*
X250589Y55739D01*
Y51438D01*
X252313Y49714D01*
G01D02*
Y49715D01*
X253411D01*
X254445Y48681D01*
Y45906D01*
X253739Y45200D01*
X253225D01*
X252525Y44500D01*
Y43500D01*
X253225Y42800D01*
X253725D01*
X254445Y42080D01*
Y40707D01*
X253638Y39900D01*
X252940D01*
X252339Y39299D01*
Y38101D01*
X252940Y37500D01*
X253738D01*
X254445Y36793D01*
Y34172D01*
X253422Y33149D01*
X252313D01*
G01X247213Y49500D02*
X245239Y51474D01*
Y55389D01*
X247170Y57320D01*
Y60190D01*
X249170Y62190D01*
Y105934D01*
X247239Y107865D01*
G01X252339Y110264D02*
X253329D01*
X255330Y108263D01*
Y59649D01*
X253430Y57749D01*
Y56620D01*
X254139Y55911D01*
Y54140D01*
X252313Y52314D01*
G01X316235Y405512D02*
Y413801D01*
X291372Y438664D01*
Y450052D01*
X288126Y453298D01*
Y453863D01*
X286831Y455158D01*
X286266D01*
X284972Y456452D01*
Y461378D01*
X285372Y461778D01*
Y463608D01*
X284972Y464008D01*
Y485009D01*
X287104Y487141D01*
Y587820D01*
X284024Y590900D01*
G01X319178Y409187D02*
Y414822D01*
X294441Y439558D01*
Y454575D01*
X293520Y455496D01*
X290904D01*
X289412Y456988D01*
Y459564D01*
X290904Y461056D01*
X293069D01*
X293569Y461556D01*
Y464220D01*
X293069Y464720D01*
X289504D01*
X287812Y466412D01*
Y483852D01*
X291144Y487184D01*
Y519146D01*
X290524Y519766D01*
Y520766D01*
X291144Y521386D01*
Y522386D01*
X290524Y523006D01*
Y524006D01*
X291144Y524626D01*
Y525626D01*
X290524Y526246D01*
Y527246D01*
X291144Y527866D01*
Y538293D01*
X290524Y538913D01*
Y539913D01*
X291144Y540533D01*
Y541533D01*
X290524Y542153D01*
Y543153D01*
X291144Y543773D01*
Y544773D01*
X290524Y545393D01*
Y546393D01*
X291144Y547013D01*
Y556987D01*
X290524Y557607D01*
Y558607D01*
X291144Y559227D01*
Y560227D01*
X290524Y560847D01*
Y561847D01*
X291144Y562467D01*
Y563626D01*
X290670Y564100D01*
Y565100D01*
X291144Y565574D01*
Y572284D01*
X290709Y572719D01*
Y573719D01*
X291144Y574154D01*
Y576292D01*
X290763Y576673D01*
Y577673D01*
X291144Y578054D01*
Y579293D01*
X290524Y579913D01*
Y580913D01*
X291144Y581533D01*
Y582533D01*
X290524Y583153D01*
Y584153D01*
X291144Y584773D01*
Y587594D01*
X290224Y588514D01*
X289124D01*
G01X315175Y405512D02*
Y413361D01*
X290314Y438222D01*
X290312D01*
Y449609D01*
X283912Y456009D01*
Y485449D01*
X286044Y487581D01*
Y559472D01*
X285530Y559986D01*
Y560986D01*
X286044Y561500D01*
Y562659D01*
X285491Y563212D01*
Y564212D01*
X286044Y564765D01*
Y575895D01*
X285636Y576303D01*
Y577303D01*
X286044Y577711D01*
Y578923D01*
X285424Y579543D01*
Y580543D01*
X286044Y581163D01*
Y582163D01*
X285424Y582783D01*
Y583783D01*
X286044Y584403D01*
Y587380D01*
X285124Y588300D01*
X284024D01*
G01X320238Y409187D02*
Y415262D01*
X295501Y439998D01*
Y455015D01*
X293960Y456556D01*
X291344D01*
X290472Y457428D01*
Y459124D01*
X291344Y459996D01*
X293509D01*
X294629Y461116D01*
Y464660D01*
X293509Y465780D01*
X289944D01*
X288872Y466852D01*
Y483409D01*
X292204Y486741D01*
Y588034D01*
X289124Y591114D01*
G01X309825Y400464D02*
Y411195D01*
X283692Y437328D01*
Y438460D01*
X284383Y439151D01*
Y440389D01*
X283252Y441520D01*
X282226D01*
X281429Y440723D01*
X280297D01*
X278692Y442328D01*
Y487900D01*
X278366Y488226D01*
Y493874D01*
X279408Y494916D01*
Y510923D01*
X278274Y512057D01*
Y516307D01*
X279355Y517388D01*
Y529513D01*
X278274Y530594D01*
Y535282D01*
X279624Y536632D01*
Y548507D01*
X278274Y549857D01*
Y554107D01*
X279424Y555257D01*
Y567267D01*
X278324Y568367D01*
Y573033D01*
X279474Y574183D01*
Y586457D01*
X277557Y588374D01*
Y593757D01*
G01X312325Y400312D02*
Y412368D01*
X287592Y437101D01*
Y449622D01*
X286674Y450540D01*
X285074D01*
X284392Y449858D01*
Y444343D01*
X283709Y443660D01*
X282109D01*
X281192Y444577D01*
Y486800D01*
X282124Y487732D01*
Y519432D01*
X282592Y519900D01*
Y527900D01*
X282124Y528368D01*
Y537700D01*
X282592Y538168D01*
Y546300D01*
X282124Y546768D01*
Y556500D01*
X282592Y556968D01*
Y562600D01*
X282124Y563068D01*
Y575600D01*
X282592Y576068D01*
Y583800D01*
X282124Y584268D01*
Y586443D01*
X280203Y588364D01*
Y588714D01*
G01X304525Y400162D02*
Y409167D01*
X273592Y440100D01*
Y465816D01*
X269492Y469916D01*
Y474022D01*
X270292Y474822D01*
X271068D01*
X271868Y475622D01*
Y477222D01*
X271068Y478022D01*
X270292D01*
X269492Y478822D01*
Y485899D01*
X272036Y488443D01*
Y494444D01*
X272792Y495200D01*
Y502600D01*
X272666Y502726D01*
Y511055D01*
X271924Y511797D01*
Y516505D01*
X272824Y517405D01*
Y529468D01*
X271924Y530368D01*
Y535242D01*
X272924Y536242D01*
Y548557D01*
X271924Y549557D01*
Y554309D01*
X272824Y555209D01*
Y567169D01*
X271776Y568217D01*
Y572944D01*
X272774Y573942D01*
Y586457D01*
X270864Y588367D01*
Y593757D01*
G01X307025Y400312D02*
Y410367D01*
X276192Y441200D01*
Y469239D01*
X275531Y469900D01*
X272862D01*
X272303Y470459D01*
Y472439D01*
X272913Y473049D01*
X275582D01*
X276192Y473659D01*
Y480132D01*
X275392Y480932D01*
X272129D01*
X271382Y481679D01*
Y483279D01*
X272235Y484132D01*
X275880D01*
X276492Y484744D01*
Y494500D01*
X275792Y495200D01*
Y506200D01*
X275566Y506426D01*
Y511539D01*
X275774Y511747D01*
Y517207D01*
X275524Y517457D01*
Y519100D01*
X275892Y519468D01*
Y527600D01*
X275524Y527968D01*
Y529992D01*
X275774Y530242D01*
Y535192D01*
X275424Y535542D01*
Y537500D01*
X275892Y537968D01*
Y546600D01*
X275424Y547068D01*
Y548885D01*
X275774Y549235D01*
Y555007D01*
X275524Y555257D01*
Y556900D01*
X275892Y557268D01*
Y565700D01*
X275524Y566068D01*
Y567997D01*
X276024Y568497D01*
Y572656D01*
X275424Y573256D01*
Y575732D01*
X275892Y576200D01*
Y584400D01*
X275424Y584868D01*
Y587200D01*
X273910Y588714D01*
G01X240746Y555957D02*
X239313Y554524D01*
Y552007D01*
X242663Y548657D01*
Y547071D01*
X242392Y546800D01*
Y538071D01*
X242663Y537800D01*
Y536471D01*
X241513Y535321D01*
Y530567D01*
X242613Y529467D01*
Y528121D01*
X242392Y527900D01*
Y519321D01*
X242613Y519100D01*
Y517457D01*
X241463Y516307D01*
Y512057D01*
X242813Y510707D01*
Y508498D01*
X241292Y506977D01*
Y497600D01*
X239592Y495900D01*
G01X243392Y550914D02*
Y550564D01*
X245313Y548643D01*
Y546979D01*
X245792Y546500D01*
Y538179D01*
X245313Y537700D01*
Y529779D01*
X245792Y529300D01*
Y519599D01*
X245313Y519120D01*
Y505999D01*
X243392Y504078D01*
Y495694D01*
G01X264171Y555957D02*
X262813Y554599D01*
Y552107D01*
X266213Y548707D01*
Y547121D01*
X265892Y546800D01*
Y537921D01*
X266213Y537600D01*
Y536242D01*
X265313Y535342D01*
Y530597D01*
X266413Y529497D01*
Y528321D01*
X265892Y527800D01*
Y519721D01*
X266392Y519221D01*
Y517836D01*
X265613Y517057D01*
Y511657D01*
X266113Y511157D01*
Y500429D01*
X264171Y498487D01*
G01X267584Y493919D02*
X268913Y495248D01*
Y511657D01*
X269513Y512257D01*
Y516807D01*
X268963Y517357D01*
Y519200D01*
X269192Y519429D01*
Y527800D01*
X268963Y528029D01*
Y529847D01*
X269813Y530697D01*
Y535478D01*
X268813Y536478D01*
Y538280D01*
X267692Y539401D01*
Y540799D01*
X268792Y541899D01*
Y543000D01*
X267896Y543896D01*
Y545404D01*
X268792Y546300D01*
Y549691D01*
X267517Y550966D01*
Y550914D01*
G01X234053Y555957D02*
X233549Y555453D01*
Y551071D01*
X235893Y548727D01*
Y536072D01*
X235087Y535266D01*
Y530305D01*
X235869Y529523D01*
Y517213D01*
X235113Y516457D01*
Y511757D01*
X236113Y510757D01*
Y504421D01*
X233292Y501600D01*
Y498500D01*
G01X237099Y550914D02*
X238613Y549400D01*
Y546879D01*
X239092Y546400D01*
Y537879D01*
X238613Y537400D01*
Y535456D01*
X239213Y534856D01*
Y530697D01*
X238713Y530197D01*
Y528079D01*
X239092Y527700D01*
Y519579D01*
X238713Y519200D01*
Y517457D01*
X238963Y517207D01*
Y511007D01*
X238613Y510657D01*
Y503800D01*
X236992Y502179D01*
Y495701D01*
X238613Y494080D01*
Y492521D01*
X236892Y490800D01*
G01X257478Y555957D02*
X256813Y555292D01*
Y551457D01*
X259713Y548557D01*
Y546721D01*
X259192Y546200D01*
Y538121D01*
X259713Y537600D01*
Y536442D01*
X258440Y535169D01*
Y530670D01*
X259513Y529597D01*
Y527821D01*
X259192Y527500D01*
Y519521D01*
X259513Y519200D01*
Y517557D01*
X258913Y516957D01*
Y512057D01*
X259713Y511257D01*
Y503022D01*
X257478Y500787D01*
Y498487D01*
G01X260824Y550914D02*
X262170Y549568D01*
X262213D01*
Y547179D01*
X263292Y546100D01*
Y544700D01*
X261992Y543400D01*
Y542100D01*
X263292Y540800D01*
Y538779D01*
X262213Y537700D01*
Y536179D01*
X262879Y535513D01*
Y530363D01*
X262313Y529797D01*
Y528179D01*
X263092Y527400D01*
Y525800D01*
X262192Y524900D01*
Y523300D01*
X263092Y522400D01*
Y520379D01*
X262013Y519300D01*
Y517657D01*
X263113Y516557D01*
Y512157D01*
X262213Y511257D01*
Y502420D01*
X259192Y499399D01*
Y495100D01*
X258238Y494146D01*
Y493354D01*
X258635Y492957D01*
X260037D01*
X260824Y493744D01*
G01X247213Y553100D02*
Y552979D01*
X250293Y549899D01*
Y507677D01*
X247992Y502122D01*
Y500301D01*
X248857Y499436D01*
Y497266D01*
X247500Y495909D01*
X247228D01*
G01X252313Y493214D02*
X250586Y494941D01*
Y499194D01*
X254333Y502941D01*
Y521060D01*
X252832Y522561D01*
Y525640D01*
X254333Y527141D01*
Y548695D01*
X252314Y550714D01*
X252313D01*
G01X247228Y493209D02*
X245486Y494951D01*
Y498841D01*
X249233Y507888D01*
Y549459D01*
X248192Y550500D01*
X247213D01*
G01X252313Y553314D02*
X252314D01*
X255393Y550235D01*
Y526701D01*
X253892Y525200D01*
Y523001D01*
X255393Y521500D01*
Y502501D01*
X254092Y501200D01*
Y497100D01*
X252806Y495814D01*
X252313D01*
G01X323104Y403924D02*
Y416100D01*
X297944Y441260D01*
Y465226D01*
X291492Y471678D01*
Y482400D01*
X296524Y487432D01*
Y493868D01*
X295992Y494400D01*
Y501200D01*
X296168Y501376D01*
Y511613D01*
X295724Y512057D01*
Y516957D01*
X296124Y517357D01*
Y529842D01*
X295724Y530242D01*
Y535832D01*
X296167Y536275D01*
Y549414D01*
X295724Y549857D01*
Y554757D01*
X296324Y555357D01*
Y557200D01*
X295992Y557532D01*
Y565600D01*
X296324Y565932D01*
Y567397D01*
X295251Y568470D01*
Y572969D01*
X296421Y574139D01*
Y575271D01*
X295992Y575700D01*
Y584400D01*
X296524Y584932D01*
Y586357D01*
X293792Y589089D01*
Y593260D01*
X294289Y593757D01*
G01X243392Y572500D02*
X242226D01*
X239041Y569315D01*
Y557662D01*
X240746Y555957D01*
G01Y566699D02*
X241726D01*
X242325Y566100D01*
Y564900D01*
X241381Y563956D01*
Y562744D01*
X242225Y561900D01*
Y560200D01*
X241381Y559356D01*
Y557936D01*
X242525Y556792D01*
Y555199D01*
X241618Y554292D01*
Y552600D01*
X243304Y550914D01*
X243392D01*
G01X267517Y572900D02*
X262466Y567849D01*
Y557662D01*
X264171Y555957D01*
G01X267517Y550914D02*
X267429D01*
X265743Y552600D01*
Y554292D01*
X265918Y554467D01*
Y557100D01*
X264806Y558212D01*
Y559288D01*
X265818Y560300D01*
Y561500D01*
X264806Y562512D01*
Y563588D01*
X265943Y564725D01*
Y565999D01*
X265243Y566699D01*
X264171D01*
G01X237013Y572500D02*
X236025D01*
X232970Y569445D01*
Y568257D01*
X232348Y567635D01*
Y557662D01*
X234053Y555957D01*
G01Y566699D02*
X235125D01*
X235725Y566099D01*
Y565201D01*
X234688Y564164D01*
Y562936D01*
X235625Y561999D01*
Y560601D01*
X234688Y559664D01*
Y558336D01*
X235825Y557199D01*
Y555300D01*
X235325Y554800D01*
Y552600D01*
X237011Y550914D01*
X237099D01*
G01X260824Y572900D02*
X255773Y567849D01*
Y557662D01*
X257478Y555957D01*
G01Y566699D02*
X258550D01*
X259250Y565999D01*
Y564725D01*
X258113Y563588D01*
Y562512D01*
X259125Y561500D01*
Y560300D01*
X258113Y559288D01*
Y558212D01*
X259225Y557100D01*
Y554467D01*
X259050Y554292D01*
Y552600D01*
X260736Y550914D01*
X260824D01*
G01X247239Y569550D02*
X248944Y567845D01*
Y565939D01*
X248205Y565200D01*
X246925D01*
X246285Y564560D01*
Y563140D01*
X246835Y562590D01*
X247415D01*
X248025Y561980D01*
Y560590D01*
X247415Y559980D01*
X246805D01*
X246285Y559460D01*
Y558090D01*
X246875Y557500D01*
X247825D01*
X248925Y556400D01*
Y554812D01*
X247213Y553100D01*
G01X252313Y550714D02*
X252025D01*
X250608Y552131D01*
Y557100D01*
X249778Y557930D01*
Y564470D01*
X250608Y565300D01*
Y570244D01*
X252313Y571949D01*
G01X247213Y550500D02*
X246925D01*
X245225Y552200D01*
Y570211D01*
X247213Y572199D01*
G01X252313Y569340D02*
X254125Y567528D01*
Y565800D01*
X253125Y564800D01*
X251609D01*
X250838Y564029D01*
Y563138D01*
X251378Y562598D01*
X251615D01*
X252325Y561888D01*
Y560800D01*
X251625Y560100D01*
X251290D01*
X250838Y559648D01*
Y558371D01*
X251509Y557700D01*
X253025D01*
X254025Y556700D01*
Y555026D01*
X252313Y553314D01*
G01X321061Y54857D02*
X320961D01*
X319342Y53238D01*
Y43953D01*
X319952Y43343D01*
X320875D01*
X321485Y42733D01*
Y40833D01*
X320875Y40223D01*
X319952D01*
X319342Y39613D01*
Y32165D01*
X319824Y31000D01*
X321061Y28014D01*
G01X324407Y54857D02*
Y53486D01*
X329362Y48531D01*
Y32969D01*
X324407Y28014D01*
G01X345037Y198346D02*
Y129045D01*
X322330Y106338D01*
Y97681D01*
X319066Y94417D01*
Y91574D01*
X319666Y90974D01*
Y88974D01*
X319066Y88374D01*
Y86174D01*
X319666Y85574D01*
Y83774D01*
X319342Y83450D01*
Y69635D01*
X318866Y69159D01*
Y67859D01*
X319448Y67277D01*
Y64957D01*
X318392Y63901D01*
Y58060D01*
X315992Y55660D01*
Y49840D01*
X316092Y49740D01*
Y34278D01*
X314368Y32554D01*
Y28014D01*
G01X354526Y54857D02*
X352892Y53223D01*
Y51800D01*
X352692Y51600D01*
Y48218D01*
X352892Y48018D01*
Y34499D01*
X354526Y32865D01*
Y28023D01*
X354525Y28022D01*
G01X351179D02*
Y29892D01*
X349459Y31612D01*
Y36958D01*
X350692Y38191D01*
Y44739D01*
X349452Y45979D01*
Y47902D01*
X350692Y49142D01*
Y51677D01*
X351179Y52164D01*
Y54857D01*
G01X344486Y28022D02*
X343893Y31000D01*
X343732Y31811D01*
X342879Y33870D01*
Y36649D01*
X341432Y38096D01*
Y44802D01*
X342862Y46232D01*
Y50936D01*
X344486Y54857D01*
G01X341140D02*
X339409Y53126D01*
Y34984D01*
X339992Y34401D01*
Y31840D01*
X341140Y30692D01*
Y28022D01*
G01X328148Y197291D02*
Y183856D01*
X321730Y177438D01*
X321003D01*
X312637Y169072D01*
Y153190D01*
X313197Y152630D01*
X313932D01*
X314492Y152070D01*
Y150630D01*
X313932Y150070D01*
X313197D01*
X312637Y149510D01*
Y148070D01*
X313197Y147510D01*
X313932D01*
X314492Y146950D01*
Y145510D01*
X313932Y144950D01*
X313197D01*
X312637Y144390D01*
Y142950D01*
X313197Y142390D01*
X313932D01*
X314492Y141830D01*
Y140390D01*
X313932Y139830D01*
X313197D01*
X312637Y139270D01*
Y137830D01*
X313197Y137270D01*
X313932D01*
X314492Y136710D01*
Y135270D01*
X313932Y134710D01*
X313197D01*
X312637Y134150D01*
Y132710D01*
X313197Y132150D01*
X313932D01*
X314492Y131590D01*
Y130150D01*
X313932Y129590D01*
X313197D01*
X312637Y129030D01*
Y125845D01*
X302892Y116100D01*
Y109000D01*
X302366Y108474D01*
Y104126D01*
X303324Y103168D01*
Y92164D01*
X302324Y91164D01*
Y86414D01*
X302924Y85814D01*
Y73131D01*
X302424Y72631D01*
Y66799D01*
X303274Y65949D01*
Y54264D01*
X302324Y53314D01*
Y48614D01*
X302924Y48014D01*
Y35331D01*
X302424Y34831D01*
Y28999D01*
X303224Y28199D01*
Y19399D01*
X300982Y17157D01*
G01X330648Y197291D02*
X330642Y197285D01*
Y182750D01*
X322953Y175061D01*
X322239D01*
X316592Y169414D01*
Y122850D01*
X306366Y112624D01*
Y103874D01*
X305824Y103332D01*
Y91874D01*
X306224Y91474D01*
Y86414D01*
X305724Y85914D01*
Y73067D01*
X306274Y72517D01*
Y66999D01*
X305774Y66499D01*
Y53914D01*
X306235Y53453D01*
Y48575D01*
X305724Y48064D01*
Y35369D01*
X306324Y34769D01*
Y29249D01*
X305774Y28699D01*
Y18882D01*
X302424Y15532D01*
Y14018D01*
X304328Y12114D01*
G01X323148Y196691D02*
X323092Y196635D01*
Y184900D01*
X319791Y181599D01*
X317782D01*
X305342Y169159D01*
Y150316D01*
X305952Y149706D01*
X307273D01*
X307883Y149096D01*
Y147876D01*
X307273Y147266D01*
X305952D01*
X305342Y146656D01*
Y145436D01*
X305952Y144826D01*
X307273D01*
X307883Y144216D01*
Y142996D01*
X307273Y142386D01*
X305952D01*
X305342Y141776D01*
Y140556D01*
X305952Y139946D01*
X307273D01*
X307883Y139336D01*
Y138116D01*
X307273Y137506D01*
X305952D01*
X305342Y136896D01*
Y126066D01*
X296692Y117416D01*
Y109500D01*
X295558Y108366D01*
Y104234D01*
X296266Y103526D01*
Y101421D01*
X295392Y100547D01*
Y98221D01*
X296266Y97347D01*
Y91756D01*
X295724Y91214D01*
Y86514D01*
X296524Y85714D01*
Y73331D01*
X295724Y72531D01*
Y66899D01*
X296124Y66499D01*
Y53814D01*
X295724Y53414D01*
Y48714D01*
X296524Y47914D01*
Y35531D01*
X295724Y34731D01*
Y29099D01*
X296324Y28499D01*
Y19932D01*
X294289Y17897D01*
Y17157D01*
G01X325648Y196651D02*
X325867Y196432D01*
Y184675D01*
X320596Y179404D01*
X319123D01*
X310442Y170723D01*
Y135950D01*
X307692Y133200D01*
Y125000D01*
X299124Y116432D01*
Y108768D01*
X299866Y108026D01*
Y104574D01*
X299066Y103774D01*
Y91772D01*
X299824Y91014D01*
Y86514D01*
X299024Y85714D01*
Y73167D01*
X299924Y72267D01*
Y67299D01*
X299124Y66499D01*
Y53914D01*
X299824Y53214D01*
Y48714D01*
X299024Y47914D01*
Y35267D01*
X299924Y34367D01*
Y29499D01*
X298824Y28399D01*
Y25399D01*
X299124Y25099D01*
Y19072D01*
X295724Y15672D01*
Y14025D01*
X297635Y12114D01*
G01X346576Y198054D02*
Y122642D01*
X329492Y105558D01*
Y101988D01*
X323452Y95948D01*
Y92274D01*
X322452Y91274D01*
Y89224D01*
X323452Y88224D01*
Y86474D01*
X322452Y85474D01*
Y75239D01*
X322799Y74892D01*
Y72706D01*
X323452Y72053D01*
Y67559D01*
X322792Y66899D01*
Y60530D01*
X321061Y58799D01*
Y54857D01*
G01X327754Y46914D02*
X322792Y51876D01*
Y57741D01*
X326019Y60968D01*
Y67092D01*
X325752Y67359D01*
Y69359D01*
X326352Y69959D01*
Y72459D01*
X326138Y72673D01*
Y83686D01*
X326352Y83900D01*
Y85874D01*
X325852Y86374D01*
Y88274D01*
X326552Y88974D01*
Y91074D01*
X325821Y91805D01*
Y95488D01*
X331600Y101267D01*
Y104837D01*
X348188Y121425D01*
Y198224D01*
G01X327754Y35957D02*
X326992D01*
X326092Y36857D01*
Y45252D01*
X327754Y46914D01*
G01X350188Y198928D02*
Y117750D01*
X346638Y114200D01*
X345930D01*
X345118Y115012D01*
X344256D01*
X342911Y113667D01*
Y112805D01*
X344008Y111708D01*
Y110846D01*
X342663Y109501D01*
X341801D01*
X340704Y110598D01*
X339842D01*
X338497Y109253D01*
Y108391D01*
X339594Y107294D01*
Y106432D01*
X338249Y105087D01*
X337387D01*
X336429Y106045D01*
X335721D01*
X334222Y104546D01*
Y103838D01*
X334976Y103084D01*
Y101814D01*
X330452Y97290D01*
Y92374D01*
X329052Y90974D01*
Y88874D01*
X329752Y88174D01*
Y86274D01*
X329152Y85674D01*
Y84039D01*
X329393Y83798D01*
Y72600D01*
X329152Y72359D01*
Y70059D01*
X329752Y69459D01*
Y67459D01*
X329487Y67194D01*
Y60955D01*
X324407Y55875D01*
Y54857D01*
G01X340101Y197885D02*
Y133716D01*
X316021Y109636D01*
Y99859D01*
X310066Y93904D01*
Y92274D01*
X309066Y91274D01*
Y89224D01*
X310066Y88224D01*
Y86474D01*
X309066Y85474D01*
Y75127D01*
X309412Y74781D01*
Y72705D01*
X310066Y72051D01*
Y67559D01*
X309316Y66809D01*
Y52286D01*
X309992Y51610D01*
Y49600D01*
X309392Y49000D01*
Y37586D01*
X311021Y35957D01*
G01X343486Y198703D02*
Y130691D01*
X320097Y107302D01*
Y98277D01*
X316366Y94546D01*
Y91674D01*
X315666Y90974D01*
Y88874D01*
X316366Y88174D01*
Y86274D01*
X315766Y85674D01*
Y75359D01*
X316091Y75034D01*
Y72684D01*
X315766Y72359D01*
Y70059D01*
X316366Y69459D01*
Y67459D01*
X316001Y67094D01*
Y64892D01*
X316366Y64527D01*
Y58383D01*
X314368Y56385D01*
Y54857D01*
G01X341660Y197909D02*
Y132228D01*
X318010Y108578D01*
Y99019D01*
X312435Y93444D01*
Y91805D01*
X313166Y91074D01*
Y88974D01*
X312466Y88274D01*
Y86374D01*
X312966Y85874D01*
Y75074D01*
X312645Y74753D01*
Y72780D01*
X312966Y72459D01*
Y69959D01*
X312366Y69359D01*
Y67359D01*
X312748Y66977D01*
Y61936D01*
X311832Y61020D01*
Y56531D01*
X312748Y55615D01*
Y48641D01*
X311021Y46914D01*
G01X366092Y192683D02*
Y109998D01*
X365409Y109315D01*
X362507D01*
X361376Y108184D01*
Y107052D01*
X362445Y105983D01*
Y104851D01*
X361314Y103720D01*
X360182D01*
X359113Y104789D01*
X357981D01*
X356850Y103658D01*
Y102526D01*
X357919Y101457D01*
Y100325D01*
X356788Y99194D01*
X354913D01*
X352593Y96874D01*
Y91805D01*
X353324Y91074D01*
Y88974D01*
X351892Y87542D01*
Y86500D01*
X353124Y85268D01*
Y83732D01*
X352905Y83513D01*
Y69740D01*
X352524Y69359D01*
Y67359D01*
X352892Y66991D01*
Y58400D01*
X354526Y56766D01*
Y54857D01*
G01Y35957D02*
X356199Y37630D01*
Y40392D01*
X354525Y42066D01*
Y46922D01*
G01D02*
Y52233D01*
X356833Y54541D01*
Y58079D01*
X355974Y58938D01*
Y60411D01*
X356474Y60911D01*
X358756D01*
X359366Y61521D01*
Y63421D01*
X358756Y64031D01*
X356763D01*
X356153Y64641D01*
Y66630D01*
X355628Y67155D01*
Y72559D01*
X356524Y73455D01*
Y82930D01*
X355924Y83530D01*
Y85674D01*
X356167Y85917D01*
Y88531D01*
X355824Y88874D01*
Y90974D01*
X356182Y91332D01*
Y94392D01*
X364627Y102837D01*
Y104204D01*
X368092Y107669D01*
Y192974D01*
G01X351179Y54857D02*
X351792Y55470D01*
Y56601D01*
X349560Y58833D01*
Y69923D01*
X349379Y70104D01*
Y72514D01*
X349464Y72599D01*
Y83427D01*
X349379Y83512D01*
Y85629D01*
X349633Y85883D01*
Y88815D01*
X349379Y89069D01*
Y91429D01*
X350474Y92524D01*
Y100111D01*
X364092Y113729D01*
Y192561D01*
G01X347833Y46922D02*
Y49011D01*
X348592Y49770D01*
Y53170D01*
X349542Y54120D01*
Y55950D01*
X346114Y59378D01*
Y67283D01*
X345638Y67759D01*
Y69159D01*
X346438Y69959D01*
Y72159D01*
X346144Y72453D01*
Y83406D01*
X346438Y83700D01*
Y85574D01*
X345838Y86174D01*
Y88374D01*
X346438Y88974D01*
Y90974D01*
X345838Y91574D01*
Y93308D01*
X348474Y95944D01*
Y100941D01*
X362092Y114559D01*
Y192853D01*
G01X347833Y35957D02*
Y37736D01*
X349023Y38926D01*
Y44082D01*
X347833Y45272D01*
Y46922D01*
G01X360092Y192853D02*
Y115389D01*
X342940Y98237D01*
Y91476D01*
X342729Y91265D01*
Y88583D01*
X343138Y88174D01*
Y86274D01*
X342538Y85674D01*
Y75155D01*
X342873Y74820D01*
Y72694D01*
X342820Y72641D01*
Y59971D01*
X346116Y56675D01*
Y51630D01*
X344486Y50000D01*
Y46922D01*
G01D02*
X345707D01*
X346207Y46422D01*
Y45398D01*
X345577Y44768D01*
X343724D01*
X343062Y44106D01*
Y43116D01*
X343620Y42558D01*
X346771D01*
X347381Y41948D01*
Y40958D01*
X346771Y40348D01*
X343673D01*
X343063Y39738D01*
Y38748D01*
X343673Y38138D01*
X345556D01*
X346155Y37539D01*
Y36523D01*
X345589Y35957D01*
X344486D01*
G01Y54857D02*
Y55957D01*
X340850Y59593D01*
X338743D01*
X338133Y60203D01*
Y61193D01*
X338743Y61803D01*
X340276D01*
X341022Y62549D01*
Y63597D01*
X339534Y65085D01*
Y68595D01*
X340401Y69462D01*
Y71796D01*
X339416Y72781D01*
Y83008D01*
X339738Y83330D01*
Y85874D01*
X339238Y86374D01*
Y88274D01*
X340392Y89428D01*
Y90620D01*
X339340Y91672D01*
Y97466D01*
X358092Y116218D01*
Y190734D01*
X356188Y192638D01*
Y198807D01*
G01X352188Y199049D02*
Y116197D01*
X332452Y96461D01*
Y91574D01*
X332896Y91130D01*
Y88818D01*
X332452Y88374D01*
Y86174D01*
X332817Y85809D01*
Y72394D01*
X332252Y71829D01*
Y67759D01*
X332792Y67219D01*
Y52500D01*
X332530Y52238D01*
Y49872D01*
X333402Y49000D01*
X335707D01*
X337793Y46914D01*
G01D02*
Y40308D01*
X337183Y39698D01*
X336193D01*
X335583Y40308D01*
Y44375D01*
X334952Y45006D01*
X333962D01*
X333373Y44417D01*
Y38460D01*
X334257Y37576D01*
X337218D01*
X337793Y37001D01*
Y35957D01*
G01X354188Y198734D02*
Y191809D01*
X356092Y189905D01*
Y117100D01*
X335508Y96516D01*
Y95384D01*
X337292Y93600D01*
Y92728D01*
X335838Y91274D01*
Y89224D01*
X336838Y88224D01*
Y86474D01*
X335838Y85474D01*
Y83300D01*
X336092Y83046D01*
Y72613D01*
X337140Y71565D01*
Y67861D01*
X336067Y66788D01*
Y64066D01*
X335039Y63038D01*
Y57551D01*
X335810Y56780D01*
X340377D01*
X341140Y56017D01*
Y54857D01*
G01X300982Y593757D02*
X300492Y593267D01*
Y589039D01*
X303024Y586507D01*
Y584832D01*
X302692Y584500D01*
Y576032D01*
X303024Y575700D01*
Y574042D01*
X302124Y573142D01*
Y568397D01*
X303224Y567297D01*
Y566232D01*
X302658Y565666D01*
Y557666D01*
X303224Y557100D01*
Y555657D01*
X302424Y554857D01*
Y549457D01*
X302924Y548957D01*
Y546532D01*
X302692Y546300D01*
Y538132D01*
X302924Y537900D01*
Y536532D01*
X302324Y535932D01*
Y530366D01*
X303274Y529416D01*
Y528582D01*
X302692Y528000D01*
Y519782D01*
X303274Y519200D01*
Y517823D01*
X302283Y516832D01*
Y511798D01*
X302924Y511157D01*
Y509432D01*
X300992Y507500D01*
Y501800D01*
X302692Y500100D01*
Y494000D01*
X303192Y493500D01*
Y487153D01*
X298634Y482595D01*
Y475752D01*
X304764Y469622D01*
Y441512D01*
X328608Y417668D01*
Y405717D01*
G01X330904Y405921D02*
Y418908D01*
X307296Y442516D01*
Y477096D01*
X306542Y477850D01*
X302317D01*
X301409Y478758D01*
Y480898D01*
X302367Y481856D01*
X304843D01*
X305724Y482737D01*
Y486160D01*
X306334Y486770D01*
X309434D01*
X310044Y487380D01*
Y489360D01*
X309434Y489970D01*
X306334D01*
X305724Y490580D01*
Y491652D01*
X307192Y493120D01*
Y499400D01*
X305724Y500868D01*
Y503107D01*
X304924Y503907D01*
X303692D01*
X302892Y504707D01*
Y506307D01*
X303692Y507107D01*
X304924D01*
X305724Y507907D01*
Y511657D01*
X306240Y512173D01*
Y516891D01*
X305774Y517357D01*
Y519782D01*
X306292Y520300D01*
Y535800D01*
X305724Y536368D01*
Y537800D01*
X306292Y538368D01*
Y546500D01*
X305724Y547068D01*
Y549457D01*
X306324Y550057D01*
Y554607D01*
X305774Y555157D01*
Y557381D01*
X306266Y557873D01*
Y573526D01*
X304924Y574868D01*
Y588118D01*
X304328Y588714D01*
G01X297635D02*
X298981Y587368D01*
X299024D01*
Y584768D01*
X299292Y584500D01*
Y575900D01*
X299024Y575632D01*
Y574067D01*
X299690Y573401D01*
Y568163D01*
X299124Y567597D01*
Y566168D01*
X299292Y566000D01*
Y557499D01*
X298824Y557031D01*
Y555457D01*
X299924Y554357D01*
Y549957D01*
X299024Y549057D01*
Y546468D01*
X299292Y546200D01*
Y538100D01*
X299024Y537832D01*
Y536268D01*
X299824Y535468D01*
Y530542D01*
X299124Y529842D01*
Y517357D01*
X299924Y516557D01*
Y512157D01*
X299024Y511257D01*
Y499368D01*
X300292Y498100D01*
Y495000D01*
X299024Y493732D01*
Y486592D01*
X294192Y481760D01*
Y472500D01*
X297863Y468829D01*
X302165D01*
X302775Y468219D01*
Y466239D01*
X302165Y465629D01*
X300957D01*
X300294Y464966D01*
Y462986D01*
X300851Y462429D01*
X302006D01*
X302616Y461819D01*
Y459839D01*
X302006Y459229D01*
X300798D01*
X300188Y458619D01*
Y456639D01*
X300798Y456029D01*
X302165D01*
X302775Y455419D01*
Y453439D01*
X302165Y452829D01*
X301327D01*
X300717Y452219D01*
Y450239D01*
X301327Y449629D01*
X302165D01*
X302775Y449019D01*
Y447039D01*
X302165Y446429D01*
X301302D01*
X300384Y445511D01*
Y442356D01*
X325604Y417136D01*
Y403862D01*
G01X346790Y397118D02*
Y482150D01*
X341459Y487481D01*
X340597D01*
X339743Y486627D01*
X338947D01*
X337963Y487611D01*
Y488539D01*
X338751Y489327D01*
Y490189D01*
X337767Y491173D01*
X336905D01*
X335831Y490099D01*
X334969D01*
X333985Y491083D01*
Y491945D01*
X335059Y493019D01*
Y493881D01*
X334075Y494865D01*
X333213D01*
X332150Y493802D01*
X331233D01*
X330249Y494786D01*
Y495593D01*
X331367Y496711D01*
Y497573D01*
X329692Y499248D01*
Y506146D01*
X326392Y509446D01*
Y510900D01*
X325792Y511500D01*
Y513800D01*
X326392Y514400D01*
Y516400D01*
X325892Y516900D01*
Y520892D01*
X326049Y521049D01*
Y532957D01*
X326092Y533000D01*
Y543400D01*
X322786Y546706D01*
Y549294D01*
X322993Y549501D01*
Y553925D01*
X321061Y555857D01*
G01X350790Y407015D02*
Y482948D01*
X333892Y499846D01*
Y510300D01*
X332592Y511600D01*
Y514000D01*
X332992Y514400D01*
Y516500D01*
X332492Y517000D01*
Y519200D01*
X332792Y519500D01*
Y530400D01*
X332484Y530708D01*
Y535692D01*
X332836Y536044D01*
Y542832D01*
X327754Y547914D01*
G01X348790Y397365D02*
Y482570D01*
X331892Y499468D01*
Y506776D01*
X329092Y509576D01*
Y510900D01*
X329692Y511500D01*
Y514100D01*
X329092Y514700D01*
Y516400D01*
X329792Y517100D01*
Y518900D01*
X329486Y519206D01*
Y530388D01*
X329383Y530491D01*
Y543509D01*
X326092Y546800D01*
Y548900D01*
X325492Y549500D01*
Y554030D01*
X324407Y555115D01*
Y555857D01*
G01X314368Y566814D02*
Y564640D01*
X319451Y559557D01*
Y553061D01*
X318992Y552602D01*
Y549900D01*
X319349Y549543D01*
Y546201D01*
X322092Y543458D01*
Y538800D01*
X322787Y538105D01*
Y535995D01*
X323227Y535555D01*
Y531135D01*
X322792Y530700D01*
Y519500D01*
X322992Y519300D01*
Y516900D01*
X322392Y516300D01*
Y514400D01*
X322892Y513900D01*
Y511600D01*
X322492Y511200D01*
Y498800D01*
X344790Y476502D01*
Y396937D01*
G01X340746Y401003D02*
Y474546D01*
X315792Y499500D01*
Y511300D01*
X316292Y511800D01*
Y513800D01*
X315792Y514300D01*
Y516500D01*
X316192Y516900D01*
Y527700D01*
X315999Y527893D01*
Y535807D01*
X316087Y535895D01*
Y543405D01*
X312649Y546843D01*
Y551757D01*
X312752Y551860D01*
Y567840D01*
X311021Y569571D01*
Y574757D01*
G01X314368Y555857D02*
X315592Y554633D01*
Y552100D01*
X316292Y551400D01*
Y549700D01*
X316102Y549510D01*
Y546690D01*
X319349Y543443D01*
Y530643D01*
X319437Y530555D01*
Y527845D01*
X319092Y527500D01*
Y517000D01*
X319592Y516500D01*
Y514200D01*
X319192Y513800D01*
Y511800D01*
X319892Y511100D01*
Y498300D01*
X342746Y475446D01*
Y400788D01*
G01X311021Y547914D02*
Y545372D01*
X312634Y543759D01*
Y535458D01*
X312739Y535353D01*
Y527947D01*
X311842Y527050D01*
Y517750D01*
X312992Y516600D01*
Y514200D01*
X312392Y513600D01*
Y512000D01*
X313492Y510900D01*
Y498800D01*
X338746Y473546D01*
Y400454D01*
G01X358790Y408586D02*
Y493252D01*
X357435Y494607D01*
X356063D01*
X354811Y493355D01*
X353579D01*
X352448Y494486D01*
Y495518D01*
X353865Y496935D01*
Y498067D01*
X352734Y499198D01*
X351602D01*
X350451Y498047D01*
X349347D01*
X348216Y499178D01*
Y500338D01*
X349159Y501281D01*
Y502773D01*
X346392Y505540D01*
Y510780D01*
X345400Y511772D01*
Y513408D01*
X346496Y514504D01*
Y516420D01*
X345577Y517339D01*
Y520157D01*
X346118Y520698D01*
Y530374D01*
X345892Y530600D01*
Y532900D01*
X346192Y533200D01*
Y543800D01*
X344486Y545506D01*
Y547922D01*
G01X356790Y407982D02*
Y487272D01*
X344392Y499670D01*
Y507662D01*
X342695Y509359D01*
Y511303D01*
X342951Y511559D01*
Y513841D01*
X342652Y514140D01*
Y516560D01*
X342951Y516859D01*
Y519241D01*
X342792Y519400D01*
Y530400D01*
X343092Y530700D01*
Y533100D01*
X342525Y533667D01*
Y535533D01*
X342865Y535873D01*
Y551954D01*
X344486Y553575D01*
Y555857D01*
G01X352790Y407700D02*
Y485612D01*
X351795Y486607D01*
X349985D01*
X348627Y487965D01*
Y489775D01*
X347269Y491133D01*
X345459D01*
X344101Y492491D01*
Y494301D01*
X338529Y499873D01*
X336783D01*
X336048Y500608D01*
Y502666D01*
X336692Y503310D01*
X338930D01*
X339730Y504110D01*
Y505710D01*
X338930Y506510D01*
X336692D01*
X335892Y507310D01*
Y511300D01*
X336366Y511774D01*
Y513726D01*
X335892Y514200D01*
Y516500D01*
X336292Y516900D01*
Y527700D01*
X336068Y527924D01*
Y530476D01*
X336156Y530564D01*
Y546277D01*
X337793Y547914D01*
G01X354790Y407727D02*
Y486442D01*
X342392Y498840D01*
Y506833D01*
X339692Y509533D01*
Y511500D01*
X339192Y512000D01*
Y513800D01*
X339792Y514400D01*
Y516500D01*
X339340Y516952D01*
Y527848D01*
X339507Y528015D01*
Y530485D01*
X339339Y530653D01*
Y532747D01*
X339418Y532826D01*
Y551926D01*
X341140Y553648D01*
Y555857D01*
G01X362790Y408331D02*
Y494801D01*
X353192Y504399D01*
Y511100D01*
X352171Y512121D01*
Y513379D01*
X353119Y514327D01*
Y516173D01*
X352692Y516600D01*
Y519800D01*
X352905Y520013D01*
Y539339D01*
X351692Y540552D01*
Y544100D01*
X349454Y546338D01*
Y549262D01*
X350575Y550383D01*
Y553119D01*
X351179Y553723D01*
Y555857D01*
G01X360790Y408385D02*
Y493972D01*
X348392Y506370D01*
Y510300D01*
X349792Y511700D01*
Y513700D01*
X349192Y514300D01*
Y516000D01*
X349792Y516600D01*
Y519000D01*
X349556Y519236D01*
Y533036D01*
X349292Y533300D01*
Y535800D01*
X349438Y535946D01*
Y543454D01*
X347833Y545059D01*
Y547922D01*
G01X321061Y555857D02*
Y566814D01*
G01X327754Y547914D02*
Y552462D01*
X329471Y554179D01*
Y570421D01*
X327754Y572138D01*
Y574757D01*
G01X324407Y555857D02*
Y566814D01*
G01X354526Y555857D02*
Y566821D01*
X354525Y566822D01*
G01X364790Y408465D02*
Y498700D01*
X363929Y499561D01*
X361231D01*
X360100Y500692D01*
Y501824D01*
X361218Y502942D01*
Y504074D01*
X360087Y505205D01*
X358955D01*
X358078Y504328D01*
X356464D01*
X354924Y505868D01*
Y510858D01*
X356072Y512006D01*
Y513464D01*
X355435Y514101D01*
Y516599D01*
X356692Y517856D01*
Y520250D01*
X355956Y520986D01*
Y523894D01*
X356692Y524630D01*
Y527400D01*
X356161Y527931D01*
Y530469D01*
X355742Y530888D01*
Y535890D01*
X356154Y536302D01*
Y542838D01*
X352892Y546100D01*
Y551800D01*
X354155Y553063D01*
Y555486D01*
X354526Y555857D01*
G01X354525Y547922D02*
X354526Y547923D01*
Y550592D01*
X355771Y551837D01*
Y554563D01*
X356205Y554997D01*
Y568343D01*
X354526Y570022D01*
Y574757D01*
G01X366790Y408694D02*
Y500114D01*
X365236Y501668D01*
Y505929D01*
X364105Y507060D01*
X357774D01*
X357070Y507764D01*
Y510678D01*
X357719Y511327D01*
Y514114D01*
X357244Y514589D01*
Y515858D01*
X358692Y517306D01*
Y526900D01*
X359792Y528000D01*
Y539268D01*
X358992Y540068D01*
Y542377D01*
X354525Y546844D01*
Y547922D01*
G01X351179Y555857D02*
Y566822D01*
G01X347833Y547922D02*
Y550592D01*
X348692Y551451D01*
Y553800D01*
X349556Y554664D01*
Y570040D01*
X347833Y571763D01*
Y574757D01*
G01X344486Y547922D02*
Y550074D01*
X346103Y551691D01*
Y557220D01*
X347649Y558766D01*
Y563773D01*
X346103Y565319D01*
Y568753D01*
X344486Y570370D01*
Y574757D01*
G01Y555857D02*
Y557536D01*
X343876Y558146D01*
X340379D01*
X339833Y558692D01*
Y559682D01*
X340507Y560356D01*
X345371D01*
X345939Y560924D01*
Y561914D01*
X345287Y562566D01*
X340613D01*
X339982Y563197D01*
Y564187D01*
X340571Y564776D01*
X343876D01*
X344486Y565386D01*
Y566822D01*
G01X337793Y547914D02*
Y550499D01*
X336054Y552238D01*
Y552934D01*
X334844Y554144D01*
X333748D01*
X332786Y555106D01*
Y567737D01*
X333908Y568859D01*
X334744D01*
X336323Y570438D01*
Y573287D01*
X337793Y574757D01*
G01X341140Y555857D02*
X340350D01*
X338149Y558058D01*
Y559559D01*
X337539Y560169D01*
X336251D01*
X335619Y560801D01*
Y561791D01*
X336207Y562379D01*
X337539D01*
X338149Y562989D01*
Y564378D01*
X337623Y564904D01*
X336676D01*
X336075Y565505D01*
Y567650D01*
X338368Y569943D01*
Y571427D01*
X339020Y572079D01*
X341063D01*
X341757Y571385D01*
Y567439D01*
X341140Y566822D01*
G01X404723Y54857D02*
Y54245D01*
X403060Y52582D01*
Y34348D01*
X404722Y32686D01*
Y28023D01*
X404723Y28022D01*
G01X380882Y191050D02*
Y104516D01*
X381672Y103726D01*
Y80820D01*
X383792Y78700D01*
Y53900D01*
X381672Y51780D01*
Y45992D01*
X378592Y42912D01*
Y39885D01*
X370426Y31719D01*
X364582D01*
X363346Y30483D01*
Y29233D01*
X364565Y28014D01*
G01X379822Y191170D02*
Y104076D01*
X380612Y103286D01*
Y80380D01*
X382732Y78260D01*
Y54340D01*
X380612Y52220D01*
Y46432D01*
X377532Y43352D01*
Y40325D01*
X369986Y32779D01*
X364142D01*
X362286Y30923D01*
Y29082D01*
X361218Y28014D01*
G01X392026Y192547D02*
Y125067D01*
X406192Y110901D01*
Y102500D01*
X412892Y95800D01*
Y91400D01*
X413215Y91077D01*
Y88823D01*
X412961Y88569D01*
Y86079D01*
X413215Y85825D01*
Y83824D01*
X413026Y83635D01*
Y72399D01*
X413156Y72269D01*
Y64764D01*
X412900Y64508D01*
Y59792D01*
X416382Y56310D01*
Y51344D01*
X419849Y47877D01*
Y45051D01*
X420475Y44425D01*
Y37621D01*
X419849Y36995D01*
Y33006D01*
X418788Y31945D01*
X417802D01*
X416673Y33074D01*
X415609D01*
X414762Y32227D01*
Y28021D01*
G01X398029Y54842D02*
X398819Y54052D01*
Y52954D01*
X398029Y52164D01*
Y49551D01*
X399752Y47828D01*
Y31959D01*
X398029Y30236D01*
Y28007D01*
G01X408069Y54842D02*
X406350Y53123D01*
Y40149D01*
X409789Y36710D01*
Y34986D01*
X410051Y34724D01*
Y29989D01*
X408069Y28007D01*
G01X385719Y200166D02*
Y110059D01*
X397592Y98186D01*
Y93781D01*
X400699Y90674D01*
Y89340D01*
X399392Y88033D01*
Y86330D01*
X400383Y85339D01*
Y83443D01*
X399392Y82452D01*
Y74813D01*
X399760Y74445D01*
Y66994D01*
X399765Y66971D01*
Y62966D01*
X400942Y58050D01*
X404135Y54857D01*
X404723D01*
G01X371346Y189046D02*
Y106423D01*
X369702Y104779D01*
X369699D01*
X368671Y103751D01*
Y102147D01*
X360730Y94206D01*
Y90944D01*
X360652Y90866D01*
Y86271D01*
X362952Y83971D01*
Y82591D01*
X363562Y81981D01*
X367030D01*
X368289Y80722D01*
Y78452D01*
X367088Y77251D01*
X363562D01*
X362952Y76641D01*
Y72176D01*
X364768Y70360D01*
X367472D01*
X369848Y67984D01*
Y62846D01*
X367258Y60256D01*
X365291D01*
X363446Y58411D01*
Y55961D01*
X364565Y54842D01*
G01X377946Y189046D02*
Y102279D01*
X378372Y101853D01*
Y49752D01*
X373844Y45224D01*
Y42599D01*
X371755Y40510D01*
X368881D01*
X367761Y41630D01*
Y42595D01*
X367025Y43331D01*
X364541D01*
X363346Y42136D01*
Y37161D01*
X364565Y35942D01*
G01X374646Y188846D02*
Y104826D01*
X372272Y102452D01*
Y72320D01*
X374472Y70120D01*
Y57491D01*
X368381Y51400D01*
X366391D01*
X363346Y48355D01*
Y47833D01*
X364265Y46914D01*
G01X370286Y188926D02*
Y106866D01*
X367611Y104191D01*
Y102587D01*
X359670Y94646D01*
Y91384D01*
X359592Y91306D01*
Y85831D01*
X361892Y83531D01*
Y82151D01*
X363122Y80921D01*
X366590D01*
X367229Y80282D01*
Y78892D01*
X366648Y78311D01*
X363122D01*
X361892Y77081D01*
Y71736D01*
X364328Y69300D01*
X367032D01*
X368788Y67544D01*
Y63286D01*
X366818Y61316D01*
X364851D01*
X362386Y58851D01*
Y56010D01*
X361218Y54842D01*
G01X376886Y188926D02*
Y101839D01*
X377312Y101413D01*
Y50192D01*
X372784Y45664D01*
Y43039D01*
X371315Y41570D01*
X369321D01*
X368821Y42070D01*
Y43035D01*
X367465Y44391D01*
X364101D01*
X362286Y42576D01*
Y37010D01*
X361218Y35942D01*
G01X373586Y188726D02*
Y105266D01*
X371212Y102892D01*
Y71880D01*
X373412Y69680D01*
Y57931D01*
X367941Y52460D01*
X365951D01*
X362286Y48795D01*
Y47682D01*
X361518Y46914D01*
G01X390516Y192316D02*
Y120974D01*
X391696Y119794D01*
X394469D01*
X395360Y118903D01*
Y117773D01*
X394355Y116769D01*
Y115639D01*
X395488Y114506D01*
X396618D01*
X397623Y115510D01*
X398753D01*
X399886Y114377D01*
Y113247D01*
X398881Y112243D01*
Y111113D01*
X400014Y109980D01*
X401144D01*
X402032Y110868D01*
X403199D01*
X403992Y110075D01*
Y101800D01*
X409953Y95839D01*
Y91761D01*
X409544Y91352D01*
Y88796D01*
X409920Y88420D01*
Y86428D01*
X409239Y85747D01*
Y82915D01*
X409793Y82361D01*
Y72408D01*
X410492Y71709D01*
Y67985D01*
X409803Y67296D01*
Y59817D01*
X414763Y54857D01*
G01X384136Y195798D02*
Y109272D01*
X387630Y105778D01*
Y104856D01*
X385944Y103170D01*
Y102339D01*
X387075Y101208D01*
X388508D01*
X389573Y102273D01*
X390705D01*
X391836Y101142D01*
Y100010D01*
X390603Y98777D01*
Y97595D01*
X391684Y96514D01*
X392866D01*
X393901Y97549D01*
X394840D01*
X395492Y96897D01*
Y89299D01*
X396623Y88168D01*
Y86731D01*
X395947Y86055D01*
Y84135D01*
X396938Y83144D01*
Y77756D01*
X395384Y76202D01*
Y73035D01*
X397487Y70932D01*
Y68023D01*
X396092Y66628D01*
Y62699D01*
X395420Y62027D01*
X392592D01*
X391792Y61227D01*
Y59627D01*
X392592Y58827D01*
X396968D01*
X398029Y57766D01*
Y54842D01*
G01X414763Y46922D02*
Y46219D01*
X413793Y45249D01*
X409535D01*
X408523Y44237D01*
Y40839D01*
X409189Y40173D01*
X411143D01*
X411643Y40673D01*
Y41628D01*
X412143Y42128D01*
X417113D01*
X417592Y41649D01*
Y39218D01*
X416688Y38314D01*
X415379D01*
X414763Y37698D01*
Y35957D01*
G01X389006Y191891D02*
Y118086D01*
X399392Y107700D01*
Y102390D01*
X406192Y95590D01*
Y91040D01*
X406522Y90710D01*
Y89218D01*
X406192Y88888D01*
Y85675D01*
X406692Y85175D01*
Y75101D01*
X406358Y74767D01*
Y71974D01*
X406522Y71810D01*
Y70318D01*
X406192Y69988D01*
Y66775D01*
X406336Y66631D01*
Y58256D01*
X407635Y56957D01*
X409087D01*
X409697Y56347D01*
Y53953D01*
X414763Y48887D01*
Y46922D01*
G01X387496Y199996D02*
Y111396D01*
X388480Y110412D01*
X389342D01*
X391112Y112182D01*
X391821D01*
X393295Y110708D01*
Y109951D01*
X391549Y108205D01*
Y107343D01*
X392894Y105998D01*
X393756D01*
X394657Y106899D01*
X395365D01*
X396864Y105400D01*
Y104692D01*
X395963Y103791D01*
Y102929D01*
X399875Y99017D01*
Y96685D01*
X401060Y95500D01*
X402203D01*
X403561Y94142D01*
Y92397D01*
X402692Y91528D01*
Y88621D01*
X403175Y88138D01*
Y86646D01*
X402692Y86163D01*
Y83300D01*
X403092Y82900D01*
Y80374D01*
X401962Y79244D01*
Y76502D01*
X403092Y75372D01*
Y73032D01*
X403093Y73029D01*
X402010Y71946D01*
Y68507D01*
X403040Y67477D01*
Y58953D01*
X407036Y54957D01*
X407954D01*
X408069Y54842D01*
G01X393948Y192984D02*
Y125975D01*
X410592Y109331D01*
Y101400D01*
X416788Y95204D01*
Y91912D01*
X415963Y91087D01*
Y89077D01*
X416666Y88374D01*
Y86374D01*
X416181Y85889D01*
Y83711D01*
X416398Y83494D01*
Y64594D01*
X416742Y64250D01*
Y58779D01*
X419844Y55677D01*
Y53748D01*
X420820Y52772D01*
X422124D01*
X423082Y51814D01*
Y34590D01*
X424801Y32871D01*
Y28007D01*
G01X394682Y49592D02*
X395892Y48382D01*
Y46200D01*
X396492Y45600D01*
Y37765D01*
X394684Y35957D01*
G01X382514Y195289D02*
Y106734D01*
X384278Y104970D01*
Y98414D01*
X386227Y96465D01*
X389113D01*
X392792Y92786D01*
Y65300D01*
X389692Y62200D01*
Y58800D01*
X392692Y55800D01*
Y51582D01*
X394682Y49592D01*
G01X397914Y195410D02*
Y127668D01*
X416821Y108761D01*
Y101471D01*
X423692Y94600D01*
Y92017D01*
X422688Y91013D01*
Y89035D01*
X423311Y88412D01*
Y86236D01*
X422666Y85591D01*
Y76426D01*
X423076Y76016D01*
Y71532D01*
X423639Y70969D01*
Y67449D01*
X423092Y66902D01*
Y58900D01*
X426418Y55574D01*
Y53674D01*
X426533Y53559D01*
Y34959D01*
X431494Y29998D01*
Y28007D01*
G01X404353Y195531D02*
Y132549D01*
X429792Y107110D01*
Y102180D01*
X436692Y95280D01*
Y91400D01*
X436092Y90800D01*
Y89300D01*
X436892Y88500D01*
Y86400D01*
X435992Y85500D01*
Y83500D01*
X436492Y83000D01*
Y72500D01*
X435992Y72000D01*
Y70300D01*
X436792Y69500D01*
Y67500D01*
X436558Y67266D01*
Y59930D01*
X439805Y56683D01*
Y49608D01*
X439813Y49600D01*
Y35079D01*
X444880Y30012D01*
Y28022D01*
G01X405992Y194366D02*
Y133740D01*
X431892Y107840D01*
Y102909D01*
X439452Y95349D01*
Y91740D01*
X440492Y90700D01*
Y89100D01*
X439258Y87866D01*
Y86734D01*
X440292Y85700D01*
Y75100D01*
X439828Y74636D01*
Y72264D01*
X440192Y71900D01*
Y70100D01*
X439292Y69200D01*
Y67500D01*
X439811Y66981D01*
Y59881D01*
X443256Y56436D01*
Y53164D01*
X442692Y52600D01*
Y48970D01*
X443256Y47607D01*
Y37583D01*
X444882Y35957D01*
G01X399537Y195507D02*
Y128875D01*
X418892Y109520D01*
Y102400D01*
X425692Y95600D01*
Y92199D01*
X426849Y91042D01*
Y89224D01*
X425849Y88224D01*
Y86474D01*
X426963Y85360D01*
Y83135D01*
X426520Y82692D01*
Y59816D01*
X431494Y54842D01*
G01X407617Y194172D02*
Y134945D01*
X436153Y106409D01*
Y105277D01*
X435000Y104124D01*
Y102992D01*
X436131Y101861D01*
X437263D01*
X438416Y103014D01*
X439548D01*
X440679Y101883D01*
Y100751D01*
X439526Y99598D01*
Y98466D01*
X440516Y97476D01*
X443806D01*
X444856Y96426D01*
Y92786D01*
X442689Y90619D01*
Y89350D01*
X443862Y88177D01*
Y86575D01*
X442566Y85279D01*
Y82264D01*
X443212Y81618D01*
X444499D01*
X445109Y81008D01*
Y79618D01*
X444499Y79008D01*
X443018D01*
X442407Y78397D01*
Y76033D01*
X443274Y75166D01*
Y71450D01*
X443884Y70840D01*
X444582D01*
X445192Y70230D01*
Y68840D01*
X444582Y68230D01*
X443884D01*
X443274Y67620D01*
Y64725D01*
X443884Y64115D01*
X444624D01*
X445234Y63505D01*
Y62115D01*
X444624Y61505D01*
X443884D01*
X443274Y60895D01*
Y59418D01*
X444880Y57812D01*
Y54859D01*
G01X409155Y194050D02*
Y136236D01*
X446832Y98559D01*
Y67401D01*
X446992Y67241D01*
Y53760D01*
X445178Y51946D01*
Y47220D01*
X444880Y46922D01*
G01X438189Y28022D02*
Y30103D01*
X433232Y35060D01*
Y48260D01*
X431713Y49779D01*
Y52143D01*
X433131Y53561D01*
Y56973D01*
X429773Y60331D01*
Y69852D01*
X429466Y70159D01*
Y72059D01*
X429754Y72347D01*
Y83186D01*
X429552Y83388D01*
Y85660D01*
X429997Y86105D01*
Y88543D01*
X429566Y88974D01*
Y91074D01*
X429979Y91487D01*
Y94813D01*
X423692Y101100D01*
Y107550D01*
X401250Y129992D01*
Y195652D01*
G01X395749Y192972D02*
Y127004D01*
X412592Y110161D01*
Y102300D01*
X419592Y95300D01*
Y91631D01*
X420149Y91074D01*
Y75359D01*
X419844Y75054D01*
Y72664D01*
X419861Y72647D01*
Y71783D01*
X419549Y71471D01*
Y67459D01*
X419842Y67166D01*
Y64650D01*
X418972Y63780D01*
Y60120D01*
X424250Y54842D01*
X424801D01*
G01X438187Y54859D02*
X433219Y59827D01*
Y66670D01*
X431736Y68153D01*
Y71163D01*
X433200Y72627D01*
Y85740D01*
X432971Y85969D01*
Y88479D01*
X433339Y88847D01*
Y91101D01*
X432653Y91787D01*
Y95139D01*
X425692Y102100D01*
Y108380D01*
X402806Y131266D01*
Y195555D01*
G01X422390Y178498D02*
Y145331D01*
X437811Y129910D01*
Y129118D01*
X436340Y127647D01*
X435548D01*
X432464Y130731D01*
X431672D01*
X430162Y129221D01*
Y128429D01*
X460066Y98525D01*
Y92011D01*
X458983Y90928D01*
Y86718D01*
X460333Y85368D01*
Y73341D01*
X458983Y71991D01*
Y67409D01*
X460133Y66259D01*
Y65020D01*
X456992Y61879D01*
Y56231D01*
X458266Y54957D01*
G01X424890Y178501D02*
Y146367D01*
X447075Y124182D01*
Y123114D01*
X445880Y121919D01*
X444813D01*
X442033Y124699D01*
X441241D01*
X440020Y123478D01*
Y122686D01*
X462833Y99873D01*
Y64442D01*
X460333Y61942D01*
Y54542D01*
X458839Y53048D01*
Y51987D01*
X460912Y49914D01*
G01X417666Y178774D02*
Y142494D01*
X425110Y135050D01*
Y134040D01*
X423857Y132787D01*
X422847D01*
X421959Y133675D01*
X421167D01*
X419827Y132335D01*
Y131543D01*
X453992Y97378D01*
Y96600D01*
X452692Y95300D01*
Y94600D01*
X453992Y93300D01*
Y92577D01*
X452633Y91218D01*
Y86418D01*
X453633Y85418D01*
Y73103D01*
X452633Y72103D01*
Y67159D01*
X453373Y66419D01*
Y64482D01*
X451573Y62682D01*
Y54957D01*
G01X454619Y49564D02*
X452769Y51414D01*
Y53178D01*
X454292Y54701D01*
Y62301D01*
X456466Y64475D01*
Y66636D01*
X456483Y66653D01*
Y72853D01*
X456133Y73203D01*
Y86118D01*
X456483Y86468D01*
Y89857D01*
X456469Y89871D01*
Y91102D01*
X456466Y91105D01*
Y98590D01*
X425792Y129264D01*
Y130735D01*
X428992Y133935D01*
Y135193D01*
X419890Y144295D01*
Y178501D01*
G01X404723Y555857D02*
Y554445D01*
X403065Y552787D01*
Y545995D01*
X399744Y542674D01*
Y519552D01*
X399492Y519300D01*
Y516900D01*
X400492Y515900D01*
Y514700D01*
X399492Y513700D01*
Y511700D01*
X399992Y511200D01*
Y509416D01*
X397620Y507044D01*
Y500098D01*
X386192Y488670D01*
Y406737D01*
G01X364565Y566814D02*
X363333Y568046D01*
Y569747D01*
X364206Y570620D01*
X366254D01*
X366701Y570173D01*
X368531D01*
X368978Y570620D01*
X371044D01*
X371833Y569831D01*
Y569224D01*
X373127Y567930D01*
X373734D01*
X375017Y566647D01*
Y566019D01*
X376311Y564725D01*
X376939D01*
X377732Y563932D01*
Y562102D01*
X377284Y561654D01*
Y559824D01*
X377732Y559376D01*
Y557546D01*
X377284Y557098D01*
Y555268D01*
X377732Y554820D01*
Y550540D01*
X378612Y549660D01*
Y537166D01*
X378164Y536718D01*
Y534888D01*
X378612Y534440D01*
Y532610D01*
X378164Y532162D01*
Y530332D01*
X378612Y529884D01*
Y528054D01*
X378164Y527606D01*
Y525776D01*
X378612Y525328D01*
Y523498D01*
X378164Y523050D01*
Y521220D01*
X378612Y520772D01*
Y516038D01*
X377458Y514884D01*
X376602D01*
X375482Y513764D01*
Y511274D01*
X376602Y510154D01*
X377511D01*
X378319Y509346D01*
Y508044D01*
X375244Y504969D01*
Y409402D01*
G01X372212Y409466D02*
Y520219D01*
X373936Y521943D01*
Y524433D01*
X373488Y524881D01*
Y526711D01*
X373936Y527159D01*
Y528989D01*
X373488Y529437D01*
Y531267D01*
X373936Y531715D01*
Y533545D01*
X373488Y533993D01*
Y535823D01*
X373936Y536271D01*
Y538101D01*
X373488Y538549D01*
Y540379D01*
X373936Y540827D01*
Y542657D01*
X373488Y543105D01*
Y544935D01*
X373936Y545383D01*
Y547213D01*
X373488Y547661D01*
Y549491D01*
X373936Y549939D01*
Y551769D01*
X373488Y552217D01*
Y554047D01*
X373936Y554495D01*
Y556325D01*
X373116Y557145D01*
X372603Y557146D01*
X371473Y558276D01*
Y558788D01*
X370741Y559520D01*
X369283D01*
X368837Y559074D01*
X367007D01*
X366561Y559520D01*
X364447D01*
X363295Y558368D01*
Y557112D01*
X364565Y555842D01*
G01X378666Y409306D02*
Y485929D01*
X378218Y486377D01*
Y488207D01*
X378666Y488655D01*
Y490485D01*
X378218Y490933D01*
Y492763D01*
X378666Y493211D01*
Y495041D01*
X378218Y495489D01*
Y497319D01*
X378666Y497767D01*
Y499597D01*
X381816Y502747D01*
Y504613D01*
X381404Y505025D01*
Y506855D01*
X381816Y507267D01*
Y511551D01*
X381439Y511928D01*
Y513758D01*
X381816Y514135D01*
Y551730D01*
X381404Y552142D01*
Y553972D01*
X381816Y554384D01*
Y556160D01*
X380632Y557344D01*
Y565502D01*
X380309Y565825D01*
Y567655D01*
X380632Y567978D01*
Y569629D01*
X377985Y572276D01*
X377352D01*
X376057Y573571D01*
Y574204D01*
X374763Y575498D01*
X374130D01*
X372835Y576793D01*
Y577426D01*
X371541Y578720D01*
X369353D01*
X368905Y578272D01*
X367075D01*
X366627Y578720D01*
X364797D01*
X363504Y577427D01*
Y575803D01*
X364565Y574742D01*
G01X368910Y409472D02*
Y502296D01*
X368462Y502744D01*
Y504574D01*
X368910Y505022D01*
Y506852D01*
X368462Y507300D01*
Y509130D01*
X368910Y509578D01*
Y511408D01*
X368462Y511856D01*
Y513686D01*
X368910Y514134D01*
Y515964D01*
X367553Y517321D01*
X364867D01*
X363433Y518755D01*
Y522050D01*
X364758Y523375D01*
X365663D01*
X366083Y523795D01*
X367913D01*
X368333Y523375D01*
X369244D01*
X370112Y524243D01*
Y525540D01*
X369665Y525987D01*
Y527817D01*
X370112Y528264D01*
Y529840D01*
X369664Y530288D01*
Y532118D01*
X370112Y532566D01*
Y534396D01*
X369664Y534844D01*
Y536674D01*
X370112Y537122D01*
Y538450D01*
X369502Y539060D01*
X368447D01*
X368000Y538613D01*
X366170D01*
X365723Y539060D01*
X364501D01*
X363235Y540326D01*
Y542596D01*
X364429Y543790D01*
X365668D01*
X366114Y544236D01*
X367944D01*
X368390Y543790D01*
X369502D01*
X370112Y544400D01*
Y548180D01*
X366852Y551440D01*
X364028D01*
X363072Y550484D01*
Y549107D01*
X364265Y547914D01*
G01X376304Y409402D02*
Y504529D01*
X379379Y507604D01*
Y509786D01*
X377951Y511214D01*
X377042D01*
X376542Y511714D01*
Y513324D01*
X377042Y513824D01*
X377898D01*
X379672Y515598D01*
Y550100D01*
X378792Y550980D01*
Y564372D01*
X371484Y571680D01*
X363766D01*
X362273Y570187D01*
Y567869D01*
X361218Y566814D01*
G01X373272Y409466D02*
Y519779D01*
X374996Y521503D01*
Y556768D01*
X371184Y560580D01*
X364007D01*
X362235Y558808D01*
Y556859D01*
X361320Y555944D01*
Y555842D01*
G01X379726Y409186D02*
Y499157D01*
X382876Y502307D01*
Y556600D01*
X381692Y557784D01*
Y570072D01*
X371984Y579780D01*
X364357D01*
X362444Y577867D01*
Y575968D01*
X361218Y574742D01*
G01X361518Y547914D02*
X362012Y548408D01*
Y550924D01*
X363588Y552500D01*
X367292D01*
X371172Y548620D01*
Y543960D01*
X369942Y542730D01*
X364869D01*
X364295Y542156D01*
Y540766D01*
X364941Y540120D01*
X369942D01*
X371172Y538890D01*
Y523803D01*
X369684Y522315D01*
X365198D01*
X364493Y521610D01*
Y519195D01*
X365307Y518381D01*
X367993D01*
X369970Y516404D01*
Y409511D01*
G01X414763Y566822D02*
Y559640D01*
X413078Y557955D01*
X410986D01*
X409683Y556652D01*
Y554143D01*
X409892Y553934D01*
Y549200D01*
X409779Y549087D01*
Y546587D01*
X406992Y543800D01*
Y538700D01*
X406356Y538064D01*
Y535864D01*
X405945Y535453D01*
Y531047D01*
X406349Y530643D01*
Y527006D01*
X405139Y525796D01*
Y524189D01*
X405943Y523385D01*
X407845D01*
X408455Y522775D01*
Y521385D01*
X407845Y520775D01*
X406217D01*
X405607Y520165D01*
Y517485D01*
X406592Y516500D01*
Y514300D01*
X406192Y513900D01*
Y511600D01*
X407492Y510300D01*
Y508288D01*
X406304Y507100D01*
X403334D01*
X401894Y505660D01*
Y504528D01*
X403292Y503130D01*
Y500111D01*
X399386Y496205D01*
X399387D01*
X390192Y487010D01*
Y406540D01*
G01X400192Y407615D02*
Y478476D01*
X412222Y490506D01*
Y494894D01*
X422647Y505319D01*
Y511255D01*
X423592Y512200D01*
Y513700D01*
X422892Y514400D01*
Y516300D01*
X423392Y516800D01*
Y519300D01*
X423092Y519600D01*
Y530400D01*
X423492Y530800D01*
Y535190D01*
X423076Y535606D01*
Y543384D01*
X426528Y546836D01*
Y548964D01*
X426092Y549400D01*
Y551244D01*
X429871Y555023D01*
Y565184D01*
X431494Y566807D01*
G01X444880Y566822D02*
X443092Y565034D01*
Y557400D01*
X443248Y557244D01*
Y554856D01*
X439810Y551418D01*
Y546818D01*
X436475Y543483D01*
Y532917D01*
X436519Y532873D01*
Y519673D01*
X436692Y519500D01*
Y516900D01*
X436292Y516500D01*
Y514400D01*
X436692Y514000D01*
Y511700D01*
X436328Y511336D01*
Y507684D01*
X420222Y491578D01*
Y487856D01*
X408192Y475826D01*
Y405358D01*
G01X414192Y406826D02*
Y473230D01*
X446797Y505835D01*
Y510895D01*
X445892Y511800D01*
Y513600D01*
X446797Y514505D01*
Y519750D01*
X446485Y520062D01*
Y530307D01*
X446570Y530392D01*
Y538778D01*
X446992Y539200D01*
Y548500D01*
X445792Y549700D01*
Y551200D01*
X446792Y552200D01*
Y557300D01*
X447292Y557800D01*
Y567300D01*
X444880Y569712D01*
Y574755D01*
X444882Y574757D01*
G01X414763Y555857D02*
X413100Y554194D01*
Y546908D01*
X409793Y543601D01*
Y535799D01*
X409992Y535600D01*
Y530700D01*
X409779Y530487D01*
Y527213D01*
X410192Y526800D01*
Y517300D01*
X409492Y516600D01*
Y514200D01*
X409992Y513700D01*
Y511500D01*
X409581Y511089D01*
Y509401D01*
X410799Y508183D01*
Y506456D01*
X409521Y505178D01*
X407636D01*
X406443Y503985D01*
Y502611D01*
X406967Y502087D01*
Y500955D01*
X396297Y490285D01*
Y489153D01*
X398005Y487445D01*
Y486313D01*
X396874Y485182D01*
X395742D01*
X394034Y486890D01*
X392902D01*
X392192Y486180D01*
Y406612D01*
G01X402192Y407687D02*
Y477868D01*
X414222Y489898D01*
Y494065D01*
X426892Y506735D01*
Y510850D01*
X425912Y511830D01*
Y513090D01*
X427343Y514521D01*
Y516149D01*
X425720Y517772D01*
Y521440D01*
X426514Y522234D01*
Y530451D01*
X427012Y530949D01*
Y534647D01*
X426514Y535145D01*
Y543922D01*
X429776Y547184D01*
Y551446D01*
X431494Y553164D01*
Y555842D01*
G01X410192Y405805D02*
Y475109D01*
X422222Y487139D01*
Y490749D01*
X440372Y508899D01*
Y510920D01*
X439273Y512019D01*
Y513381D01*
X440292Y514400D01*
Y516200D01*
X439810Y516682D01*
Y530682D01*
X439795Y530697D01*
Y543303D01*
X443263Y546771D01*
Y551547D01*
X444880Y553164D01*
Y555859D01*
G01X412192Y406100D02*
Y473892D01*
X442592Y504292D01*
Y510900D01*
X443333Y511641D01*
Y513859D01*
X443080Y514112D01*
Y516688D01*
X443333Y516941D01*
Y519459D01*
X443240Y519552D01*
Y530548D01*
X443263Y530571D01*
Y543771D01*
X444880Y545388D01*
Y547922D01*
G01X398029Y555842D02*
Y550863D01*
X396229Y549063D01*
Y547053D01*
X396321Y546961D01*
Y532971D01*
X396585Y532707D01*
Y529995D01*
X396314Y529724D01*
Y518662D01*
X395333Y517681D01*
Y515259D01*
X396998Y513594D01*
Y512006D01*
X395492Y510500D01*
Y508002D01*
X393151Y505661D01*
Y504529D01*
X395620Y502060D01*
Y500928D01*
X394489Y499797D01*
X393357D01*
X390977Y502177D01*
X390269D01*
X388714Y500622D01*
Y499914D01*
X391094Y497534D01*
Y496402D01*
X389963Y495271D01*
X388831D01*
X386471Y497631D01*
X385521D01*
X384192Y496302D01*
Y495188D01*
X386236Y493144D01*
Y491202D01*
X384192Y489158D01*
Y406734D01*
G01X394192Y406684D02*
Y480353D01*
X400136Y486297D01*
Y491295D01*
X401577Y492736D01*
X402440D01*
X404048Y491128D01*
X404889D01*
X405873Y492112D01*
Y492994D01*
X404285Y494582D01*
Y495444D01*
X413492Y504651D01*
Y510800D01*
X412892Y511400D01*
Y514200D01*
X413292Y514600D01*
Y516100D01*
X412892Y516500D01*
Y527700D01*
X413129Y527937D01*
Y530363D01*
X412892Y530600D01*
Y532700D01*
X413026Y532834D01*
Y543499D01*
X414763Y545236D01*
Y547922D01*
G01X408069Y555842D02*
Y554398D01*
X406341Y552670D01*
Y546449D01*
X403092Y543200D01*
Y535300D01*
X403050Y535258D01*
Y519642D01*
X403392Y519300D01*
Y516900D01*
X402692Y516200D01*
Y514400D01*
X403292Y513800D01*
Y511800D01*
X402792Y511300D01*
Y509387D01*
X399620Y506215D01*
Y503973D01*
X401292Y502301D01*
Y500940D01*
X388192Y487840D01*
Y406629D01*
G01X396192Y406935D02*
Y479634D01*
X408092Y491534D01*
Y496422D01*
X415792Y504122D01*
Y510700D01*
X416892Y511800D01*
Y513900D01*
X416292Y514500D01*
Y516400D01*
X416692Y516800D01*
Y527600D01*
X416398Y527894D01*
Y535690D01*
X416390Y535698D01*
Y543198D01*
X419813Y546621D01*
Y549179D01*
X419592Y549400D01*
Y552738D01*
X420681Y553827D01*
X421931D01*
X423120Y555016D01*
Y565126D01*
X424801Y566807D01*
G01X404192Y407669D02*
Y477262D01*
X416222Y489292D01*
Y493236D01*
X428992Y506006D01*
Y510400D01*
X429992Y511400D01*
Y514100D01*
X429392Y514700D01*
Y516400D01*
X430127Y517135D01*
Y519365D01*
X429789Y519703D01*
Y533103D01*
X429760Y533132D01*
Y543068D01*
X433213Y546521D01*
Y548831D01*
X435725Y551343D01*
Y554033D01*
X436548Y554856D01*
Y565181D01*
X438189Y566822D01*
G01X398192Y407132D02*
Y478968D01*
X410222Y490998D01*
Y495723D01*
X419862Y505363D01*
Y511230D01*
X419494Y511598D01*
Y513902D01*
X419935Y514343D01*
Y516557D01*
X419555Y516937D01*
Y527563D01*
X419829Y527837D01*
Y529963D01*
X419592Y530200D01*
Y535326D01*
X419829Y535563D01*
Y543637D01*
X423090Y546898D01*
Y548898D01*
X423992Y549800D01*
Y552453D01*
X424801Y553262D01*
Y555842D01*
G01X438187Y555859D02*
Y550795D01*
X436504Y549112D01*
Y546812D01*
X433227Y543535D01*
Y535827D01*
X431773Y534373D01*
Y531619D01*
X433213Y530179D01*
Y519721D01*
X432916Y519424D01*
Y517176D01*
X433364Y516728D01*
Y514372D01*
X432892Y513900D01*
Y511500D01*
X433280Y511112D01*
Y507465D01*
X418222Y492407D01*
Y488630D01*
X406192Y476600D01*
Y405734D01*
G01X382192Y407043D02*
Y496600D01*
X387992Y502400D01*
Y503600D01*
X392882Y508490D01*
Y548792D01*
X394682Y550592D01*
G01X404723Y555857D02*
Y566822D01*
G01X398029Y555842D02*
Y566807D01*
G01X414763Y547922D02*
X416376Y549535D01*
Y571016D01*
X414761Y572631D01*
X414763Y572633D01*
Y574757D01*
G01X408069Y555842D02*
X407183D01*
X406373Y556652D01*
Y561287D01*
X407149Y562063D01*
X408111D01*
X408668Y561506D01*
Y560251D01*
X409278Y559641D01*
X411882D01*
X412523Y560282D01*
Y563720D01*
X411809Y564434D01*
X407090D01*
X406480Y565044D01*
Y566132D01*
X407155Y566807D01*
X408069D01*
G01X394682Y550592D02*
Y553090D01*
X396395Y554803D01*
Y557197D01*
X395792Y557800D01*
Y567800D01*
X396692Y568700D01*
Y570300D01*
X394682Y572310D01*
Y574755D01*
X394684Y574757D01*
G01X460912Y49914D02*
X462385Y48441D01*
Y35316D01*
X463001Y34700D01*
Y33356D01*
X461545Y31900D01*
X460145D01*
X458266Y30021D01*
Y27899D01*
G01X451573D02*
Y29453D01*
X453820Y31700D01*
X455044D01*
X456620Y33276D01*
Y34900D01*
X455845Y35675D01*
Y48348D01*
X454629Y49564D01*
X454619D01*
G01X478344Y49914D02*
X479733Y48525D01*
Y35512D01*
X480345Y34900D01*
Y33500D01*
X478545Y31700D01*
X477545D01*
X476245Y30400D01*
Y29146D01*
X474998Y27899D01*
G01X464732Y52100D02*
X467838Y48994D01*
Y32848D01*
X466510Y31520D01*
X465528D01*
X464758Y30750D01*
G01X464732Y49500D02*
X465831D01*
X466778Y48553D01*
Y46020D01*
X465808Y45050D01*
X465460D01*
X464844Y44434D01*
Y43102D01*
X465346Y42600D01*
X466058D01*
X466778Y41880D01*
Y40920D01*
X465958Y40100D01*
X465458D01*
X464858Y39500D01*
Y38500D01*
X466778Y36580D01*
Y33291D01*
X466067Y32580D01*
X465551D01*
X464732Y33399D01*
G01X469832Y52314D02*
X473024Y49122D01*
Y33732D01*
X469832Y30540D01*
G01X458266Y54957D02*
X457145Y53836D01*
Y50900D01*
X460045Y48000D01*
Y46032D01*
X458512Y44499D01*
Y43300D01*
X459762Y42050D01*
Y41150D01*
X458412Y39800D01*
Y38501D01*
X460045Y36868D01*
Y34567D01*
X460912Y33700D01*
G01X451573Y54957D02*
X450645Y54029D01*
Y50901D01*
X453445Y48101D01*
Y46232D01*
X452062Y44849D01*
Y43450D01*
X453512Y42000D01*
Y40800D01*
X452012Y39300D01*
Y38101D01*
X453445Y36668D01*
Y34788D01*
X454533Y33700D01*
G01X474998Y54957D02*
X474070Y54029D01*
Y50901D01*
X477112Y47859D01*
Y46474D01*
X475437Y44799D01*
Y43676D01*
X476937Y42176D01*
Y40824D01*
X475437Y39324D01*
Y38101D01*
X476870Y36668D01*
Y35574D01*
X478344Y34100D01*
G01X435698Y179831D02*
Y150195D01*
X458438Y127455D01*
Y126324D01*
X457769Y125655D01*
Y124525D01*
X458902Y123392D01*
X460801D01*
X462295Y121898D01*
Y119999D01*
X463428Y118866D01*
X464558D01*
X465227Y119536D01*
X466357D01*
X467490Y118403D01*
Y117272D01*
X466821Y116603D01*
Y115473D01*
X467954Y114340D01*
X469084D01*
X469753Y115010D01*
X470883D01*
X472016Y113877D01*
Y112746D01*
X471347Y112077D01*
Y110947D01*
X472480Y109814D01*
X473610D01*
X474279Y110484D01*
X475409D01*
X475892Y110001D01*
Y94600D01*
X476833Y93659D01*
Y91618D01*
X476433Y91218D01*
Y86518D01*
X477233Y85718D01*
Y73341D01*
X476433Y72541D01*
Y66903D01*
X476798Y66538D01*
Y64306D01*
X475992Y63500D01*
Y61700D01*
X476798Y60894D01*
Y59407D01*
X474239Y56848D01*
Y55716D01*
X474998Y54957D01*
G01X438210Y179831D02*
X438267Y179774D01*
Y151226D01*
X479592Y109901D01*
Y108300D01*
X478392Y107100D01*
Y96000D01*
X479891Y94501D01*
Y91660D01*
X480533Y91018D01*
Y86518D01*
X479733Y85718D01*
Y73059D01*
X480633Y72159D01*
Y67253D01*
X479891Y66511D01*
Y57640D01*
X477983Y55732D01*
Y55160D01*
X476433Y53610D01*
Y51825D01*
X478344Y49914D01*
G01X428781Y179041D02*
Y176959D01*
X429281Y176459D01*
Y175459D01*
X428781Y174959D01*
Y147683D01*
X450772Y125692D01*
Y122350D01*
X451973Y121149D01*
Y121146D01*
X453172Y119947D01*
Y116537D01*
X455443Y114266D01*
X458425D01*
X460386Y112305D01*
Y110202D01*
X459168Y108984D01*
Y107752D01*
X460935Y105985D01*
X462166D01*
X463596Y107415D01*
X465707D01*
X468100Y105022D01*
Y102912D01*
X466668Y101481D01*
Y99396D01*
X467813Y98251D01*
Y82820D01*
X468433Y82200D01*
Y81200D01*
X467813Y80580D01*
Y79820D01*
X468433Y79200D01*
Y78200D01*
X467813Y77580D01*
Y76820D01*
X468433Y76200D01*
Y75200D01*
X467812Y74579D01*
Y63488D01*
X463938Y59614D01*
Y57420D01*
X464658Y56700D01*
X465658D01*
X466458Y55900D01*
Y53826D01*
X464732Y52100D01*
G01X469832Y49714D02*
Y49715D01*
X470930D01*
X471964Y48681D01*
Y45906D01*
X471258Y45200D01*
X470744D01*
X470044Y44500D01*
Y43500D01*
X470744Y42800D01*
X471244D01*
X471964Y42080D01*
Y40707D01*
X471157Y39900D01*
X470459D01*
X469858Y39299D01*
Y38101D01*
X470459Y37500D01*
X471257D01*
X471964Y36793D01*
Y34172D01*
X470941Y33149D01*
X469832D01*
G01X432059Y179495D02*
Y177155D01*
X431559Y176655D01*
Y175655D01*
X432059Y175155D01*
Y173906D01*
X431559Y173406D01*
Y172406D01*
X432059Y171906D01*
Y148465D01*
X453912Y126612D01*
Y123174D01*
X471853Y105233D01*
Y63194D01*
X468078Y59419D01*
Y51468D01*
X469832Y49714D01*
G01X427721Y179041D02*
Y147243D01*
X449712Y125252D01*
Y121910D01*
X451222Y120400D01*
Y120397D01*
X452112Y119507D01*
Y116097D01*
X455003Y113206D01*
X457985D01*
X459326Y111865D01*
Y110642D01*
X458108Y109424D01*
Y107312D01*
X460495Y104925D01*
X462609D01*
X464039Y106355D01*
X465264D01*
X467040Y104579D01*
Y103356D01*
X465608Y101924D01*
Y98953D01*
X466752Y97809D01*
Y63931D01*
X462878Y60057D01*
Y51354D01*
X464732Y49500D01*
G01X433119Y179495D02*
Y148905D01*
X454972Y127052D01*
Y123617D01*
X472913Y105676D01*
Y77120D01*
X473533Y76500D01*
Y75500D01*
X472913Y74880D01*
Y62751D01*
X472019Y61857D01*
Y60981D01*
X471311Y60273D01*
X470435D01*
X469138Y58976D01*
Y57554D01*
X469892Y56800D01*
X471092D01*
X471658Y56234D01*
Y54140D01*
X469832Y52314D01*
G01X440710Y179831D02*
X440767Y179774D01*
Y171799D01*
X441377Y171189D01*
X442532D01*
X443092Y170629D01*
Y168639D01*
X442532Y168079D01*
X441377D01*
X440767Y167469D01*
Y152325D01*
X483983Y109109D01*
Y100905D01*
X483183Y100105D01*
X482102D01*
X481542Y99545D01*
Y97465D01*
X482102Y96905D01*
X483183D01*
X483983Y96105D01*
Y92068D01*
X483033Y91118D01*
Y86418D01*
X483633Y85818D01*
Y73041D01*
X483133Y72541D01*
Y66803D01*
X483933Y66003D01*
Y57819D01*
X481691Y55577D01*
Y54957D01*
G01X443210Y179831D02*
X443267Y179774D01*
Y176219D01*
X445970Y173516D01*
Y165039D01*
X443267Y162336D01*
Y153425D01*
X486483Y110209D01*
Y91668D01*
X487133Y91018D01*
Y86618D01*
X486433Y85918D01*
Y73059D01*
X487033Y72459D01*
Y67053D01*
X486483Y66503D01*
Y56768D01*
X483133Y53418D01*
Y51818D01*
X485037Y49914D01*
G01X495077Y17157D02*
Y24786D01*
X496944Y26653D01*
Y28447D01*
X495794Y29597D01*
Y34203D01*
X497144Y35553D01*
Y47564D01*
X495794Y48914D01*
Y53102D01*
X497144Y54452D01*
Y66047D01*
X495794Y67397D01*
Y72103D01*
X497144Y73453D01*
Y85364D01*
X495794Y86714D01*
Y90914D01*
X497144Y92264D01*
Y104796D01*
X495766Y106174D01*
Y110374D01*
X497092Y111700D01*
Y113472D01*
X481095Y129469D01*
Y130601D01*
X483727Y133233D01*
Y134365D01*
X482596Y135496D01*
X481464D01*
X480326Y134358D01*
X479534D01*
X477952Y135940D01*
Y136732D01*
X479090Y137870D01*
Y139002D01*
X477959Y140133D01*
X476827D01*
X474889Y138195D01*
X474097D01*
X472438Y139854D01*
Y140646D01*
X474470Y142678D01*
Y143810D01*
X454692Y163588D01*
Y184800D01*
G01X497723Y12114D02*
X495861Y13976D01*
Y15369D01*
X497184Y16692D01*
Y23393D01*
X499644Y25853D01*
Y114456D01*
X490392Y123708D01*
Y125600D01*
X492692Y127900D01*
Y129124D01*
X491406Y130410D01*
X489682D01*
X488011Y132081D01*
Y133805D01*
X457192Y164624D01*
Y184900D01*
G01X488384Y17157D02*
Y25256D01*
X490344Y27216D01*
Y28447D01*
X489444Y29347D01*
Y34299D01*
X490444Y35299D01*
Y47614D01*
X489444Y48614D01*
Y53414D01*
X490344Y54314D01*
Y66247D01*
X489444Y67147D01*
Y72099D01*
X490444Y73099D01*
Y85414D01*
X489444Y86414D01*
Y91214D01*
X490492Y92262D01*
Y105200D01*
X489392Y106300D01*
Y110300D01*
X490492Y111400D01*
Y113200D01*
X488792Y114900D01*
X488592D01*
X460192Y143300D01*
Y144898D01*
X462685Y147391D01*
Y148523D01*
X461410Y149798D01*
X460278D01*
X458632Y148152D01*
X457840D01*
X456369Y149623D01*
Y150415D01*
X458015Y152061D01*
Y153193D01*
X456884Y154324D01*
X455752D01*
X454306Y152878D01*
X453514D01*
X452043Y154349D01*
Y155141D01*
X453489Y156587D01*
Y157719D01*
X449692Y161516D01*
Y183700D01*
G01X491430Y12114D02*
X489444Y14100D01*
Y15514D01*
X491192Y17262D01*
Y24368D01*
X493277Y26453D01*
Y28832D01*
X493294Y28849D01*
Y35049D01*
X492944Y35399D01*
Y48314D01*
X493294Y48664D01*
Y53614D01*
X493044Y53864D01*
Y66399D01*
X493294Y66649D01*
Y72849D01*
X492944Y73199D01*
Y86114D01*
X493230Y86400D01*
Y91478D01*
X493127Y91581D01*
Y105961D01*
X493292Y106126D01*
Y111000D01*
X492992Y111300D01*
Y114036D01*
X468392Y138636D01*
Y140136D01*
X470824Y142568D01*
Y143920D01*
X469616Y145128D01*
X468484D01*
X467020Y143664D01*
X466228D01*
X464757Y145135D01*
Y145927D01*
X466221Y147391D01*
Y148523D01*
X452192Y162552D01*
Y184000D01*
G01X501544Y14300D02*
X503270Y16026D01*
Y18100D01*
X502470Y18900D01*
X501470D01*
X500750Y19620D01*
Y20688D01*
X504624Y24562D01*
Y36580D01*
X505244Y37200D01*
Y38200D01*
X504624Y38820D01*
Y39580D01*
X505244Y40200D01*
Y41200D01*
X504624Y41820D01*
Y118695D01*
X505190Y119261D01*
Y121490D01*
X502915Y123765D01*
X500690D01*
X498663Y121738D01*
X497622D01*
X495759Y123601D01*
Y124830D01*
X497870Y126941D01*
Y129154D01*
X471699Y155325D01*
Y155961D01*
X470991Y156669D01*
X470355D01*
X469648Y157376D01*
Y158012D01*
X468940Y158720D01*
X468304D01*
X467373Y159651D01*
Y160287D01*
X466665Y160995D01*
X466029D01*
X465293Y161731D01*
Y162367D01*
X464585Y163075D01*
X463949D01*
X462906Y164118D01*
Y164754D01*
X462198Y165462D01*
X461562D01*
X460855Y166169D01*
Y170112D01*
X461305Y170562D01*
Y171562D01*
X460855Y172012D01*
Y173012D01*
X461305Y173462D01*
Y174462D01*
X460855Y174912D01*
Y175912D01*
X461305Y176362D01*
Y177362D01*
X460855Y177812D01*
Y178812D01*
X461305Y179262D01*
Y180262D01*
X460855Y180712D01*
Y182127D01*
X461305Y182577D01*
Y183577D01*
X460855Y184027D01*
Y186124D01*
G01X506644Y14514D02*
X508470Y16340D01*
Y17900D01*
X506450Y19920D01*
Y20788D01*
X507424Y21762D01*
X508300D01*
X509008Y22470D01*
Y23346D01*
X509889Y24227D01*
Y37080D01*
X510509Y37700D01*
Y38700D01*
X509889Y39320D01*
Y113934D01*
X509072Y114751D01*
Y123352D01*
X464764Y167660D01*
Y186124D01*
G01X501544Y11700D02*
X499690Y13554D01*
Y21131D01*
X503564Y25005D01*
Y119138D01*
X504130Y119704D01*
Y121050D01*
X502475Y122705D01*
X501130D01*
X499103Y120678D01*
X497182D01*
X494699Y123161D01*
Y125270D01*
X496810Y127381D01*
Y128714D01*
X459795Y165729D01*
Y186124D01*
G01X506644Y11914D02*
X504920Y13638D01*
Y18529D01*
X505390Y18999D01*
Y21231D01*
X508829Y24670D01*
Y113491D01*
X508012Y114308D01*
Y122909D01*
X463704Y167217D01*
Y186124D01*
G01X482292Y195894D02*
X500156Y178030D01*
X508882D01*
X545546Y141366D01*
Y139720D01*
X542968Y137142D01*
Y136010D01*
X544099Y134879D01*
X545231D01*
X546801Y136449D01*
X547593D01*
X549259Y134783D01*
Y133991D01*
X547692Y132424D01*
Y131286D01*
X571992Y106986D01*
Y105339D01*
X571192Y104539D01*
X569892D01*
X569092Y103739D01*
Y102139D01*
X569892Y101339D01*
X571192D01*
X571992Y100539D01*
Y98939D01*
X571192Y98139D01*
X569892D01*
X569092Y97339D01*
Y95739D01*
X570642Y94189D01*
Y92119D01*
X570638D01*
X569416Y90897D01*
Y86718D01*
X570766Y85368D01*
Y73473D01*
X569416Y72123D01*
Y67394D01*
X570566Y66244D01*
Y64674D01*
X568699Y62807D01*
Y54957D01*
G01X483787Y197065D02*
X500937Y179915D01*
X510533D01*
X552292Y138156D01*
Y133489D01*
X551225Y132422D01*
Y131289D01*
X574492Y108022D01*
Y95300D01*
X573266Y94074D01*
Y64174D01*
X570766Y61674D01*
Y54574D01*
X569272Y53080D01*
Y51987D01*
X571345Y49914D01*
G01X479552Y193302D02*
X498594Y174260D01*
X505580D01*
X532192Y147648D01*
Y139714D01*
X538202Y133704D01*
Y132572D01*
X537077Y131447D01*
Y130315D01*
X538208Y129184D01*
X539340D01*
X540465Y130309D01*
X541597D01*
X542728Y129178D01*
Y128046D01*
X541603Y126921D01*
Y125789D01*
X542734Y124658D01*
X543866D01*
X544991Y125783D01*
X546123D01*
X547254Y124652D01*
Y123520D01*
X546129Y122395D01*
Y121263D01*
X547260Y120132D01*
X548392D01*
X549517Y121257D01*
X550649D01*
X551780Y120126D01*
Y118994D01*
X550655Y117869D01*
Y116737D01*
X551786Y115606D01*
X552918D01*
X554043Y116731D01*
X555175D01*
X563806Y108100D01*
Y91958D01*
X563066Y91218D01*
Y86274D01*
X564066Y85274D01*
Y73103D01*
X563066Y72103D01*
Y67127D01*
X563966Y66227D01*
Y56917D01*
X562006Y54957D01*
G01X480885Y194635D02*
X499375Y176145D01*
X507231D01*
X534692Y148684D01*
Y144250D01*
X537574Y141368D01*
X538366D01*
X539478Y142480D01*
X540610D01*
X541741Y141349D01*
Y140217D01*
X539049Y137525D01*
Y136393D01*
X566392Y109050D01*
Y91942D01*
X567566Y90768D01*
Y86374D01*
X566566Y85374D01*
Y73203D01*
X566916Y72853D01*
Y66653D01*
X566092Y65829D01*
Y56344D01*
X563066Y53318D01*
Y51718D01*
X564016Y50768D01*
X564198D01*
X565052Y49914D01*
G01X486561Y199771D02*
X487268Y199064D01*
X487904D01*
X488612Y198356D01*
Y197720D01*
X489378Y196954D01*
X490014D01*
X490722Y196246D01*
Y195610D01*
X491429Y194903D01*
X492065D01*
X492773Y194195D01*
Y193559D01*
X493570Y192762D01*
X494207D01*
X494915Y192054D01*
Y191417D01*
X495780Y190552D01*
X496416D01*
X497124Y189844D01*
Y189208D01*
X497831Y188501D01*
X498467D01*
X499175Y187793D01*
Y187157D01*
X500119Y186213D01*
X500755D01*
X501463Y185505D01*
Y184869D01*
X503472Y182860D01*
X512849D01*
X558804Y136905D01*
Y134794D01*
X556393Y132383D01*
Y131256D01*
X558176Y129473D01*
X559486D01*
X561532Y131519D01*
X563641D01*
X566029Y129131D01*
Y127019D01*
X564149Y125139D01*
Y123913D01*
X578246Y109816D01*
Y96020D01*
X578866Y95400D01*
Y94400D01*
X578246Y93780D01*
Y83320D01*
X578866Y82700D01*
Y81700D01*
X578246Y81080D01*
Y80320D01*
X578866Y79700D01*
Y78700D01*
X578246Y78080D01*
Y77320D01*
X578866Y76700D01*
Y75700D01*
X578246Y75080D01*
Y63122D01*
X574372Y59248D01*
Y57420D01*
X575092Y56700D01*
X576092D01*
X576892Y55900D01*
Y53826D01*
X575166Y52100D01*
G01X485812Y199020D02*
X503032Y181800D01*
X512409D01*
X557744Y136465D01*
Y135234D01*
X555333Y132823D01*
Y130816D01*
X557736Y128413D01*
X559926D01*
X561972Y130459D01*
X563201D01*
X564969Y128691D01*
Y127462D01*
X563089Y125582D01*
Y123470D01*
X577186Y109373D01*
Y63565D01*
X573312Y59691D01*
Y51354D01*
X575166Y49500D01*
G01X488903Y203089D02*
X489624Y202368D01*
Y201731D01*
X490332Y201023D01*
X490969D01*
X492159Y199833D01*
Y199196D01*
X492867Y198488D01*
X493504D01*
X494369Y197623D01*
Y196987D01*
X495077Y196279D01*
X495713D01*
X507247Y184745D01*
X514864D01*
X569112Y130497D01*
Y122851D01*
X571328Y120636D01*
X573728Y118236D01*
X576009Y115954D01*
Y115953D01*
X582286Y109676D01*
Y62825D01*
X578512Y59051D01*
Y51468D01*
X580266Y49714D01*
G01X472384Y185598D02*
Y170872D01*
X507311Y135945D01*
X508443D01*
X509129Y136631D01*
X510261D01*
X511392Y135500D01*
Y134368D01*
X510706Y133682D01*
Y132550D01*
X511837Y131419D01*
X512969D01*
X513655Y132105D01*
X514787D01*
X515918Y130974D01*
Y129842D01*
X515232Y129156D01*
Y128024D01*
X522092Y121164D01*
Y115400D01*
X520466Y113774D01*
Y111774D01*
X519092Y110400D01*
Y106300D01*
X520844Y104548D01*
Y92114D01*
X519844Y91114D01*
Y86414D01*
X520444Y85814D01*
Y73051D01*
X519992Y72599D01*
Y66751D01*
X520794Y65949D01*
Y54264D01*
X519844Y53314D01*
Y48614D01*
X520444Y48014D01*
Y44099D01*
X518992Y42647D01*
Y40899D01*
X520444Y39447D01*
Y35351D01*
X519944Y34851D01*
Y28999D01*
X520744Y28199D01*
Y19399D01*
X518502Y17157D01*
G01X474884Y186158D02*
Y173760D01*
X509444Y139200D01*
X511292D01*
X524592Y125900D01*
Y114600D01*
X522966Y112974D01*
Y111674D01*
X523666Y110974D01*
Y105974D01*
X523292Y105600D01*
Y91926D01*
X523944Y91274D01*
Y86614D01*
X523244Y85914D01*
Y73047D01*
X523844Y72447D01*
Y67049D01*
X523294Y66499D01*
Y53864D01*
X523944Y53214D01*
Y48814D01*
X523244Y48114D01*
Y35147D01*
X523844Y34547D01*
Y29249D01*
X523294Y28699D01*
Y18964D01*
X519944Y15614D01*
Y14018D01*
X521848Y12114D01*
G01X511809Y17157D02*
Y18017D01*
X513844Y20052D01*
Y28499D01*
X513244Y29099D01*
Y34751D01*
X514044Y35551D01*
Y41421D01*
X512692Y42773D01*
Y44621D01*
X514044Y45973D01*
Y47914D01*
X513244Y48714D01*
Y53414D01*
X513644Y53814D01*
Y59047D01*
X512492Y60199D01*
Y62247D01*
X513644Y63399D01*
Y66499D01*
X513244Y66899D01*
Y72451D01*
X514044Y73251D01*
Y77684D01*
X512792Y78936D01*
Y80884D01*
X514044Y82136D01*
Y85714D01*
X513244Y86514D01*
Y91214D01*
X513892Y91862D01*
Y105000D01*
X512792Y106100D01*
Y110300D01*
X513892Y111400D01*
Y113100D01*
X511830Y115162D01*
Y116206D01*
X512568Y116944D01*
X514932D01*
X515492Y117504D01*
Y119584D01*
X514932Y120144D01*
X512492D01*
X511692Y120944D01*
Y122100D01*
X512492Y122900D01*
Y123692D01*
X467384Y168800D01*
Y185192D01*
G01X515155Y12114D02*
X513244Y14025D01*
Y15692D01*
X516344Y18792D01*
Y28399D01*
X517444Y29499D01*
Y34447D01*
X516544Y35347D01*
Y47914D01*
X517344Y48714D01*
Y53214D01*
X516644Y53914D01*
Y66499D01*
X517444Y67299D01*
Y72047D01*
X516544Y72947D01*
Y85714D01*
X517344Y86514D01*
Y91014D01*
X516392Y91966D01*
Y105400D01*
X517266Y106274D01*
Y110774D01*
X516392Y111648D01*
Y113300D01*
X517392Y114300D01*
Y122328D01*
X469884Y169836D01*
Y185408D01*
G01X498410Y204865D02*
X511815Y191460D01*
X520506D01*
X592592Y119374D01*
Y114008D01*
X593392Y113208D01*
X594232D01*
X594792Y112648D01*
Y110568D01*
X594232Y110008D01*
X593392D01*
X592592Y109208D01*
Y107608D01*
X593392Y106808D01*
X594082D01*
X594642Y106248D01*
Y104168D01*
X594082Y103608D01*
X593552D01*
X592992Y103048D01*
Y100968D01*
X593552Y100408D01*
X594282D01*
X594842Y99848D01*
Y97768D01*
X593992Y96918D01*
Y91644D01*
X593466Y91118D01*
Y86418D01*
X594066Y85818D01*
Y73075D01*
X593566Y72575D01*
Y66803D01*
X594366Y66003D01*
Y58375D01*
X592124Y56133D01*
Y54957D01*
G01X498491Y207450D02*
X512596Y193345D01*
X522157D01*
X597017Y118485D01*
Y91567D01*
X597566Y91018D01*
Y86618D01*
X596866Y85918D01*
Y73227D01*
X597466Y72627D01*
Y67053D01*
X596916Y66503D01*
Y56768D01*
X593566Y53418D01*
Y51818D01*
X595470Y49914D01*
G01X495527Y202415D02*
X510252Y187690D01*
X517016D01*
X517792Y186917D01*
X572792Y132101D01*
Y124376D01*
X573567Y123601D01*
X574699D01*
X576224Y125126D01*
X577016D01*
X578487Y123655D01*
Y122863D01*
X576962Y121338D01*
Y120206D01*
X578093Y119075D01*
X579225D01*
X581200Y121050D01*
X581992D01*
X583463Y119579D01*
Y118787D01*
X581488Y116812D01*
Y115680D01*
X585992Y111176D01*
Y95474D01*
X587231Y94235D01*
Y91583D01*
X586866Y91218D01*
Y86518D01*
X587666Y85718D01*
Y73375D01*
X586866Y72575D01*
Y66903D01*
X587292Y66477D01*
Y59044D01*
X585431Y57183D01*
Y54957D01*
G01X495508Y205100D02*
X511033Y189575D01*
X518855D01*
X588492Y119938D01*
Y118299D01*
X589392Y117399D01*
Y114499D01*
X588492Y113599D01*
Y111899D01*
X590292Y110099D01*
Y91692D01*
X590966Y91018D01*
Y86518D01*
X590166Y85718D01*
Y73127D01*
X590592Y72701D01*
Y66779D01*
X590192Y66379D01*
Y58408D01*
X588416Y56632D01*
Y55194D01*
X586866Y53644D01*
Y51825D01*
X588777Y49914D01*
G01X489652Y203840D02*
X507687Y185805D01*
X515304D01*
X570172Y130937D01*
Y123291D01*
X572078Y121386D01*
X583346Y110117D01*
Y71620D01*
X583966Y71000D01*
Y70000D01*
X583346Y69380D01*
Y68620D01*
X583966Y68000D01*
Y67000D01*
X583346Y66380D01*
Y62382D01*
X579572Y58608D01*
Y57620D01*
X580392Y56800D01*
X581492D01*
X582092Y56200D01*
Y54140D01*
X580266Y52314D01*
G01X424208Y418511D02*
Y462094D01*
X427008Y464894D01*
Y466023D01*
X426131Y466900D01*
Y468004D01*
X427264Y469137D01*
X428421D01*
X429271Y468287D01*
X430401D01*
X431534Y469420D01*
Y470549D01*
X430365Y471718D01*
Y472848D01*
X431498Y473981D01*
X432629D01*
X433797Y472813D01*
X434927D01*
X457714Y495600D01*
Y507022D01*
X460333Y509641D01*
Y510707D01*
X458983Y512057D01*
Y516307D01*
X460133Y517457D01*
Y519000D01*
X459093Y520040D01*
Y526801D01*
X460133Y527841D01*
Y529459D01*
X459033Y530559D01*
Y535341D01*
X460183Y536491D01*
Y538000D01*
X458802Y539381D01*
Y545610D01*
X460183Y546991D01*
Y548657D01*
X456833Y552007D01*
Y554524D01*
X458266Y555957D01*
G01X426708Y418521D02*
Y461051D01*
X461636Y495979D01*
Y500851D01*
X462196Y501411D01*
X462221D01*
X462831Y502021D01*
Y503411D01*
X462221Y504021D01*
X460472D01*
X459862Y504631D01*
Y505750D01*
X460422Y506310D01*
X461342D01*
X461903Y506871D01*
Y507911D01*
X462833Y508841D01*
Y518738D01*
X464450Y520355D01*
Y521431D01*
X463840Y522041D01*
X461851D01*
X461268Y522624D01*
Y524014D01*
X461905Y524651D01*
X463840D01*
X464450Y525261D01*
Y526454D01*
X462833Y528071D01*
Y537740D01*
X464530Y539437D01*
Y540471D01*
X463920Y541081D01*
X461613D01*
X461003Y541691D01*
Y543081D01*
X461613Y543691D01*
X463920D01*
X464530Y544301D01*
Y545462D01*
X462833Y547159D01*
Y548643D01*
X460912Y550564D01*
Y550914D01*
G01X441818Y410424D02*
Y453250D01*
X465480Y476912D01*
Y479788D01*
X482192Y496500D01*
Y507400D01*
X483410Y508618D01*
Y511282D01*
X483197Y511495D01*
Y517121D01*
X483595Y517519D01*
Y529595D01*
X482833Y530357D01*
Y535342D01*
X483463Y535972D01*
Y548977D01*
X480333Y552107D01*
Y554599D01*
X481691Y555957D01*
G01X444318Y409681D02*
Y452214D01*
X472617Y480513D01*
Y481375D01*
X471629Y482363D01*
Y483225D01*
X472613Y484209D01*
X473475D01*
X474463Y483221D01*
X475325D01*
X476309Y484205D01*
Y485067D01*
X475321Y486055D01*
Y486917D01*
X476305Y487901D01*
X477167D01*
X478155Y486913D01*
X479017D01*
X480001Y487897D01*
Y488759D01*
X479142Y489618D01*
Y490326D01*
X480280Y491464D01*
X480988D01*
X481847Y490605D01*
X482709D01*
X484692Y492588D01*
Y501500D01*
X486433Y503241D01*
Y511041D01*
X487033Y511641D01*
Y516807D01*
X486092Y517748D01*
Y519401D01*
X486692Y520001D01*
Y527900D01*
X486483Y528109D01*
Y529619D01*
X487333Y530469D01*
Y535258D01*
X486333Y536258D01*
Y537540D01*
X486692Y537899D01*
Y546400D01*
X486333Y546759D01*
Y549670D01*
X485037Y550966D01*
Y550914D01*
G01X419208Y417842D02*
Y469042D01*
X453374Y503208D01*
Y511016D01*
X452633Y511757D01*
Y516507D01*
X453533Y517407D01*
Y529359D01*
X452702Y530190D01*
Y535361D01*
X453483Y536142D01*
Y548657D01*
X451031Y551109D01*
Y555415D01*
X451573Y555957D01*
G01X421708Y418081D02*
Y468093D01*
X431879Y478264D01*
X433011D01*
X434229Y477046D01*
X435461D01*
X436492Y478077D01*
Y479309D01*
X435274Y480527D01*
Y481659D01*
X436368Y482753D01*
X437500D01*
X438884Y481369D01*
X439883D01*
X455492Y496978D01*
Y510800D01*
X456483Y511791D01*
Y517207D01*
X456233Y517457D01*
Y519100D01*
X456592Y519459D01*
Y527300D01*
X456233Y527659D01*
Y530197D01*
X456733Y530697D01*
Y534856D01*
X456133Y535456D01*
Y537600D01*
X456592Y538059D01*
Y546500D01*
X456133Y546959D01*
Y549400D01*
X454619Y550914D01*
G01X436808Y411022D02*
Y456780D01*
X476992Y496964D01*
Y511000D01*
X475992Y512000D01*
Y516100D01*
X477392Y517500D01*
Y519141D01*
X476692Y519841D01*
Y527800D01*
X477176Y528284D01*
Y529416D01*
X475592Y531000D01*
Y535101D01*
X477233Y536742D01*
Y537700D01*
X476667Y538266D01*
Y546475D01*
X477233Y547041D01*
Y548821D01*
X474333Y551721D01*
Y555292D01*
X474998Y555957D01*
G01X439308Y411535D02*
Y456516D01*
X445746Y462954D01*
X446608D01*
X447246Y462316D01*
X448108D01*
X449509Y463717D01*
Y464579D01*
X448871Y465217D01*
Y466079D01*
X450272Y467480D01*
X451134D01*
X451772Y466842D01*
X452634D01*
X454035Y468243D01*
Y469105D01*
X453397Y469743D01*
Y470605D01*
X454798Y472006D01*
X455660D01*
X456298Y471368D01*
X457160D01*
X458561Y472769D01*
Y473631D01*
X457923Y474269D01*
Y475131D01*
X459324Y476532D01*
X460186D01*
X460824Y475894D01*
X461686D01*
X463087Y477295D01*
Y478157D01*
X462449Y478795D01*
Y479657D01*
X479492Y496700D01*
Y511016D01*
X480892Y512416D01*
Y516000D01*
X479392Y517500D01*
Y519359D01*
X480392Y520359D01*
Y522200D01*
X479192Y523400D01*
Y525100D01*
X480292Y526200D01*
Y527500D01*
X479833Y527959D01*
Y529655D01*
X480399Y530221D01*
Y535493D01*
X479733Y536159D01*
Y537740D01*
X480392Y538399D01*
Y540100D01*
X479326Y541166D01*
Y543534D01*
X480392Y544600D01*
Y546400D01*
X479733Y547059D01*
Y549568D01*
X479690D01*
X478344Y550914D01*
G01X484032Y423105D02*
Y438040D01*
X496692Y450700D01*
X507558D01*
X529400Y472542D01*
X553691Y477397D01*
X570766Y494472D01*
Y510707D01*
X569416Y512057D01*
Y516307D01*
X570566Y517457D01*
Y519300D01*
X570392Y519474D01*
Y527700D01*
X570566Y527874D01*
Y529444D01*
X569355Y530655D01*
Y535264D01*
X570616Y536525D01*
Y537700D01*
X570392Y537924D01*
Y546800D01*
X570616Y547024D01*
Y548657D01*
X567792Y551481D01*
Y555050D01*
X568699Y555957D01*
G01X571345Y550914D02*
Y550564D01*
X573266Y548643D01*
Y547226D01*
X573692Y546800D01*
Y538126D01*
X573266Y537700D01*
Y527726D01*
X573792Y527200D01*
Y519800D01*
X573266Y519274D01*
Y493905D01*
X549888Y470527D01*
X549026D01*
X546520Y473033D01*
X545658D01*
X544674Y472049D01*
Y471187D01*
X547180Y468681D01*
Y467819D01*
X546196Y466835D01*
X545334D01*
X542828Y469341D01*
X541966D01*
X540982Y468357D01*
Y467495D01*
X543488Y464989D01*
Y464127D01*
X507511Y428150D01*
X487642D01*
X486492Y427000D01*
Y422864D01*
G01X479032Y422710D02*
Y440234D01*
X493704Y454906D01*
X505002D01*
X534917Y484821D01*
X553097D01*
X564066Y495790D01*
Y510757D01*
X563066Y511757D01*
Y516457D01*
X563966Y517357D01*
Y519200D01*
X563692Y519474D01*
Y527800D01*
X563966Y528074D01*
Y529425D01*
X562918Y530473D01*
Y535144D01*
X563916Y536142D01*
Y537900D01*
X563692Y538124D01*
Y546300D01*
X563916Y546524D01*
Y548657D01*
X560766Y551807D01*
Y554717D01*
X562006Y555957D01*
G01X565266Y550574D02*
X565392D01*
X566566Y549400D01*
Y547026D01*
X566992Y546600D01*
Y538026D01*
X566566Y537600D01*
Y535456D01*
X567166Y534856D01*
Y530697D01*
X566666Y530197D01*
Y527926D01*
X567092Y527500D01*
Y519926D01*
X566666Y519500D01*
Y517457D01*
X566992Y517131D01*
Y511399D01*
X566566Y510973D01*
Y493346D01*
X555398Y482178D01*
X552409D01*
X551799Y481568D01*
Y480022D01*
X551189Y479412D01*
X549799D01*
X549189Y480022D01*
Y481568D01*
X548579Y482178D01*
X547189D01*
X546579Y481568D01*
Y480022D01*
X545969Y479412D01*
X544579D01*
X543969Y480022D01*
Y481568D01*
X543359Y482178D01*
X535669D01*
X506512Y453021D01*
X494485D01*
X481532Y440068D01*
Y423140D01*
G01X430733Y419187D02*
Y459869D01*
X465589Y494725D01*
Y506565D01*
X467813Y508789D01*
Y550020D01*
X464733Y553100D01*
G01X491958Y421696D02*
X495002Y424740D01*
X508662D01*
X578246Y494324D01*
Y550020D01*
X575166Y553100D01*
G01X433123Y419537D02*
Y458302D01*
X461892Y487071D01*
Y487949D01*
X462600Y488656D01*
X463477D01*
X464184Y489363D01*
Y490241D01*
X464891Y490948D01*
X465769D01*
X467473Y492652D01*
Y495079D01*
X468971Y496577D01*
X471040D01*
X471912Y497449D01*
Y499145D01*
X471040Y500017D01*
X469249D01*
X467866Y501400D01*
Y504782D01*
X469314Y506230D01*
X471252D01*
X472053Y507031D01*
Y508840D01*
X471433Y509460D01*
Y510460D01*
X472053Y511080D01*
Y512496D01*
X471579Y512970D01*
Y513970D01*
X472053Y514444D01*
Y515604D01*
X471500Y516157D01*
Y517157D01*
X472053Y517710D01*
Y518934D01*
X471433Y519554D01*
Y520554D01*
X472053Y521174D01*
Y522174D01*
X471433Y522794D01*
Y523794D01*
X472053Y524414D01*
Y525414D01*
X471433Y526034D01*
Y527034D01*
X472053Y527654D01*
Y529233D01*
X471433Y529853D01*
Y530853D01*
X472053Y531473D01*
Y534152D01*
X471433Y534772D01*
Y535772D01*
X472053Y536392D01*
Y537947D01*
X471433Y538567D01*
Y539567D01*
X472053Y540187D01*
Y541187D01*
X471433Y541807D01*
Y542807D01*
X472053Y543427D01*
Y544427D01*
X471433Y545047D01*
Y546047D01*
X472053Y546667D01*
Y549594D01*
X470933Y550714D01*
X469832D01*
G01X500179Y422405D02*
X509494D01*
X561727Y474638D01*
X566658D01*
X570680Y478660D01*
Y480976D01*
X572564Y482860D01*
X574890D01*
X575874Y483844D01*
Y484716D01*
X575168Y485422D01*
Y487162D01*
X576776Y488770D01*
X578516D01*
X579222Y488064D01*
X580084D01*
X582286Y490266D01*
Y493415D01*
X581666Y494035D01*
Y495035D01*
X582286Y495655D01*
Y496655D01*
X581666Y497275D01*
Y498275D01*
X582286Y498895D01*
Y499895D01*
X581666Y500515D01*
Y501515D01*
X582286Y502135D01*
Y503135D01*
X581666Y503755D01*
Y504755D01*
X582286Y505375D01*
Y506375D01*
X581666Y506995D01*
Y507995D01*
X582286Y508615D01*
Y510432D01*
X581733Y510985D01*
Y511985D01*
X582286Y512538D01*
Y519067D01*
X581666Y519687D01*
Y520687D01*
X582286Y521307D01*
Y522307D01*
X581666Y522927D01*
Y523927D01*
X582286Y524547D01*
Y525547D01*
X581666Y526167D01*
Y527167D01*
X582286Y527787D01*
Y529287D01*
X581812Y529761D01*
Y530761D01*
X582286Y531235D01*
Y534458D01*
X581852Y534892D01*
Y535892D01*
X582286Y536326D01*
Y537841D01*
X581666Y538461D01*
Y539461D01*
X582286Y540081D01*
Y541081D01*
X581666Y541701D01*
Y542701D01*
X582286Y543321D01*
Y544321D01*
X581666Y544941D01*
Y545941D01*
X582286Y546561D01*
Y549794D01*
X581366Y550714D01*
X580266D01*
G01X429673Y419187D02*
Y460309D01*
X464529Y495165D01*
Y507005D01*
X466753Y509229D01*
Y538696D01*
X466288Y539161D01*
Y540161D01*
X466753Y540626D01*
Y541626D01*
X466288Y542091D01*
Y543091D01*
X466753Y543556D01*
Y544556D01*
X466288Y545021D01*
Y546021D01*
X466753Y546486D01*
Y549580D01*
X465833Y550500D01*
X464732D01*
G01X491207Y422445D02*
X494562Y425800D01*
X508222D01*
X577186Y494764D01*
Y538398D01*
X576725Y538859D01*
Y539859D01*
X577186Y540320D01*
Y541479D01*
X576566Y542099D01*
Y543099D01*
X577186Y543719D01*
Y544719D01*
X576566Y545339D01*
Y546339D01*
X577186Y546959D01*
Y549580D01*
X576266Y550500D01*
X575166D01*
G01X434183Y419537D02*
Y457862D01*
X468533Y492212D01*
Y494639D01*
X469411Y495517D01*
X471480D01*
X472972Y497009D01*
Y499585D01*
X471480Y501077D01*
X469689D01*
X468926Y501840D01*
Y504342D01*
X469754Y505170D01*
X471692D01*
X473113Y506591D01*
Y550034D01*
X469833Y553314D01*
G01X500179Y421345D02*
X509934D01*
X562167Y473578D01*
X567098D01*
X571740Y478220D01*
Y480536D01*
X573004Y481800D01*
X575330D01*
X576934Y483404D01*
Y485156D01*
X576228Y485862D01*
Y486722D01*
X577216Y487710D01*
X578076D01*
X578782Y487004D01*
X580524D01*
X583346Y489826D01*
Y550234D01*
X580266Y553314D01*
G01X495077Y593757D02*
Y588374D01*
X496994Y586457D01*
Y574203D01*
X495844Y573053D01*
Y568347D01*
X496944Y567247D01*
Y565952D01*
X496792Y565800D01*
Y557452D01*
X496992Y557252D01*
Y555305D01*
X495794Y554107D01*
Y549857D01*
X497144Y548507D01*
Y546352D01*
X496092Y545300D01*
Y538752D01*
X497144Y537700D01*
Y536552D01*
X495794Y535202D01*
Y530598D01*
X497144Y529248D01*
Y528252D01*
X496492Y527600D01*
Y519952D01*
X497144Y519300D01*
Y517657D01*
X495794Y516307D01*
Y512057D01*
X496966Y510885D01*
Y508726D01*
X498392Y507300D01*
Y501036D01*
X496966Y499610D01*
Y495674D01*
X495192Y493900D01*
Y489601D01*
X489246Y483655D01*
X487865D01*
X463601Y459391D01*
Y455412D01*
X454242Y446053D01*
Y422014D01*
G01X497723Y588714D02*
X499666Y586771D01*
Y566126D01*
X500092Y565700D01*
Y563000D01*
X499292Y562200D01*
Y559800D01*
X500092Y559000D01*
Y557200D01*
X499666Y556774D01*
Y546926D01*
X500092Y546500D01*
Y544800D01*
X498792Y543500D01*
Y541700D01*
X500092Y540400D01*
Y538326D01*
X499666Y537900D01*
Y528026D01*
X500092Y527600D01*
Y519300D01*
X499666Y518874D01*
Y509326D01*
X500944Y508048D01*
Y501152D01*
X499492Y499700D01*
Y488653D01*
X492479Y481640D01*
X489085D01*
X481009Y473564D01*
Y472702D01*
X482003Y471708D01*
Y470846D01*
X481019Y469862D01*
X480157D01*
X479163Y470856D01*
X478301D01*
X477317Y469872D01*
Y469010D01*
X478311Y468016D01*
Y467154D01*
X477327Y466170D01*
X476465D01*
X475471Y467164D01*
X474609D01*
X473625Y466180D01*
Y465318D01*
X474619Y464324D01*
Y463462D01*
X473635Y462478D01*
X472773D01*
X471779Y463472D01*
X470917D01*
X469933Y462488D01*
Y461626D01*
X470927Y460632D01*
Y459770D01*
X469943Y458786D01*
X469081D01*
X468087Y459780D01*
X467225D01*
X466241Y458796D01*
Y457934D01*
X467235Y456940D01*
Y456078D01*
X456632Y445475D01*
Y422124D01*
G01X471732D02*
Y442384D01*
X494653Y465305D01*
X501017D01*
X515550Y479838D01*
Y484690D01*
X519092Y488232D01*
Y494600D01*
X519692Y495200D01*
Y497078D01*
X520444Y497830D01*
Y511157D01*
X519944Y511657D01*
Y517057D01*
X520692Y517805D01*
Y519202D01*
X520192Y519702D01*
Y527800D01*
X520794Y528402D01*
Y529288D01*
X519844Y530238D01*
Y535952D01*
X520444Y536552D01*
Y537700D01*
X520192Y537952D01*
Y546400D01*
X520444Y546652D01*
Y548957D01*
X519944Y549457D01*
Y554857D01*
X520744Y555657D01*
Y557000D01*
X520177Y557567D01*
Y565485D01*
X520744Y566052D01*
Y567297D01*
X519644Y568397D01*
Y573142D01*
X520544Y574042D01*
Y586507D01*
X518502Y588549D01*
Y593757D01*
G01X474232Y422124D02*
X474292Y422184D01*
Y441708D01*
X495581Y462997D01*
X501837D01*
X514059Y475219D01*
X514921D01*
X515496Y474644D01*
X516204D01*
X517342Y475782D01*
Y476490D01*
X516767Y477065D01*
Y477927D01*
X519574Y480734D01*
Y481596D01*
X518596Y482574D01*
Y483282D01*
X519734Y484420D01*
X520442D01*
X521247Y483615D01*
X522176D01*
X523398Y484837D01*
Y491494D01*
X522792Y492100D01*
Y502848D01*
X523244Y503300D01*
Y511657D01*
X523844Y512257D01*
Y516807D01*
X523294Y517357D01*
Y519400D01*
X523492Y519598D01*
Y527800D01*
X523294Y527998D01*
Y529608D01*
X523944Y530258D01*
Y535448D01*
X523244Y536148D01*
Y537500D01*
X523492Y537748D01*
Y546700D01*
X523244Y546948D01*
Y549457D01*
G01X522792Y555659D02*
Y567145D01*
X524144Y568497D01*
Y573248D01*
X523144Y574248D01*
Y587470D01*
X521848Y588766D01*
Y588714D01*
G01X449132Y422124D02*
Y450631D01*
X486953Y488452D01*
X488366D01*
X489566Y489652D01*
Y494674D01*
X490344Y495452D01*
Y500000D01*
X489492Y500852D01*
Y502398D01*
X490292Y503198D01*
X490992D01*
X491792Y503998D01*
Y505598D01*
X490992Y506398D01*
X490292D01*
X489492Y507198D01*
Y508600D01*
X490344Y509452D01*
Y510897D01*
X489444Y511797D01*
Y516353D01*
X490692Y517601D01*
Y519452D01*
X490092Y520052D01*
Y527800D01*
X490344Y528052D01*
Y529448D01*
X489444Y530348D01*
Y535242D01*
X490444Y536242D01*
Y537700D01*
X490092Y538052D01*
Y546900D01*
X490444Y547252D01*
Y548557D01*
X489444Y549557D01*
Y554257D01*
X490692Y555505D01*
Y557200D01*
X490092Y557800D01*
Y565700D01*
X490344Y565952D01*
Y567249D01*
X488692Y568901D01*
Y572340D01*
X490507Y574155D01*
Y575287D01*
X486225Y579569D01*
Y586929D01*
X488384Y589088D01*
Y593757D01*
G01X451632Y422124D02*
Y450179D01*
X453950Y452497D01*
X454812D01*
X455804Y451505D01*
X456667D01*
X457651Y452489D01*
Y453351D01*
X456658Y454344D01*
Y455205D01*
X457642Y456189D01*
X458504D01*
X459496Y455197D01*
X460359D01*
X461343Y456181D01*
Y457043D01*
X460350Y458036D01*
Y458897D01*
X487405Y485952D01*
X488844D01*
X493192Y490300D01*
Y494500D01*
X492592Y495100D01*
Y499026D01*
X495992Y502426D01*
Y505800D01*
X493066Y508726D01*
Y511724D01*
X493692Y512350D01*
Y516101D01*
X492492Y517301D01*
Y519200D01*
X493392Y520100D01*
Y527652D01*
X492692Y528352D01*
Y529700D01*
X493392Y530400D01*
Y535600D01*
X492784Y536208D01*
Y537340D01*
X493392Y537948D01*
Y546200D01*
X492606Y546986D01*
Y548915D01*
X493792Y550101D01*
Y554509D01*
X492792Y555509D01*
Y556948D01*
X493392Y557548D01*
Y565700D01*
X493044Y566048D01*
Y567997D01*
X493544Y568497D01*
Y572656D01*
X492944Y573256D01*
Y575400D01*
X493392Y575848D01*
Y578954D01*
X492782Y579564D01*
X489964D01*
X489354Y580174D01*
Y582154D01*
X489964Y582764D01*
X492782D01*
X493392Y583374D01*
Y584600D01*
X491430Y586562D01*
Y588714D01*
G01X466732Y422124D02*
Y443164D01*
X501337Y477769D01*
X507541D01*
X511493Y481721D01*
Y487395D01*
X511992Y487894D01*
Y493700D01*
X513492Y495200D01*
Y504500D01*
X514044Y505052D01*
Y511257D01*
X513244Y512057D01*
Y516957D01*
X513644Y517357D01*
Y519400D01*
X513492Y519552D01*
Y527800D01*
X513644Y527952D01*
Y529650D01*
X513244Y530050D01*
Y535752D01*
X514044Y536552D01*
Y537500D01*
X513477Y538067D01*
Y546985D01*
X514044Y547552D01*
Y549057D01*
X513244Y549857D01*
Y554757D01*
X513844Y555357D01*
Y557000D01*
X513492Y557352D01*
Y565600D01*
X513844Y565952D01*
Y567397D01*
X512771Y568470D01*
Y572969D01*
X514044Y574242D01*
Y586357D01*
X511809Y588592D01*
Y593757D01*
G01X460353Y422387D02*
Y444316D01*
X504624Y488587D01*
Y587820D01*
X501544Y590900D01*
G01X462993Y423137D02*
Y443843D01*
X501902Y482752D01*
X504363D01*
X505784Y481331D01*
X506835D01*
X508095Y482591D01*
Y483296D01*
X505934Y485457D01*
Y487242D01*
X508664Y489972D01*
Y518908D01*
X508044Y519528D01*
Y520528D01*
X508664Y521148D01*
Y522148D01*
X508044Y522768D01*
Y523768D01*
X508664Y524388D01*
Y525388D01*
X508044Y526008D01*
Y527008D01*
X508664Y527628D01*
Y537842D01*
X508044Y538462D01*
Y539462D01*
X508664Y540082D01*
Y541082D01*
X508044Y541702D01*
Y542702D01*
X508664Y543322D01*
Y544322D01*
X508044Y544942D01*
Y545942D01*
X508664Y546562D01*
Y551124D01*
X508296Y551492D01*
Y552492D01*
X508664Y552860D01*
Y556881D01*
X508044Y557501D01*
Y558501D01*
X508664Y559121D01*
Y560121D01*
X508044Y560741D01*
Y561741D01*
X508664Y562361D01*
Y563361D01*
X508044Y563981D01*
Y564981D01*
X508664Y565601D01*
Y575921D01*
X508044Y576541D01*
Y577541D01*
X508664Y578161D01*
Y579161D01*
X508044Y579781D01*
Y580781D01*
X508664Y581401D01*
Y582401D01*
X508044Y583021D01*
Y584021D01*
X508664Y584641D01*
Y587594D01*
X507744Y588514D01*
X506644D01*
G01X459293Y422387D02*
Y444756D01*
X503564Y489027D01*
Y575949D01*
X503209Y576304D01*
Y577304D01*
X503564Y577659D01*
Y579070D01*
X503117Y579517D01*
Y580517D01*
X503564Y580964D01*
Y582137D01*
X502944Y582757D01*
Y583757D01*
X503564Y584377D01*
Y587380D01*
X502644Y588300D01*
X501544D01*
G01X464053Y423137D02*
Y443403D01*
X502342Y481692D01*
X503923D01*
X505344Y480271D01*
X507275D01*
X509155Y482151D01*
Y483736D01*
X506994Y485897D01*
Y486802D01*
X509724Y489532D01*
Y588034D01*
X506644Y591114D01*
G01X515155Y588714D02*
X516501Y587368D01*
X516544D01*
Y574147D01*
X517210Y573481D01*
Y568163D01*
X516644Y567597D01*
Y565548D01*
X516892Y565300D01*
Y557699D01*
X516344Y557151D01*
Y555457D01*
X517444Y554357D01*
Y549957D01*
X516544Y549057D01*
Y546248D01*
X516892Y545900D01*
Y538100D01*
X516544Y537752D01*
Y536348D01*
X517344Y535548D01*
Y530350D01*
X516644Y529650D01*
Y527948D01*
X516792Y527800D01*
Y519348D01*
X516644Y519200D01*
Y517357D01*
X517444Y516557D01*
Y512157D01*
X516544Y511257D01*
Y504352D01*
X515692Y503500D01*
Y495200D01*
X516544Y494348D01*
Y489291D01*
X513561Y486308D01*
Y480925D01*
X508230Y475594D01*
X502132D01*
X501003Y474465D01*
Y473603D01*
X503055Y471551D01*
Y470843D01*
X501917Y469705D01*
X501209D01*
X499157Y471757D01*
X498295D01*
X497311Y470773D01*
Y469911D01*
X498169Y469053D01*
Y468345D01*
X497031Y467207D01*
X496323D01*
X495465Y468065D01*
X494603D01*
X469232Y442694D01*
Y422124D01*
G01X458266Y555957D02*
X456561Y557662D01*
Y569315D01*
X459746Y572500D01*
X460912D01*
G01Y550914D02*
X460824D01*
X459138Y552600D01*
Y554292D01*
X460045Y555199D01*
Y556792D01*
X458901Y557936D01*
Y559356D01*
X459745Y560200D01*
Y561900D01*
X458901Y562744D01*
Y563956D01*
X459845Y564900D01*
Y566100D01*
X459246Y566699D01*
X458266D01*
G01X451573Y555957D02*
X449868Y557662D01*
Y567635D01*
X450490Y568257D01*
Y569445D01*
X453545Y572500D01*
X454533D01*
G01X454619Y550914D02*
X454531D01*
X452845Y552600D01*
Y554800D01*
X453345Y555300D01*
Y557199D01*
X452208Y558336D01*
Y559664D01*
X453145Y560601D01*
Y561999D01*
X452208Y562936D01*
Y564164D01*
X453245Y565201D01*
Y566099D01*
X452645Y566699D01*
X451573D01*
G01X474998Y555957D02*
X473293Y557662D01*
Y567849D01*
X478344Y572900D01*
G01Y550914D02*
X478256D01*
X476570Y552600D01*
Y554292D01*
X476745Y554467D01*
Y557100D01*
X475633Y558212D01*
Y559288D01*
X476645Y560300D01*
Y561500D01*
X475633Y562512D01*
Y563588D01*
X476770Y564725D01*
Y565999D01*
X476070Y566699D01*
X474998D01*
G01X464732Y553100D02*
X464733D01*
G01D02*
X466445Y554812D01*
Y556400D01*
X465345Y557500D01*
X464395D01*
X463805Y558090D01*
Y559460D01*
X464325Y559980D01*
X464935D01*
X465567Y560612D01*
Y561958D01*
X464935Y562590D01*
X464355D01*
X463805Y563140D01*
Y564560D01*
X464445Y565200D01*
X465725D01*
X466464Y565939D01*
Y567845D01*
X464759Y569550D01*
X464758D01*
G01X469832Y550714D02*
X469545D01*
X468127Y552132D01*
Y557101D01*
X467298Y557930D01*
Y564470D01*
X468127Y565299D01*
Y570244D01*
X469832Y571949D01*
G01X464732Y550500D02*
X464445D01*
X462745Y552200D01*
Y570212D01*
X464732Y572199D01*
G01X469832Y553314D02*
X469833D01*
G01D02*
X471545Y555026D01*
Y556700D01*
X470545Y557700D01*
X469029D01*
X468358Y558371D01*
Y559648D01*
X468810Y560100D01*
X469145D01*
X469845Y560800D01*
Y561888D01*
X469135Y562598D01*
X468898D01*
X468358Y563138D01*
Y564029D01*
X469129Y564800D01*
X470645D01*
X471645Y565800D01*
Y567528D01*
X469833Y569340D01*
X469832D01*
G01X777569Y-43720D02*
X583560D01*
G03Y-46380I0J-1330D01*
G01X777172D01*
G02Y-51160I0J-2390D01*
G01X576040D01*
X572711Y-47831D01*
X511716D01*
X507246Y-52301D01*
G01X777569Y-42660D02*
X583560D01*
G03Y-47440I0J-2390D01*
G01X777172D01*
G02Y-50100I0J-1330D01*
G01X576480D01*
X573151Y-46771D01*
X511716D01*
X507246Y-42301D01*
G01X485037Y49914D02*
X486426Y48525D01*
Y35512D01*
X487038Y34900D01*
Y33500D01*
X485238Y31700D01*
X484238D01*
X482938Y30400D01*
Y29146D01*
X481691Y27899D01*
G01X531888D02*
Y30021D01*
X533767Y31900D01*
X535167D01*
X536623Y33356D01*
Y34700D01*
X536007Y35316D01*
Y48441D01*
X534534Y49914D01*
G01X525195Y27899D02*
X526192Y28896D01*
Y30450D01*
X527442Y31700D01*
X528666D01*
X530242Y33276D01*
Y34900D01*
X529467Y35675D01*
Y48688D01*
X528241Y49914D01*
G01X538355Y52100D02*
X541461Y48994D01*
Y32851D01*
X540130Y31520D01*
X539151D01*
X538381Y30750D01*
G01X538355Y49500D02*
X539454D01*
X540401Y48553D01*
Y46020D01*
X539431Y45050D01*
X539083D01*
X538467Y44434D01*
Y43102D01*
X538969Y42600D01*
X539681D01*
X540401Y41880D01*
Y40920D01*
X539581Y40100D01*
X539081D01*
X538481Y39500D01*
Y38500D01*
X540401Y36580D01*
Y33291D01*
X539690Y32580D01*
X539174D01*
X538355Y33399D01*
G01X481691Y54957D02*
X480570Y53836D01*
Y50900D01*
X483912Y47558D01*
Y46500D01*
X482112Y44700D01*
Y43125D01*
X483312Y41925D01*
Y40799D01*
X482112Y39599D01*
Y38226D01*
X483470Y36868D01*
Y35667D01*
X485037Y34100D01*
G01X531888Y112357D02*
Y106733D01*
X533697Y104924D01*
Y92104D01*
X532692Y91099D01*
Y86479D01*
X533866Y85305D01*
Y73374D01*
X532566Y72074D01*
Y67433D01*
X533797Y66202D01*
Y63266D01*
X531888Y61357D01*
Y54957D01*
G01D02*
X530767Y53836D01*
Y50900D01*
X533667Y48000D01*
Y46032D01*
X532134Y44499D01*
Y43300D01*
X533384Y42050D01*
Y41150D01*
X532034Y39800D01*
Y38501D01*
X533667Y36868D01*
Y34567D01*
X534534Y33700D01*
G01Y49914D02*
X532792Y51656D01*
Y53400D01*
X534316Y54924D01*
Y61135D01*
X536447Y63266D01*
Y105051D01*
X534534Y106964D01*
G01X525195Y54957D02*
X526292Y53860D01*
Y48876D01*
X527067Y48101D01*
Y45876D01*
X525684Y44493D01*
Y43008D01*
X526021Y42671D01*
X526721D01*
X527134Y42258D01*
Y40542D01*
X526571Y39979D01*
X525971D01*
X525634Y39642D01*
Y38557D01*
X527067Y37124D01*
Y34788D01*
X528155Y33700D01*
G01X525134Y112357D02*
X525195D01*
X526266Y111286D01*
Y105905D01*
X527097Y105074D01*
Y92006D01*
X526247Y91156D01*
Y86424D01*
X526382Y86290D01*
X527097Y85574D01*
Y72959D01*
X526247Y72109D01*
Y67145D01*
X527097Y66295D01*
Y58805D01*
X525195Y56903D01*
Y54957D01*
G01X528241Y49914D02*
Y56249D01*
X529292Y57300D01*
Y66100D01*
X530097Y66905D01*
Y72659D01*
X529797Y72959D01*
Y86074D01*
X530197Y86474D01*
Y91174D01*
X529897Y91474D01*
Y105658D01*
X528241Y107314D01*
G01X538355Y110514D02*
X541372Y107497D01*
Y61747D01*
X539372Y59747D01*
Y56781D01*
X540081Y56072D01*
Y53826D01*
X538355Y52100D01*
G01X538381Y107865D02*
X540312Y105934D01*
Y62190D01*
X538312Y60190D01*
Y57320D01*
X536381Y55389D01*
Y51474D01*
X538355Y49500D01*
G01X501981Y414534D02*
X502747Y415300D01*
X513055D01*
X562019Y464264D01*
X567650D01*
X593937Y490551D01*
Y511286D01*
X593566Y511657D01*
Y517057D01*
X593935Y517426D01*
Y529756D01*
X593266Y530425D01*
Y535342D01*
X594042Y536118D01*
Y548831D01*
X591761Y551112D01*
Y555594D01*
X592124Y555957D01*
G01X503774Y412791D02*
X513346D01*
X562219Y461664D01*
X568284D01*
X596136Y489516D01*
Y498797D01*
X597136Y499797D01*
X599054D01*
X599664Y500407D01*
Y501797D01*
X599054Y502407D01*
X596627D01*
X596070Y502964D01*
Y504354D01*
X596733Y505017D01*
X599054D01*
X599664Y505627D01*
Y507017D01*
X599054Y507627D01*
X597304D01*
X596455Y508476D01*
Y511246D01*
X597466Y512257D01*
Y516807D01*
X596825Y517448D01*
Y529602D01*
X597356Y530133D01*
Y535936D01*
X596766Y536526D01*
Y549618D01*
X595470Y550914D01*
G01X498063Y417688D02*
X499725Y419350D01*
X511505D01*
X561915Y469760D01*
X566834D01*
X585821Y488747D01*
Y507309D01*
X587253Y508741D01*
Y511670D01*
X586866Y512057D01*
Y516957D01*
X587466Y517557D01*
Y519500D01*
X587092Y519874D01*
Y527600D01*
X587466Y527974D01*
Y529511D01*
X586393Y530584D01*
Y535169D01*
X587666Y536442D01*
Y537400D01*
X587092Y537974D01*
Y546200D01*
X587666Y546774D01*
Y548557D01*
X584766Y551457D01*
Y555292D01*
X585431Y555957D01*
G01X499913Y416002D02*
X501311Y417400D01*
X512355D01*
X562063Y467108D01*
X567472D01*
X590223Y489859D01*
Y496615D01*
X589613Y497225D01*
X588234D01*
X587624Y497835D01*
Y499225D01*
X588234Y499835D01*
X589613D01*
X590223Y500445D01*
Y501835D01*
X589613Y502445D01*
X588234D01*
X587624Y503055D01*
Y504445D01*
X588234Y505055D01*
X589613D01*
X590223Y505665D01*
Y511314D01*
X591066Y512157D01*
Y516557D01*
X589966Y517657D01*
Y518688D01*
X591786Y520508D01*
Y521346D01*
X591176Y521956D01*
X590093D01*
X589483Y522566D01*
Y524546D01*
X590093Y525156D01*
X591176D01*
X591786Y525766D01*
Y526622D01*
X590266Y528142D01*
Y529633D01*
X590832Y530199D01*
Y535761D01*
X590166Y536427D01*
Y537674D01*
X590492Y538000D01*
Y546500D01*
X590166Y546826D01*
Y549568D01*
X590123D01*
X588777Y550914D01*
G01X530792Y498387D02*
X531888Y499483D01*
Y506610D01*
X533955Y508677D01*
Y510707D01*
X532605Y512057D01*
Y516307D01*
X533755Y517457D01*
Y519600D01*
X533592Y519763D01*
Y527600D01*
X533755Y527763D01*
Y529467D01*
X532655Y530567D01*
Y535263D01*
X533805Y536413D01*
Y537900D01*
X533592Y538113D01*
Y547100D01*
X533805Y547313D01*
Y548657D01*
X530455Y552007D01*
Y554524D01*
X531888Y555957D01*
G01X534534Y493394D02*
X533766Y494162D01*
Y504952D01*
X536455Y507641D01*
Y518964D01*
X536892Y519401D01*
Y528100D01*
X536455Y528537D01*
Y537700D01*
X536892Y538137D01*
Y546400D01*
X536455Y546837D01*
Y548643D01*
X534534Y550564D01*
Y550914D01*
G01X524595Y498387D02*
X524992Y498784D01*
Y505978D01*
X527255Y508241D01*
Y510757D01*
X526255Y511757D01*
Y516507D01*
X527155Y517407D01*
Y519500D01*
X526892Y519763D01*
Y527800D01*
X527155Y528063D01*
Y529437D01*
X526107Y530485D01*
Y535144D01*
X527105Y536142D01*
Y537800D01*
X526892Y538013D01*
Y547200D01*
X527105Y547413D01*
Y548657D01*
G01X528191Y493544D02*
Y504476D01*
X529755Y506040D01*
Y511441D01*
X530105Y511791D01*
Y517207D01*
X529855Y517457D01*
Y519200D01*
X530192Y519537D01*
Y527600D01*
X529855Y527937D01*
Y530197D01*
X530355Y530697D01*
Y534856D01*
X529755Y535456D01*
Y537500D01*
X530192Y537937D01*
Y546400D01*
X529755Y546837D01*
Y549400D01*
X528241Y550914D01*
G01X538370Y495909D02*
X540092Y497631D01*
Y499700D01*
X539192Y500600D01*
Y503846D01*
X541435Y506089D01*
Y549532D01*
X540355Y550612D01*
Y551244D01*
X538499Y553100D01*
X538355D01*
G01X538370Y493209D02*
X536490Y495089D01*
Y499398D01*
X538132Y501040D01*
Y504286D01*
X540375Y506529D01*
Y548674D01*
X538549Y550500D01*
X538355D01*
G01X481691Y555957D02*
X479986Y557662D01*
Y567849D01*
X485037Y572900D01*
G01Y550914D02*
X484949D01*
X483263Y552600D01*
Y554292D01*
X483438Y554467D01*
Y557100D01*
X482326Y558212D01*
Y559288D01*
X483338Y560300D01*
Y561500D01*
X482326Y562512D01*
Y563588D01*
X483463Y564725D01*
Y565999D01*
X482763Y566699D01*
X481691D01*
G01X555313Y27899D02*
X556560Y29146D01*
Y30400D01*
X557860Y31700D01*
X558860D01*
X560660Y33500D01*
Y34900D01*
X560048Y35512D01*
Y48525D01*
X558659Y49914D01*
G01X548620Y27899D02*
X549867Y29146D01*
Y30400D01*
X551167Y31700D01*
X552167D01*
X553967Y33500D01*
Y34900D01*
X553355Y35512D01*
Y48525D01*
X551966Y49914D01*
G01X571345D02*
X572818Y48441D01*
Y35316D01*
X573434Y34700D01*
Y33356D01*
X571978Y31900D01*
X570578D01*
X568699Y30021D01*
Y27899D01*
G01X595470Y49914D02*
X596859Y48525D01*
Y35512D01*
X597471Y34900D01*
Y33500D01*
X595671Y31700D01*
X594671D01*
X593371Y30400D01*
Y29146D01*
X592124Y27899D01*
G01X565052Y49914D02*
X566278Y48688D01*
Y35675D01*
X567053Y34900D01*
Y33276D01*
X565477Y31700D01*
X564253D01*
X562006Y29453D01*
Y27899D01*
G01X588777Y49914D02*
X590166Y48525D01*
Y35512D01*
X590778Y34900D01*
Y33500D01*
X588978Y31700D01*
X587978D01*
X586678Y30400D01*
Y29146D01*
X585431Y27899D01*
G01X575166Y52100D02*
X578272Y48994D01*
Y32848D01*
X576944Y31520D01*
X575962D01*
X575192Y30750D01*
G01X580266Y52314D02*
X583458Y49122D01*
Y33732D01*
X580266Y30540D01*
G01X575166Y49500D02*
X576265D01*
X577212Y48553D01*
Y46020D01*
X576242Y45050D01*
X575894D01*
X575278Y44434D01*
Y43102D01*
X575780Y42600D01*
X576492D01*
X577212Y41880D01*
Y40920D01*
X576392Y40100D01*
X575892D01*
X575292Y39500D01*
Y38500D01*
X577212Y36580D01*
Y33291D01*
X576501Y32580D01*
X575985D01*
X575166Y33399D01*
G01X543455Y52314D02*
X546647Y49122D01*
Y33732D01*
X543455Y30540D01*
G01X555313Y54957D02*
Y63152D01*
X557113Y64952D01*
Y66511D01*
X556597Y67027D01*
Y72405D01*
X557397Y73205D01*
Y85774D01*
X556666Y86505D01*
Y91275D01*
X557297Y91906D01*
Y104954D01*
X556666Y105585D01*
Y109374D01*
X555313Y110727D01*
Y112357D01*
G01X558659Y34100D02*
X557092Y35667D01*
Y36868D01*
X555734Y38226D01*
Y39599D01*
X556934Y40799D01*
Y41925D01*
X555734Y43125D01*
Y44700D01*
X557534Y46500D01*
Y47558D01*
X554192Y50900D01*
Y53836D01*
X555313Y54957D01*
G01X558659Y49914D02*
X556513Y52060D01*
Y53192D01*
X558306Y54985D01*
Y61815D01*
X560206Y63715D01*
Y66588D01*
X560597Y66979D01*
Y72395D01*
X559897Y73095D01*
Y85794D01*
X560597Y86494D01*
Y91342D01*
X559897Y92042D01*
Y106076D01*
X558659Y107314D01*
G01X548620Y54957D02*
X550597Y56934D01*
Y66339D01*
X549797Y67139D01*
Y72505D01*
X550566Y73274D01*
Y86005D01*
X549797Y86774D01*
Y91074D01*
X550897Y92174D01*
Y104775D01*
X549677Y105995D01*
Y109064D01*
X549416Y109324D01*
X548620Y110121D01*
Y112357D01*
G01X551966Y34100D02*
X550492Y35574D01*
Y36668D01*
X549059Y38101D01*
Y39324D01*
X550559Y40824D01*
Y42176D01*
X549059Y43676D01*
Y44799D01*
X550734Y46474D01*
Y47859D01*
X547692Y50901D01*
Y54029D01*
X548620Y54957D01*
G01X551966Y49914D02*
X550166Y51714D01*
Y53545D01*
X552797Y56176D01*
Y65791D01*
X553997Y66991D01*
Y72395D01*
X553266Y73126D01*
Y85843D01*
X554097Y86674D01*
Y91012D01*
X553397Y91712D01*
Y105883D01*
X551966Y107314D01*
G01X568699Y54957D02*
X567578Y53836D01*
Y50900D01*
X570478Y48000D01*
Y46032D01*
X568945Y44499D01*
Y43300D01*
X570195Y42050D01*
Y41150D01*
X568845Y39800D01*
Y38501D01*
X570478Y36868D01*
Y34567D01*
X571345Y33700D01*
G01X592124Y54957D02*
X591003Y53836D01*
Y50900D01*
X594345Y47558D01*
Y46500D01*
X592545Y44700D01*
Y43125D01*
X593745Y41925D01*
Y40799D01*
X592545Y39599D01*
Y38226D01*
X593903Y36868D01*
Y35667D01*
X595470Y34100D01*
G01X562006Y54957D02*
X561078Y54029D01*
Y50901D01*
X563878Y48101D01*
Y46232D01*
X562495Y44849D01*
Y43450D01*
X563945Y42000D01*
Y40800D01*
X562445Y39300D01*
Y38101D01*
X563878Y36668D01*
Y34788D01*
X564966Y33700D01*
G01X585431Y54957D02*
X584503Y54029D01*
Y50901D01*
X587545Y47859D01*
Y46474D01*
X585870Y44799D01*
Y43676D01*
X587370Y42176D01*
Y40824D01*
X585870Y39324D01*
Y38101D01*
X587303Y36668D01*
Y35574D01*
X588777Y34100D01*
G01X543455Y107655D02*
X545412Y105698D01*
Y60092D01*
X543512Y58192D01*
Y57520D01*
X541731Y55739D01*
Y51438D01*
X543455Y49714D01*
G01D02*
Y49715D01*
X544553D01*
X545587Y48681D01*
Y45906D01*
X544881Y45200D01*
X544367D01*
X543667Y44500D01*
Y43500D01*
X544367Y42800D01*
X544867D01*
X545587Y42080D01*
Y40707D01*
X544780Y39900D01*
X544082D01*
X543481Y39299D01*
Y38101D01*
X544082Y37500D01*
X544880D01*
X545587Y36793D01*
Y34172D01*
X544564Y33149D01*
X543455D01*
G01X543481Y110264D02*
Y110238D01*
X546472Y107247D01*
Y59649D01*
X544572Y57749D01*
Y56620D01*
X545281Y55911D01*
Y54140D01*
X543455Y52314D01*
G01X580266Y49714D02*
Y49715D01*
X581364D01*
X582398Y48681D01*
Y45906D01*
X581692Y45200D01*
X581178D01*
X580478Y44500D01*
Y43500D01*
X581178Y42800D01*
X581678D01*
X582398Y42080D01*
Y40707D01*
X581591Y39900D01*
X580893D01*
X580292Y39299D01*
Y38101D01*
X580893Y37500D01*
X581691D01*
X582398Y36793D01*
Y34172D01*
X581375Y33149D01*
X580266D01*
G01X554792Y498487D02*
X554913D01*
X557255Y500829D01*
Y511157D01*
X556755Y511657D01*
Y517057D01*
X557555Y517857D01*
Y519500D01*
X556989Y520066D01*
Y527697D01*
X557555Y528263D01*
Y529497D01*
X556455Y530597D01*
Y535342D01*
X557355Y536242D01*
Y537636D01*
X556992Y537999D01*
Y546300D01*
X557355Y546663D01*
Y548707D01*
X553955Y552107D01*
Y554599D01*
X555313Y555957D01*
G01X558659Y496144D02*
X560055Y497540D01*
Y511657D01*
X560655Y512257D01*
Y516807D01*
X560105Y517357D01*
Y519800D01*
X560392Y520087D01*
Y527600D01*
X560105Y527887D01*
Y529847D01*
X560955Y530697D01*
Y535338D01*
X559955Y536338D01*
Y537600D01*
X560292Y537937D01*
Y545900D01*
X559955Y546237D01*
Y549670D01*
X558659Y550966D01*
Y550914D01*
G01X548492Y498400D02*
X548620Y498528D01*
Y502606D01*
X550855Y504841D01*
Y511257D01*
X550055Y512057D01*
Y516957D01*
X550655Y517557D01*
Y519500D01*
X550292Y519863D01*
Y527700D01*
X550655Y528063D01*
Y529597D01*
X549582Y530670D01*
Y535169D01*
X550592Y536179D01*
Y537963D01*
X550292Y538263D01*
Y546600D01*
X550855Y547163D01*
Y548557D01*
X547955Y551457D01*
Y555292D01*
X548620Y555957D01*
G01X551366Y493344D02*
Y499652D01*
X553355Y501641D01*
Y511257D01*
X554255Y512157D01*
Y516557D01*
X553455Y517357D01*
Y519400D01*
X553592Y519537D01*
Y527900D01*
X553455Y528037D01*
Y529797D01*
X554021Y530363D01*
Y535571D01*
X553355Y536237D01*
Y537800D01*
X553692Y538137D01*
Y546500D01*
X553355Y546837D01*
Y549568D01*
X553312D01*
X551966Y550914D01*
G01X543455Y493509D02*
X541692Y495272D01*
Y499600D01*
X545475Y503383D01*
Y519485D01*
X544111Y520849D01*
Y525061D01*
X545475Y526425D01*
Y538790D01*
X543908Y540357D01*
Y543840D01*
X545475Y545407D01*
Y548694D01*
X543455Y550714D01*
G01Y496209D02*
X545192Y497946D01*
Y501600D01*
X546535Y502943D01*
Y519925D01*
X545171Y521289D01*
Y524621D01*
X546535Y525985D01*
Y539230D01*
X544968Y540797D01*
Y543400D01*
X546535Y544967D01*
Y550234D01*
X543455Y553314D01*
G01X568699Y555957D02*
X566994Y557662D01*
Y569315D01*
X570179Y572500D01*
X571345D01*
G01Y550914D02*
X571257D01*
X569571Y552600D01*
Y554292D01*
X570478Y555199D01*
Y556792D01*
X569334Y557936D01*
Y559356D01*
X570178Y560200D01*
Y561900D01*
X569334Y562744D01*
Y563956D01*
X570278Y564900D01*
Y566100D01*
X569679Y566699D01*
X568699D01*
G01X592124Y555957D02*
X590419Y557662D01*
Y567849D01*
X595470Y572900D01*
G01Y550914D02*
X593696Y552688D01*
Y554292D01*
X593871Y554467D01*
Y557100D01*
X592759Y558212D01*
Y559288D01*
X593771Y560300D01*
Y561500D01*
X592759Y562512D01*
Y563588D01*
X593896Y564725D01*
Y565999D01*
X593196Y566699D01*
X592124D01*
G01X562006Y555957D02*
X560301Y557662D01*
Y567635D01*
X560923Y568257D01*
Y569445D01*
X563978Y572500D01*
X564966D01*
G01X565266Y550574D02*
Y550612D01*
X563278Y552600D01*
Y554800D01*
X563778Y555300D01*
Y557199D01*
X562641Y558336D01*
Y559664D01*
X563578Y560601D01*
Y561999D01*
X562641Y562936D01*
Y564164D01*
X563678Y565201D01*
Y566099D01*
X563078Y566699D01*
X562006D01*
G01X585431Y555957D02*
X583726Y557662D01*
Y567849D01*
X588777Y572900D01*
G01Y550914D02*
X588689D01*
X587003Y552600D01*
Y554292D01*
X587178Y554467D01*
Y557100D01*
X586066Y558212D01*
Y559288D01*
X587078Y560300D01*
Y561500D01*
X586066Y562512D01*
Y563588D01*
X587203Y564725D01*
Y565999D01*
X586503Y566699D01*
X585431D01*
G01X575166Y553100D02*
X576878Y554812D01*
Y556400D01*
X575778Y557500D01*
X574828D01*
X574238Y558090D01*
Y559460D01*
X574758Y559980D01*
X575368D01*
X575978Y560590D01*
Y561980D01*
X575368Y562590D01*
X574788D01*
X574238Y563140D01*
Y564560D01*
X574878Y565200D01*
X576158D01*
X576897Y565939D01*
Y567845D01*
X575192Y569550D01*
G01X580266Y550714D02*
X579978D01*
X578560Y552132D01*
Y557101D01*
X577731Y557930D01*
Y564470D01*
X578560Y565299D01*
Y570243D01*
X580266Y571949D01*
G01X575166Y550500D02*
X574878D01*
X573178Y552200D01*
Y570211D01*
X575166Y572199D01*
G01X580266Y553314D02*
X581978Y555026D01*
Y556700D01*
X580978Y557700D01*
X579462D01*
X578791Y558371D01*
Y559648D01*
X579243Y560100D01*
X579578D01*
X580278Y560800D01*
Y561888D01*
X579568Y562598D01*
X579331D01*
X578791Y563138D01*
Y564029D01*
X579562Y564800D01*
X581078D01*
X582078Y565800D01*
Y567528D01*
X580266Y569340D01*
G01X779921Y27899D02*
Y30021D01*
X781800Y31900D01*
X783200D01*
X784656Y33356D01*
Y34700D01*
X784040Y35316D01*
Y48441D01*
X782567Y49914D01*
G01X773228Y27899D02*
Y29453D01*
X775475Y31700D01*
X776699D01*
X778275Y33276D01*
Y34900D01*
X777500Y35675D01*
Y48688D01*
X776274Y49914D01*
G01X786414Y30750D02*
X787184Y31520D01*
X788166D01*
X789494Y32848D01*
Y48994D01*
X786388Y52100D01*
G01X911506Y269321D02*
X904971D01*
X863050Y227400D01*
X861750D01*
X800675Y166325D01*
Y163075D01*
X797550Y159950D01*
X794300D01*
X781500Y147150D01*
Y144822D01*
X780350Y143672D01*
Y142212D01*
X781500Y141062D01*
Y139602D01*
X780350Y138452D01*
Y136992D01*
X781500Y135842D01*
Y134382D01*
X780350Y133232D01*
Y131772D01*
X781500Y130622D01*
Y129162D01*
X780350Y128012D01*
Y126552D01*
X781500Y125402D01*
Y107874D01*
X782000Y107374D01*
X782790D01*
X783400Y106764D01*
Y105374D01*
X782790Y104764D01*
X781210D01*
X780600Y104154D01*
Y102764D01*
X781210Y102154D01*
X782790D01*
X783400Y101544D01*
Y100154D01*
X782790Y99544D01*
X781210D01*
X780600Y98934D01*
Y95600D01*
X781988Y94212D01*
Y92288D01*
X780700Y91000D01*
Y86400D01*
X781800Y85300D01*
Y73200D01*
X780600Y72000D01*
Y67450D01*
X781900Y66150D01*
Y64800D01*
X779921Y62821D01*
Y54957D01*
G01D02*
X778800Y53836D01*
Y50900D01*
X781700Y48000D01*
Y46032D01*
X780167Y44499D01*
Y43300D01*
X781417Y42050D01*
Y41150D01*
X780067Y39800D01*
Y38501D01*
X781700Y36868D01*
Y34567D01*
X782567Y33700D01*
G01Y49914D02*
X780494Y51987D01*
Y53094D01*
X781988Y54588D01*
Y61488D01*
X784488Y63988D01*
Y93688D01*
X785600Y94800D01*
Y107600D01*
X783550Y109650D01*
Y146350D01*
X794675Y157475D01*
X797875D01*
X802675Y162275D01*
Y165475D01*
X862650Y225450D01*
X864000D01*
X905371Y266821D01*
X911506D01*
G01X773228Y54957D02*
Y59128D01*
X775100Y61000D01*
Y66300D01*
X774200Y67200D01*
Y72100D01*
X775100Y73000D01*
Y85700D01*
X774400Y86400D01*
Y91200D01*
X775100Y91900D01*
Y146500D01*
X860600Y232000D01*
X861650D01*
X905050Y275400D01*
X914647D01*
X915786Y274261D01*
G01X776188Y33700D02*
X775100Y34788D01*
Y36668D01*
X773667Y38101D01*
Y39300D01*
X775167Y40800D01*
Y42000D01*
X773717Y43450D01*
Y44849D01*
X775100Y46232D01*
Y48101D01*
X772300Y50901D01*
Y54029D01*
X773228Y54957D01*
G01X776274Y49914D02*
X774288Y51900D01*
Y53318D01*
X777500Y56530D01*
Y66500D01*
X778000Y67000D01*
Y72300D01*
X777900Y72400D01*
Y86200D01*
X778100Y86400D01*
Y146550D01*
X861000Y229450D01*
X862100D01*
X904300Y271650D01*
X915019D01*
X915898Y272529D01*
G01X786388Y52100D02*
X788164Y53876D01*
Y55850D01*
X787314Y56700D01*
X786314D01*
X785594Y57420D01*
Y59488D01*
X789468Y63362D01*
Y77580D01*
X790088Y78200D01*
Y79200D01*
X789468Y79820D01*
Y80580D01*
X790088Y81200D01*
Y82200D01*
X789468Y82820D01*
Y93480D01*
X790088Y94100D01*
Y95100D01*
X789468Y95720D01*
Y109463D01*
X787280Y111651D01*
Y113481D01*
X790680Y116881D01*
Y119763D01*
X788891Y121552D01*
X787752D01*
X786880Y122424D01*
Y124920D01*
X787752Y125792D01*
X788891D01*
X790380Y127281D01*
Y130663D01*
X786880Y134163D01*
Y145329D01*
X795001Y153450D01*
X802701D01*
X805926Y156675D01*
Y164375D01*
X863801Y222250D01*
X865549D01*
X868312Y225013D01*
X868948D01*
X869903Y225968D01*
Y226604D01*
X870856Y227557D01*
X871492D01*
X872447Y228512D01*
Y229148D01*
X873401Y230102D01*
X874037D01*
X874992Y231057D01*
Y231693D01*
X875945Y232646D01*
X876581D01*
X877536Y233601D01*
Y234237D01*
X878490Y235191D01*
X879126D01*
X880081Y236146D01*
Y236782D01*
X881034Y237735D01*
X881670D01*
X882625Y238690D01*
Y239326D01*
X883579Y240280D01*
X884215D01*
X885170Y241235D01*
Y241871D01*
X886123Y242824D01*
X886759D01*
X887714Y243779D01*
Y244415D01*
X888668Y245369D01*
X889304D01*
X890259Y246324D01*
Y246960D01*
X891212Y247913D01*
X891848D01*
X892803Y248868D01*
Y249504D01*
X893757Y250458D01*
X894393D01*
X895348Y251413D01*
Y252049D01*
X896301Y253002D01*
X896937D01*
X897892Y253957D01*
Y254593D01*
X898846Y255547D01*
X899482D01*
X900437Y256502D01*
Y257138D01*
X901390Y258091D01*
X902026D01*
X902981Y259046D01*
Y259682D01*
X903935Y260636D01*
X904571D01*
X905526Y261591D01*
Y262227D01*
X906479Y263180D01*
X908000D01*
G01X786388Y49500D02*
X784534Y51354D01*
Y59928D01*
X788408Y63802D01*
Y109020D01*
X786220Y111208D01*
Y113924D01*
X789620Y117324D01*
Y119320D01*
X788448Y120492D01*
X787309D01*
X785820Y121981D01*
Y125363D01*
X787309Y126852D01*
X788448D01*
X789320Y127724D01*
Y130223D01*
X785820Y133723D01*
Y145769D01*
X794561Y154510D01*
X802261D01*
X804866Y157115D01*
Y164815D01*
X863361Y223310D01*
X865109D01*
X906039Y264240D01*
X908000D01*
G01X786388Y33399D02*
X787207Y32580D01*
X787723D01*
X788434Y33291D01*
Y36580D01*
X786514Y38500D01*
Y39500D01*
X787114Y40100D01*
X787614D01*
X788434Y40920D01*
Y41880D01*
X787714Y42600D01*
X787002D01*
X786500Y43102D01*
Y44434D01*
X787116Y45050D01*
X787464D01*
X788434Y46020D01*
Y48553D01*
X787487Y49500D01*
X786388D01*
G01X908696Y327380D02*
X899221D01*
X863751Y362850D01*
Y380648D01*
X819799Y424600D01*
X815399D01*
X793399Y446600D01*
X789799D01*
X780074Y456325D01*
Y507775D01*
X781571Y509272D01*
Y511055D01*
X780674Y511952D01*
Y516474D01*
X781974Y517774D01*
Y519500D01*
X780800Y520674D01*
Y527100D01*
X781974Y528274D01*
Y529281D01*
X780674Y530581D01*
Y535375D01*
X781774Y536475D01*
Y537900D01*
X781600Y538074D01*
Y546800D01*
X781774Y546974D01*
Y548582D01*
X778958Y551398D01*
Y554928D01*
X779921Y555891D01*
Y555957D01*
G01X908816Y329880D02*
X900257D01*
X865636Y364501D01*
Y381463D01*
X820399Y426700D01*
X815899D01*
X792000Y450599D01*
Y453798D01*
X791021Y454777D01*
X790229D01*
X787671Y452219D01*
X786881Y452218D01*
X785861Y453238D01*
Y454030D01*
X788419Y456588D01*
X788418Y457380D01*
X787399Y458399D01*
X786607D01*
X784049Y455841D01*
X783259Y455840D01*
X782600Y456499D01*
Y507296D01*
X784474Y509170D01*
Y518674D01*
X786200Y520400D01*
Y521328D01*
X785590Y521938D01*
X783610D01*
X783100Y522448D01*
Y524428D01*
X783810Y525138D01*
X785590D01*
X786200Y525748D01*
Y526900D01*
X784474Y528626D01*
Y537700D01*
X785000Y538226D01*
Y546300D01*
X784474Y546826D01*
Y548657D01*
X782567Y550564D01*
Y550914D01*
G01X909426Y321780D02*
X897749D01*
X859981Y359548D01*
Y374967D01*
X857188Y381711D01*
X823816Y415083D01*
X823487Y415219D01*
X810255Y420700D01*
X775386Y455569D01*
Y510417D01*
X775145Y511000D01*
X774979Y511400D01*
X774374Y512861D01*
Y516130D01*
X775028Y517709D01*
Y529124D01*
X774274Y530946D01*
Y534890D01*
X775107Y536902D01*
Y548134D01*
X774124Y550508D01*
X772799Y551833D01*
Y555528D01*
X773228Y555957D01*
G01X909426Y324280D02*
X898785D01*
X861866Y361199D01*
Y379833D01*
X819099Y422600D01*
X814698D01*
X799221Y438077D01*
X798430D01*
X797372Y437019D01*
X796580D01*
X795560Y438039D01*
X795561Y438829D01*
X796619Y439887D01*
Y440679D01*
X795600Y441698D01*
X794808Y441699D01*
X793750Y440641D01*
X792958D01*
X791938Y441661D01*
X791939Y442451D01*
X792489Y443001D01*
Y443709D01*
X791478Y444720D01*
X790586Y444721D01*
X790128Y444263D01*
X789336D01*
X777574Y456025D01*
Y510952D01*
X778274Y511652D01*
Y516352D01*
X777300Y517326D01*
Y529193D01*
X778340Y530233D01*
Y535301D01*
X777774Y535867D01*
Y537500D01*
X778300Y538026D01*
Y546200D01*
X777774Y546726D01*
Y549414D01*
X776274Y550914D01*
G01X910113Y333980D02*
X901790D01*
X868581Y367189D01*
Y382718D01*
X821499Y429800D01*
X816971D01*
X799749Y447022D01*
Y450283D01*
X786280Y463752D01*
Y465248D01*
X786936Y465904D01*
X789493D01*
X790982Y467393D01*
Y469975D01*
X789493Y471464D01*
X787152D01*
X786280Y472336D01*
Y505845D01*
X789468Y509033D01*
Y541466D01*
X789942Y541940D01*
Y542940D01*
X789468Y543414D01*
Y544560D01*
X790088Y545180D01*
Y546180D01*
X789468Y546800D01*
Y550049D01*
X786417Y553100D01*
X786388D01*
G01Y550500D02*
X787369D01*
X788408Y549461D01*
Y509473D01*
X785220Y506285D01*
Y471896D01*
X786712Y470404D01*
X789053D01*
X789922Y469535D01*
Y467836D01*
X789050Y466964D01*
X786496D01*
X785220Y465688D01*
Y463312D01*
X798689Y449843D01*
Y446582D01*
X816531Y428740D01*
X821059D01*
X867521Y382278D01*
Y366749D01*
X901350Y332920D01*
X910113D01*
G01X779921Y555957D02*
X778216Y557662D01*
Y569315D01*
X781401Y572500D01*
X782567D01*
G01Y550914D02*
X782479D01*
X780793Y552600D01*
Y554292D01*
X781700Y555199D01*
Y556792D01*
X780556Y557936D01*
Y559356D01*
X781400Y560200D01*
Y561900D01*
X780556Y562744D01*
Y563956D01*
X781500Y564900D01*
Y566100D01*
X780901Y566699D01*
X779921D01*
G01X773228Y555957D02*
X771523Y557662D01*
Y567835D01*
X776188Y572500D01*
G01X776274Y550914D02*
X776186D01*
X774500Y552600D01*
Y554800D01*
X775000Y555300D01*
Y557199D01*
X773863Y558336D01*
Y559664D01*
X774800Y560601D01*
Y561999D01*
X773863Y562936D01*
Y564164D01*
X774900Y565201D01*
Y566099D01*
X774300Y566699D01*
X773228D01*
G01X786388Y553100D02*
X788100Y554812D01*
Y556400D01*
X787000Y557500D01*
X786050D01*
X785460Y558090D01*
Y559460D01*
X785980Y559980D01*
X786590D01*
X787200Y560590D01*
Y561980D01*
X786590Y562590D01*
X786010D01*
X785460Y563140D01*
Y564560D01*
X786100Y565200D01*
X787380D01*
X788119Y565939D01*
Y567845D01*
X786414Y569550D01*
G01X786388Y572199D02*
X784400Y570211D01*
Y552200D01*
X786100Y550500D01*
X786388D01*
G01X840157Y27899D02*
X841404Y29146D01*
Y30400D01*
X842704Y31700D01*
X843704D01*
X845504Y33500D01*
Y34900D01*
X844892Y35512D01*
Y48525D01*
X843503Y49914D01*
G01X810039Y27899D02*
Y29453D01*
X812286Y31700D01*
X813510D01*
X815086Y33276D01*
Y34900D01*
X814311Y35675D01*
Y48688D01*
X813085Y49914D01*
G01X836810D02*
X838199Y48525D01*
Y35512D01*
X838811Y34900D01*
Y33500D01*
X837011Y31700D01*
X836011D01*
X834711Y30400D01*
Y29146D01*
X833464Y27899D01*
G01X849896Y49914D02*
X851122Y48688D01*
Y35675D01*
X851897Y34900D01*
Y33276D01*
X850321Y31700D01*
X849097D01*
X846850Y29453D01*
Y27899D01*
G01X803346D02*
X804593Y29146D01*
Y30400D01*
X805893Y31700D01*
X806893D01*
X808693Y33500D01*
Y34900D01*
X808081Y35512D01*
Y48525D01*
X806692Y49914D01*
G01X796653Y27899D02*
X797900Y29146D01*
Y30400D01*
X799200Y31700D01*
X800200D01*
X802000Y33500D01*
Y34900D01*
X801388Y35512D01*
Y48525D01*
X799999Y49914D01*
G01X819378D02*
X820851Y48441D01*
Y35316D01*
X821467Y34700D01*
Y33356D01*
X820011Y31900D01*
X818611D01*
X816732Y30021D01*
Y27899D01*
G01X791488Y52314D02*
X794680Y49122D01*
Y33732D01*
X791488Y30540D01*
G01X823199Y52100D02*
X826305Y48994D01*
Y32848D01*
X824977Y31520D01*
X823995D01*
X823225Y30750D01*
G01X828299Y30540D02*
X831491Y33732D01*
Y49122D01*
X828299Y52314D01*
G01X823199Y33399D02*
X824018Y32580D01*
X824534D01*
X825245Y33291D01*
Y36580D01*
X823325Y38500D01*
Y39500D01*
X823925Y40100D01*
X824425D01*
X825245Y40920D01*
Y41880D01*
X824525Y42600D01*
X823813D01*
X823311Y43102D01*
Y44434D01*
X823927Y45050D01*
X824275D01*
X825245Y46020D01*
Y48553D01*
X824298Y49500D01*
X823199D01*
G01X840157Y54957D02*
X839036Y53836D01*
Y50900D01*
X842378Y47558D01*
Y46500D01*
X840578Y44700D01*
Y43125D01*
X841778Y41925D01*
Y40799D01*
X840578Y39599D01*
Y38226D01*
X841936Y36868D01*
Y35667D01*
X843503Y34100D01*
G01X925005Y215000D02*
X920700D01*
X915300Y209600D01*
Y209037D01*
X885600Y179337D01*
Y164900D01*
X883068Y162368D01*
X882206D01*
X878968Y165606D01*
X878106D01*
X877122Y164622D01*
Y163760D01*
X880360Y160522D01*
Y159660D01*
X879376Y158676D01*
X878514D01*
X876327Y160863D01*
X875465D01*
X874481Y159879D01*
Y159017D01*
X876668Y156830D01*
Y155968D01*
X875684Y154984D01*
X874822D01*
X872635Y157171D01*
X871773D01*
X870789Y156187D01*
Y155325D01*
X872976Y153138D01*
Y152276D01*
X871992Y151292D01*
X871130D01*
X868943Y153479D01*
X868081D01*
X867097Y152495D01*
Y151633D01*
X869284Y149446D01*
Y148584D01*
X868300Y147600D01*
X867438D01*
X865251Y149787D01*
X864389D01*
X863405Y148803D01*
Y147941D01*
X865592Y145754D01*
Y144892D01*
X840100Y119400D01*
Y95548D01*
X841974Y93674D01*
Y91593D01*
X841499Y91118D01*
Y86418D01*
X842099Y85818D01*
Y73099D01*
X841599Y72599D01*
Y66803D01*
X842000Y66402D01*
Y64800D01*
X840157Y62957D01*
Y54957D01*
G01X843503Y49914D02*
X841599Y51818D01*
Y53418D01*
X843090Y54909D01*
Y62241D01*
X844949Y64100D01*
Y66503D01*
X845499Y67053D01*
Y72401D01*
X844899Y73001D01*
Y85918D01*
X845599Y86618D01*
Y91018D01*
X844949Y91668D01*
Y99920D01*
X844449Y100420D01*
X843210D01*
X842600Y101030D01*
Y102420D01*
X843210Y103030D01*
X844840D01*
X845450Y103640D01*
Y105030D01*
X844840Y105640D01*
X843210D01*
X842600Y106250D01*
Y107640D01*
X843210Y108250D01*
X845690D01*
X846300Y108860D01*
Y110250D01*
X845690Y110860D01*
X843210D01*
X842600Y111470D01*
Y112860D01*
X843210Y113470D01*
X845400D01*
X845900Y113970D01*
Y115580D01*
X845400Y116080D01*
X843210D01*
X842600Y116690D01*
Y118850D01*
X846709Y122959D01*
X847571D01*
X848834Y121696D01*
X849696D01*
X850680Y122680D01*
Y123542D01*
X849417Y124805D01*
Y125667D01*
X850401Y126651D01*
X851263D01*
X852526Y125388D01*
X853388D01*
X854372Y126372D01*
Y127234D01*
X853109Y128497D01*
Y129359D01*
X888150Y164400D01*
Y178351D01*
X890754Y180955D01*
X891616D01*
X892828Y179742D01*
X893690D01*
X894674Y180726D01*
Y181588D01*
X893462Y182801D01*
Y183663D01*
X894446Y184647D01*
X895308D01*
X896520Y183434D01*
X897382D01*
X898366Y184418D01*
Y185280D01*
X897154Y186493D01*
Y187355D01*
X901300Y191501D01*
Y191590D01*
X901910Y192200D01*
X903000D01*
X919800Y209000D01*
X921300D01*
X923300Y211000D01*
X924900D01*
X926700Y212800D01*
X928000D01*
X929400Y214200D01*
Y215365D01*
X929407Y215372D01*
G01X810039Y54957D02*
Y56258D01*
X811100Y57319D01*
Y64099D01*
X811999Y64998D01*
Y66301D01*
X811099Y67201D01*
Y72103D01*
X812099Y73103D01*
Y85418D01*
X811099Y86418D01*
Y91218D01*
X811999Y92118D01*
Y95074D01*
X814547Y97622D01*
Y107997D01*
X817500Y110950D01*
Y143608D01*
X894950Y221058D01*
Y225658D01*
X909133Y239841D01*
X909886D01*
G01X812999Y33700D02*
X811911Y34788D01*
Y36668D01*
X810478Y38101D01*
Y39300D01*
X811978Y40800D01*
Y42000D01*
X810528Y43450D01*
Y44849D01*
X811911Y46232D01*
Y48101D01*
X809111Y50901D01*
Y54029D01*
X810039Y54957D01*
G01X813085Y49914D02*
X811235Y51764D01*
Y53454D01*
X813040Y55259D01*
X814799Y64199D01*
Y73003D01*
X814782Y73020D01*
Y86301D01*
X814885Y86404D01*
Y93272D01*
X817256Y97488D01*
Y107406D01*
X820000Y110150D01*
Y142572D01*
X897450Y220022D01*
Y224622D01*
X909328Y236500D01*
X910097D01*
X911081Y237484D01*
G01X836810Y34100D02*
X835336Y35574D01*
Y36668D01*
X833903Y38101D01*
Y39324D01*
X835403Y40824D01*
Y42176D01*
X833903Y43676D01*
Y44799D01*
X835578Y46474D01*
Y47859D01*
X832536Y50901D01*
Y54029D01*
X833464Y54957D01*
G01D02*
Y57183D01*
X835499Y59218D01*
Y66303D01*
X834899Y66903D01*
Y72699D01*
X835699Y73499D01*
Y85718D01*
X834899Y86518D01*
Y91218D01*
X835299Y91618D01*
Y93800D01*
X835100Y93999D01*
Y123050D01*
X856807Y144757D01*
Y150443D01*
X854100Y153150D01*
Y155090D01*
X855753Y156743D01*
X856615D01*
X859948Y153410D01*
X860810D01*
X861794Y154394D01*
Y155256D01*
X858461Y158589D01*
Y159451D01*
X859445Y160435D01*
X860307D01*
X863640Y157102D01*
X864502D01*
X865486Y158086D01*
Y158948D01*
X862153Y162281D01*
Y163143D01*
X863137Y164127D01*
X863999D01*
X867332Y160794D01*
X868194D01*
X869178Y161778D01*
Y162640D01*
X865845Y165973D01*
Y166835D01*
X919121Y220111D01*
X922216D01*
G01Y217611D02*
X920310D01*
X881357Y178658D01*
Y177796D01*
X883420Y175734D01*
Y174872D01*
X882436Y173888D01*
X881574D01*
X879961Y175500D01*
X879511Y175950D01*
X878649D01*
X877665Y174966D01*
Y174104D01*
X879728Y172042D01*
Y171180D01*
X878744Y170196D01*
X877882D01*
X875819Y172258D01*
X874957D01*
X873973Y171274D01*
Y170412D01*
X875578Y168808D01*
X876036Y168350D01*
Y167488D01*
X875052Y166504D01*
X874190D01*
X872127Y168566D01*
X871265D01*
X869591Y166892D01*
Y165659D01*
X872623Y162627D01*
Y161495D01*
X861364Y150236D01*
Y145114D01*
X837600Y121350D01*
Y93499D01*
X838299Y92800D01*
Y91718D01*
X838999Y91018D01*
Y86518D01*
X838199Y85718D01*
Y73101D01*
X839099Y72201D01*
Y67253D01*
X837999Y66153D01*
Y58182D01*
X835474Y55657D01*
Y54145D01*
X834999Y53670D01*
Y51725D01*
X836810Y49914D01*
G01X849810Y33700D02*
X848722Y34788D01*
Y36668D01*
X847289Y38101D01*
Y39300D01*
X848789Y40800D01*
Y42000D01*
X847339Y43450D01*
Y44849D01*
X848722Y46232D01*
Y48101D01*
X845922Y50901D01*
Y54029D01*
X846850Y54957D01*
G01D02*
Y56249D01*
X847884Y57283D01*
Y58416D01*
X846850Y59450D01*
Y61750D01*
X848810Y63710D01*
Y66291D01*
X847910Y67191D01*
Y72103D01*
X848910Y73103D01*
Y75900D01*
X850200Y77190D01*
Y81200D01*
X848910Y82490D01*
Y85418D01*
X847910Y86418D01*
Y91218D01*
X848810Y92118D01*
Y93590D01*
X848500Y93900D01*
Y105264D01*
X852000Y108764D01*
Y110215D01*
X851390Y110825D01*
X850210D01*
X849650Y111385D01*
Y112875D01*
X850210Y113435D01*
X851390D01*
X852000Y114045D01*
Y115435D01*
X851390Y116045D01*
X849860D01*
X849250Y116655D01*
Y118045D01*
X849860Y118655D01*
X851390D01*
X857800Y125065D01*
Y129109D01*
X892100Y163409D01*
Y173783D01*
X904900Y186583D01*
Y190501D01*
G01X907817Y188367D02*
X906950Y187500D01*
Y185097D01*
X894600Y172747D01*
Y162373D01*
X860950Y128723D01*
Y123950D01*
X854650Y117650D01*
Y108000D01*
X851100Y104450D01*
Y95000D01*
X851510Y94590D01*
Y91668D01*
X851760Y91418D01*
Y86468D01*
X851410Y86118D01*
Y83691D01*
X852800Y82301D01*
Y76099D01*
X851410Y74709D01*
Y73203D01*
X851760Y72853D01*
Y66653D01*
X851510Y66403D01*
Y63266D01*
X849600Y61356D01*
Y60100D01*
X850530Y59170D01*
Y55938D01*
X847910Y53318D01*
Y51900D01*
X849896Y49914D01*
G01X803346Y54957D02*
Y55577D01*
X805588Y57819D01*
Y66003D01*
X804788Y66803D01*
Y72587D01*
X805288Y73087D01*
Y85818D01*
X804688Y86418D01*
Y91118D01*
X805638Y92068D01*
Y93463D01*
X803500Y95601D01*
Y108700D01*
X805150Y110350D01*
Y130350D01*
X805650Y130850D01*
X810600D01*
X811400Y131650D01*
Y133401D01*
X810790Y134011D01*
X806960D01*
X806350Y134621D01*
Y136011D01*
X806960Y136621D01*
X810790D01*
X811400Y137231D01*
Y145950D01*
X855268Y189818D01*
Y190680D01*
X853005Y192943D01*
Y193805D01*
X853989Y194789D01*
X854851D01*
X857114Y192526D01*
X857976D01*
X858960Y193510D01*
Y194372D01*
X856697Y196635D01*
Y197497D01*
X857681Y198481D01*
X858543D01*
X860806Y196218D01*
X861668D01*
X862652Y197202D01*
Y198064D01*
X860389Y200327D01*
Y201189D01*
X861373Y202173D01*
X862235D01*
X864498Y199910D01*
X865360D01*
X866344Y200894D01*
Y201756D01*
X864081Y204019D01*
Y204881D01*
X865065Y205865D01*
X865927D01*
X868190Y203602D01*
X869052D01*
X870036Y204586D01*
Y205448D01*
X867773Y207711D01*
Y208573D01*
X868757Y209557D01*
X869619D01*
X871882Y207294D01*
X872744D01*
X888400Y222950D01*
Y227590D01*
X905849Y245039D01*
G01X806692Y34100D02*
X805125Y35667D01*
Y36868D01*
X803767Y38226D01*
Y39599D01*
X804967Y40799D01*
Y41925D01*
X803767Y43125D01*
Y44700D01*
X805567Y46500D01*
Y47558D01*
X802225Y50900D01*
Y53836D01*
X803346Y54957D01*
G01X806692Y49914D02*
X804788Y51818D01*
Y53418D01*
X808138Y56768D01*
Y66503D01*
X808688Y67053D01*
Y72511D01*
X808088Y73111D01*
Y85918D01*
X808788Y86618D01*
Y91018D01*
X808138Y91668D01*
Y96089D01*
X809750Y97701D01*
Y99326D01*
X809140Y99936D01*
X806710D01*
X806100Y100546D01*
Y101936D01*
X806710Y102546D01*
X809890D01*
X810500Y103156D01*
Y104546D01*
X809890Y105156D01*
X806710D01*
X806100Y105766D01*
Y107156D01*
X806710Y107766D01*
X809890D01*
X810500Y108376D01*
Y111275D01*
X811000Y111775D01*
X813126D01*
X814250Y112899D01*
Y115098D01*
X813640Y115708D01*
X809260D01*
X808650Y116318D01*
Y117708D01*
X809260Y118318D01*
X813640D01*
X814250Y118928D01*
Y120318D01*
X813640Y120928D01*
X809260D01*
X808650Y121538D01*
Y122928D01*
X809260Y123538D01*
X813640D01*
X814250Y124148D01*
Y125538D01*
X813640Y126148D01*
X809260D01*
X808650Y126758D01*
Y128148D01*
X809260Y128758D01*
X813640D01*
X814250Y129368D01*
Y145100D01*
X891700Y222550D01*
Y227354D01*
X908017Y243671D01*
G01X796653Y54957D02*
Y57183D01*
X798688Y59218D01*
Y66303D01*
X798088Y66903D01*
Y72487D01*
X798888Y73287D01*
Y85718D01*
X798088Y86518D01*
Y91218D01*
X798488Y91618D01*
Y111738D01*
X800400Y113650D01*
Y119341D01*
X799790Y119951D01*
X797560D01*
X796950Y120561D01*
Y121951D01*
X797560Y122561D01*
X799790D01*
X800400Y123171D01*
Y124561D01*
X799790Y125171D01*
X797560D01*
X796950Y125781D01*
Y127171D01*
X797560Y127781D01*
X799790D01*
X800400Y128391D01*
Y129781D01*
X799790Y130391D01*
X797560D01*
X796950Y131001D01*
Y132391D01*
X797560Y133001D01*
X799790D01*
X800400Y133611D01*
Y135001D01*
X799790Y135611D01*
X797660D01*
X797050Y136221D01*
Y137611D01*
X797660Y138221D01*
X799790D01*
X800400Y138831D01*
Y142774D01*
X817355Y159729D01*
Y160591D01*
X814827Y163119D01*
Y163827D01*
X815965Y164965D01*
X816673D01*
X819201Y162437D01*
X820063D01*
X821047Y163421D01*
Y164283D01*
X818494Y166836D01*
Y167544D01*
X819632Y168682D01*
X820340D01*
X822893Y166129D01*
X823755D01*
X824909Y167283D01*
Y167991D01*
X822504Y170396D01*
Y171104D01*
X867300Y215900D01*
X869618D01*
X873684Y219966D01*
X876566D01*
X879284Y222684D01*
Y225566D01*
X903303Y249585D01*
G01X799999Y34100D02*
X798525Y35574D01*
Y36668D01*
X797092Y38101D01*
Y39324D01*
X798592Y40824D01*
Y42176D01*
X797092Y43676D01*
Y44799D01*
X798767Y46474D01*
Y47859D01*
X795725Y50901D01*
Y54029D01*
X796653Y54957D01*
G01X799999Y49914D02*
X798188Y51725D01*
Y53558D01*
X799638Y55008D01*
Y56632D01*
X801188Y58182D01*
Y66153D01*
X802288Y67253D01*
Y72111D01*
X801388Y73011D01*
Y85718D01*
X802188Y86518D01*
Y91018D01*
X801000Y92206D01*
Y110250D01*
X802550Y111800D01*
Y141388D01*
X830000Y168838D01*
Y169700D01*
X828556Y171144D01*
Y172006D01*
X829540Y172990D01*
X830402D01*
X831846Y171546D01*
X832708D01*
X833692Y172530D01*
Y173392D01*
X832248Y174836D01*
Y175698D01*
X833232Y176682D01*
X834094D01*
X835538Y175238D01*
X836400D01*
X837384Y176222D01*
Y177084D01*
X835940Y178528D01*
Y179390D01*
X836924Y180374D01*
X837786D01*
X839230Y178930D01*
X840092D01*
X841076Y179914D01*
Y180776D01*
X839632Y182220D01*
Y183082D01*
X840616Y184066D01*
X841478D01*
X842922Y182622D01*
X843784D01*
X844768Y183606D01*
Y184468D01*
X843324Y185912D01*
Y186774D01*
X844308Y187758D01*
X845170D01*
X846614Y186314D01*
X847476D01*
X849140Y187978D01*
Y189810D01*
X847329Y191621D01*
Y192329D01*
X867050Y212050D01*
X874600D01*
X885137Y222587D01*
Y227863D01*
X905281Y248007D01*
G01X819378Y33700D02*
X818511Y34567D01*
Y36868D01*
X816878Y38501D01*
Y39800D01*
X818228Y41150D01*
Y42050D01*
X816978Y43300D01*
Y44499D01*
X818511Y46032D01*
Y48000D01*
X815611Y50900D01*
Y53836D01*
X816732Y54957D01*
G01D02*
Y62831D01*
X818599Y64698D01*
Y66251D01*
X817449Y67401D01*
Y72149D01*
X818799Y73499D01*
Y85368D01*
X817449Y86718D01*
Y90998D01*
X818790Y92339D01*
Y94990D01*
X820000Y96200D01*
Y106400D01*
X822500Y108900D01*
Y128651D01*
X824650Y130801D01*
Y136050D01*
X825700Y137100D01*
X830000D01*
X830600Y137700D01*
Y139040D01*
X829990Y139650D01*
X825660D01*
X825050Y140260D01*
Y141890D01*
X825660Y142500D01*
X829990D01*
X830600Y143110D01*
Y149636D01*
X899950Y218986D01*
Y223586D01*
X910907Y234543D01*
X911690D01*
X913532Y236385D01*
G01X914572Y233875D02*
X912972Y232275D01*
X912175D01*
X902450Y222550D01*
Y217950D01*
X832650Y148150D01*
Y134501D01*
X831678Y133529D01*
X830816D01*
X829730Y134616D01*
X828868D01*
X827884Y133632D01*
Y132770D01*
X828970Y131683D01*
Y130821D01*
X825000Y126851D01*
Y107100D01*
X822500Y104600D01*
Y96164D01*
X821299Y92964D01*
Y63266D01*
X818799Y60766D01*
Y54498D01*
X817500Y53199D01*
Y51792D01*
X819378Y49914D01*
G01X911363Y259280D02*
X907750D01*
X906797Y258327D01*
Y257691D01*
X905842Y256736D01*
X905206D01*
X904252Y255782D01*
Y255146D01*
X903297Y254191D01*
X902661D01*
X901708Y253238D01*
Y252602D01*
X900753Y251647D01*
X900117D01*
X899164Y250694D01*
Y250058D01*
X898209Y249103D01*
X897573D01*
X896619Y248149D01*
Y247513D01*
X895664Y246558D01*
X895028D01*
X893700Y245230D01*
Y243900D01*
X868200Y218400D01*
X865550D01*
X810250Y163100D01*
Y155700D01*
X803665Y149115D01*
X795366D01*
X792313Y146062D01*
Y145356D01*
X794568Y143101D01*
Y141268D01*
X793079Y139779D01*
X791552D01*
X790680Y138907D01*
Y136411D01*
X791552Y135539D01*
X793076D01*
X794568Y134047D01*
Y115950D01*
X795950Y114568D01*
Y109982D01*
X794568Y108600D01*
Y104082D01*
X796250Y102400D01*
Y98932D01*
X794568Y97250D01*
Y62901D01*
X790843Y59176D01*
Y57457D01*
X791500Y56800D01*
X792800D01*
X793314Y56286D01*
Y54140D01*
X791488Y52314D01*
G01X909892Y223607D02*
X906850Y220565D01*
Y216979D01*
X905881Y216010D01*
Y215374D01*
X904927Y214419D01*
X904290D01*
X903081Y213210D01*
Y212573D01*
X902126Y211619D01*
X901490D01*
X900537Y210666D01*
Y210030D01*
X899582Y209075D01*
X898946D01*
X897992Y208121D01*
Y207485D01*
X897037Y206530D01*
X896401D01*
X895448Y205577D01*
Y204941D01*
X894493Y203986D01*
X893857D01*
X892903Y203032D01*
Y202396D01*
X891948Y201441D01*
X891312D01*
X890359Y200488D01*
Y199852D01*
X889404Y198897D01*
X888768D01*
X887814Y197943D01*
Y197307D01*
X886859Y196352D01*
X886223D01*
X885270Y195399D01*
Y194763D01*
X884315Y193808D01*
X883679D01*
X882725Y192854D01*
Y192218D01*
X881770Y191263D01*
X881134D01*
X880181Y190310D01*
Y189674D01*
X879226Y188719D01*
X878590D01*
X877636Y187765D01*
Y187129D01*
X876681Y186174D01*
X876045D01*
X875092Y185221D01*
Y184585D01*
X874137Y183630D01*
X873501D01*
X843341Y153470D01*
Y152608D01*
X846757Y149192D01*
Y147607D01*
X844994Y145844D01*
X843409D01*
X841013Y148240D01*
X838111D01*
X835800Y145929D01*
Y132550D01*
X828680Y125430D01*
Y105449D01*
X826279Y103048D01*
Y101720D01*
X826899Y101100D01*
Y100100D01*
X826279Y99480D01*
Y98720D01*
X826899Y98100D01*
Y97100D01*
X826279Y96480D01*
Y95720D01*
X826899Y95100D01*
Y94100D01*
X826279Y93480D01*
Y80620D01*
X826899Y80000D01*
Y79000D01*
X826279Y78380D01*
Y76274D01*
X826729Y75824D01*
Y74475D01*
X826279Y74025D01*
Y62362D01*
X824950Y61033D01*
Y60397D01*
X823995Y59442D01*
X823359D01*
X822405Y58488D01*
Y57420D01*
X823125Y56700D01*
X824125D01*
X824885Y55940D01*
Y53786D01*
X823199Y52100D01*
G01X828299Y52314D02*
X830125Y54140D01*
Y55700D01*
X828105Y57720D01*
Y58588D01*
X829079Y59562D01*
X829955D01*
X830663Y60270D01*
Y61146D01*
X831999Y62482D01*
Y63314D01*
X831379Y63934D01*
Y74580D01*
X831999Y75200D01*
Y76200D01*
X831379Y76820D01*
Y77580D01*
X831999Y78200D01*
Y79200D01*
X831379Y79820D01*
Y93547D01*
X832480Y94648D01*
Y123781D01*
X842348Y133649D01*
Y135391D01*
X839524Y138215D01*
Y139074D01*
X840514Y140064D01*
X841371D01*
X844196Y137239D01*
X845938D01*
X852280Y143581D01*
Y152052D01*
X850480Y153852D01*
Y155174D01*
X918783Y223477D01*
X919419D01*
X920374Y224432D01*
Y225068D01*
X922311Y227005D01*
Y230644D01*
G01X911363Y260340D02*
X907310D01*
X892640Y245670D01*
Y244340D01*
X867760Y219460D01*
X865110D01*
X809190Y163540D01*
Y156140D01*
X803225Y150175D01*
X794926D01*
X791253Y146502D01*
Y144916D01*
X793508Y142661D01*
Y141711D01*
X792636Y140839D01*
X791109D01*
X789620Y139350D01*
Y135968D01*
X791109Y134479D01*
X792636D01*
X793508Y133607D01*
Y115510D01*
X794890Y114128D01*
Y110422D01*
X793508Y109040D01*
Y103642D01*
X795190Y101960D01*
Y99372D01*
X793508Y97690D01*
Y63341D01*
X789783Y59616D01*
Y51419D01*
X791488Y49714D01*
G01D02*
Y49715D01*
X792586D01*
X793620Y48681D01*
Y45906D01*
X792914Y45200D01*
X792400D01*
X791720Y44520D01*
Y43480D01*
X792400Y42800D01*
X792900D01*
X793620Y42080D01*
Y40707D01*
X792813Y39900D01*
X792115D01*
X791514Y39299D01*
Y38101D01*
X792115Y37500D01*
X792913D01*
X793620Y36793D01*
Y34172D01*
X792597Y33149D01*
X791488D01*
G01X823199Y49500D02*
X821345Y51354D01*
Y58931D01*
X825219Y62805D01*
Y103488D01*
X827620Y105889D01*
Y125870D01*
X834740Y132990D01*
Y146369D01*
X837671Y149300D01*
X841453D01*
X843849Y146904D01*
X844554D01*
X845697Y148047D01*
Y148752D01*
X842281Y152168D01*
Y153910D01*
X905790Y217419D01*
Y221005D01*
X909142Y224357D01*
G01X828299Y49714D02*
Y49715D01*
X829397D01*
X830431Y48681D01*
Y45906D01*
X829725Y45200D01*
X829211D01*
X828511Y44500D01*
Y43500D01*
X829211Y42800D01*
X829711D01*
X830431Y42080D01*
Y40707D01*
X829624Y39900D01*
X828926D01*
X828325Y39299D01*
Y38101D01*
X828926Y37500D01*
X829724D01*
X830431Y36793D01*
Y34172D01*
X829408Y33149D01*
X828299D01*
G01X921251Y230644D02*
Y227445D01*
X849422Y155616D01*
X849420Y155617D01*
Y153412D01*
X851220Y151612D01*
Y144021D01*
X845498Y138299D01*
X844636D01*
X841811Y141124D01*
X840074D01*
X838464Y139514D01*
Y137775D01*
X841288Y134951D01*
Y134089D01*
X831420Y124221D01*
Y95088D01*
X830319Y93987D01*
Y62305D01*
X827045Y59031D01*
Y58199D01*
X826575Y57729D01*
Y51438D01*
X828299Y49714D01*
G01X904895Y356741D02*
X902036Y359600D01*
X901200D01*
X883100Y377700D01*
Y387640D01*
X858900Y411840D01*
Y416800D01*
X823600Y452100D01*
Y489800D01*
X812206Y501194D01*
Y510650D01*
X811277Y511579D01*
Y516729D01*
X811999Y517451D01*
Y529401D01*
X811250Y530150D01*
Y535443D01*
X811949Y536142D01*
Y548657D01*
X809659Y550947D01*
Y555577D01*
X810039Y555957D01*
G01X813085Y550914D02*
X814599Y549400D01*
Y547001D01*
X816100Y545500D01*
Y539001D01*
X814599Y537500D01*
Y535456D01*
X815199Y534856D01*
Y530697D01*
X814301Y529799D01*
Y525713D01*
X814911Y525103D01*
X816078D01*
X816688Y524493D01*
Y523103D01*
X816078Y522493D01*
X814911D01*
X814301Y521883D01*
Y517855D01*
X814900Y517256D01*
Y511400D01*
X814600Y511100D01*
Y508025D01*
X815210Y507415D01*
X816713D01*
X817323Y506805D01*
Y505415D01*
X816713Y504805D01*
X815210D01*
X814600Y504195D01*
Y502700D01*
X826200Y491100D01*
Y452200D01*
X860785Y417615D01*
Y412621D01*
X884985Y388421D01*
Y380187D01*
X906556Y358616D01*
G01X901966Y348100D02*
X877181Y372885D01*
Y386518D01*
X829767Y433932D01*
Y436740D01*
X817100Y449407D01*
Y464100D01*
X816300Y464900D01*
X814700D01*
X813900Y464100D01*
Y456100D01*
X813100Y455300D01*
X811500D01*
X810700Y456100D01*
Y493400D01*
X809900Y494200D01*
X808300D01*
X807500Y493400D01*
Y485300D01*
X806700Y484500D01*
X805100D01*
X804300Y485300D01*
Y507612D01*
X805288Y508600D01*
Y511157D01*
X804788Y511657D01*
Y517057D01*
X805588Y517857D01*
Y519000D01*
X805022Y519566D01*
Y527322D01*
X805588Y527888D01*
Y529219D01*
X804488Y530319D01*
Y535342D01*
X805388Y536242D01*
Y537802D01*
X805000Y538190D01*
Y547000D01*
X805388Y547388D01*
Y548707D01*
X801988Y552107D01*
Y554599D01*
X803346Y555957D01*
G01X902716Y350017D02*
X879066Y373667D01*
Y387417D01*
X846002Y420481D01*
Y421343D01*
X846949Y422290D01*
Y423152D01*
X845548Y424553D01*
X844686D01*
X843739Y423606D01*
X842877D01*
X841476Y425007D01*
Y425869D01*
X842423Y426816D01*
Y427678D01*
X841022Y429079D01*
X840160D01*
X839213Y428132D01*
X838351D01*
X836950Y429533D01*
Y430395D01*
X837897Y431342D01*
Y432204D01*
X836496Y433605D01*
X835634D01*
X834687Y432658D01*
X833825D01*
X832300Y434183D01*
Y437743D01*
X819600Y450443D01*
Y487900D01*
X818800Y488700D01*
X817200D01*
X816400Y487900D01*
Y468200D01*
X815600Y467400D01*
X814000D01*
X813200Y468200D01*
Y494543D01*
X808200Y499543D01*
Y511101D01*
X809100Y512001D01*
Y516099D01*
X807800Y517399D01*
Y519700D01*
X808400Y520300D01*
Y527700D01*
X807762Y528338D01*
Y529471D01*
X808988Y530697D01*
Y535612D01*
X807616Y536984D01*
Y538316D01*
X808400Y539100D01*
Y546300D01*
X807900Y546800D01*
Y549758D01*
X806692Y550966D01*
Y550914D01*
G01X905056Y340941D02*
X903360D01*
X873411Y370890D01*
Y384788D01*
X824767Y433432D01*
Y434668D01*
X823920Y435515D01*
X822788D01*
X822152Y434879D01*
X821020D01*
X819889Y436010D01*
Y437142D01*
X820525Y437778D01*
Y438910D01*
X819394Y440041D01*
X818262D01*
X817626Y439405D01*
X816494D01*
X815363Y440536D01*
Y441668D01*
X815999Y442304D01*
Y443436D01*
X814868Y444567D01*
X813736D01*
X813100Y443931D01*
X811968D01*
X810837Y445062D01*
Y446194D01*
X811473Y446830D01*
Y447962D01*
X810342Y449093D01*
X809210D01*
X808574Y448457D01*
X807442D01*
X806311Y449588D01*
Y450720D01*
X806947Y451356D01*
Y452488D01*
X799300Y460135D01*
Y501044D01*
X798500Y501844D01*
X796900D01*
X796100Y501044D01*
Y496700D01*
X795300Y495900D01*
X793700D01*
X792900Y496700D01*
Y502399D01*
X798453Y507952D01*
Y511692D01*
X798088Y512057D01*
Y516957D01*
X798688Y517557D01*
Y519000D01*
X798300Y519388D01*
Y527600D01*
X798688Y527988D01*
Y529475D01*
X797615Y530548D01*
Y535169D01*
X798888Y536442D01*
Y537600D01*
X798322Y538166D01*
Y546822D01*
X798888Y547388D01*
Y548557D01*
X795988Y551457D01*
Y555292D01*
X796653Y555957D01*
G01X905056Y343441D02*
X903960D01*
X875296Y372105D01*
Y385603D01*
X827267Y433632D01*
Y435704D01*
X814600Y448371D01*
Y451100D01*
X812964Y452736D01*
X810235D01*
X808100Y454871D01*
Y457399D01*
X805164Y460335D01*
X802636D01*
X801800Y461171D01*
Y463450D01*
X802360Y464010D01*
X808240D01*
X808800Y464570D01*
Y466010D01*
X808240Y466570D01*
X802360D01*
X801800Y467130D01*
Y468570D01*
X802360Y469130D01*
X808240D01*
X808800Y469690D01*
Y471130D01*
X808240Y471690D01*
X802360D01*
X801800Y472250D01*
Y473690D01*
X802360Y474250D01*
X808240D01*
X808800Y474810D01*
Y476250D01*
X808240Y476810D01*
X802360D01*
X801800Y477370D01*
Y478810D01*
X802360Y479370D01*
X808240D01*
X808800Y479930D01*
Y481370D01*
X808240Y481930D01*
X802360D01*
X801800Y482490D01*
Y508788D01*
X801388Y509200D01*
Y511257D01*
X802288Y512157D01*
Y516557D01*
X801188Y517657D01*
Y519100D01*
X801700Y519612D01*
Y527700D01*
X801488Y527912D01*
Y529683D01*
X802054Y530249D01*
Y535745D01*
X801388Y536411D01*
Y537688D01*
X801700Y538000D01*
Y546700D01*
X801388Y547012D01*
Y549568D01*
X801345D01*
X799999Y550914D01*
G01X908067Y360641D02*
X886870Y381838D01*
Y389202D01*
X862670Y413402D01*
Y418430D01*
X828700Y452400D01*
Y460140D01*
X829584Y461024D01*
Y461984D01*
X828700Y462868D01*
Y492500D01*
X819444Y501756D01*
Y509856D01*
X817449Y511851D01*
Y516307D01*
X818600Y517458D01*
Y519399D01*
X818400Y519599D01*
Y527900D01*
X818599Y528099D01*
Y529467D01*
X817430Y530636D01*
Y535230D01*
X818649Y536449D01*
Y538000D01*
X818400Y538249D01*
Y546900D01*
X818649Y547149D01*
Y548657D01*
X815299Y552007D01*
Y554524D01*
X816732Y555957D01*
G01X909800Y362444D02*
X888755Y383489D01*
Y389983D01*
X864555Y414183D01*
Y416200D01*
X865055Y416700D01*
X868100D01*
X868800Y417400D01*
Y418600D01*
X867900Y419500D01*
X865500D01*
X864555Y420445D01*
Y423745D01*
X831200Y457100D01*
Y459104D01*
X832000Y459904D01*
X834300D01*
X835100Y460704D01*
Y462304D01*
X834300Y463104D01*
X832000D01*
X831200Y463904D01*
Y493500D01*
X821299Y503401D01*
Y504480D01*
X821909Y505090D01*
X823200D01*
X823700Y505590D01*
Y507790D01*
X823200Y508290D01*
X821909D01*
X821299Y508900D01*
Y518800D01*
X822100Y519601D01*
Y521825D01*
X821490Y522435D01*
X820710D01*
X820100Y523045D01*
Y525025D01*
X820710Y525635D01*
X821490D01*
X822100Y526245D01*
Y527400D01*
X821299Y528201D01*
Y537700D01*
X821800Y538201D01*
Y540456D01*
X820500Y541756D01*
Y543356D01*
X821800Y544656D01*
Y546400D01*
X821299Y546901D01*
Y548643D01*
X819378Y550564D01*
Y550914D01*
G01X791488Y550714D02*
X792453D01*
X793508Y549659D01*
Y546920D01*
X792888Y546300D01*
Y545300D01*
X793508Y544680D01*
Y543680D01*
X792888Y543060D01*
Y542060D01*
X793508Y541440D01*
Y540440D01*
X792888Y539820D01*
Y538820D01*
X793508Y538200D01*
Y536424D01*
X793008Y535924D01*
Y534924D01*
X793508Y534424D01*
Y531267D01*
X793021Y530780D01*
Y529780D01*
X793508Y529293D01*
Y527920D01*
X792888Y527300D01*
Y526300D01*
X793508Y525680D01*
Y524680D01*
X792888Y524060D01*
Y523060D01*
X793508Y522440D01*
Y521440D01*
X792888Y520820D01*
Y519820D01*
X793508Y519200D01*
Y508579D01*
X792527Y507598D01*
X791649D01*
X790942Y506891D01*
Y506013D01*
X789120Y504191D01*
Y493309D01*
X790609Y491820D01*
X794809D01*
X795520Y491109D01*
Y488730D01*
X794648Y487858D01*
X790504D01*
X789042Y486396D01*
Y483814D01*
X790558Y482298D01*
X794648D01*
X795520Y481426D01*
Y479730D01*
X794648Y478858D01*
X791009D01*
X789520Y477369D01*
Y474787D01*
X791009Y473298D01*
X794648D01*
X795520Y472426D01*
Y468712D01*
X792556Y465748D01*
Y461416D01*
X802539Y451433D01*
Y448129D01*
X818828Y431840D01*
X822160D01*
X870466Y383534D01*
Y368834D01*
X902371Y336929D01*
X904992D01*
G01X912012Y365426D02*
X902235Y375202D01*
X902233D01*
X892460Y384975D01*
Y390444D01*
X872260Y410644D01*
Y420308D01*
X836696Y455872D01*
Y457325D01*
X837680Y458309D01*
X839891D01*
X842100Y460518D01*
Y462900D01*
X840331Y464669D01*
X838052D01*
X834880Y467841D01*
Y495452D01*
X827180Y503152D01*
Y510252D01*
X826279Y511153D01*
Y541764D01*
X826623Y542108D01*
Y543108D01*
X826279Y543452D01*
Y544545D01*
X826729Y544995D01*
Y545995D01*
X826279Y546445D01*
Y550049D01*
X823228Y553100D01*
X823199D01*
G01X828299Y550714D02*
X829253D01*
X830319Y549648D01*
Y546854D01*
X829699Y546234D01*
Y545234D01*
X830319Y544614D01*
Y543614D01*
X829699Y542994D01*
Y541994D01*
X830319Y541374D01*
Y540307D01*
X829805Y539793D01*
Y538793D01*
X830319Y538279D01*
Y527893D01*
X829924Y527498D01*
Y526498D01*
X830319Y526103D01*
Y504210D01*
X837620Y496909D01*
Y471009D01*
X846420Y462209D01*
Y460752D01*
X842420Y456752D01*
Y454248D01*
X844348Y452320D01*
X847018D01*
X849800Y455102D01*
X851025D01*
X852801Y453326D01*
Y452102D01*
X849739Y449041D01*
Y446929D01*
X852127Y444541D01*
X854237D01*
X857299Y447602D01*
X858525D01*
X860301Y445826D01*
Y444602D01*
X859795Y444096D01*
X857239Y441541D01*
Y439429D01*
X874700Y421968D01*
Y411601D01*
X894900Y391401D01*
Y386423D01*
X909605Y371718D01*
G01X904992Y337989D02*
X902811D01*
X871526Y369274D01*
Y383974D01*
X822600Y432900D01*
X819268D01*
X803599Y448569D01*
Y451873D01*
X793616Y461856D01*
Y465308D01*
X796580Y468272D01*
Y472866D01*
X795088Y474358D01*
X791452D01*
X790580Y475230D01*
Y476926D01*
X791452Y477798D01*
X795091D01*
X796580Y479287D01*
Y481866D01*
X795088Y483358D01*
X790998D01*
X790102Y484254D01*
Y485956D01*
X790944Y486798D01*
X795088D01*
X796580Y488290D01*
Y491549D01*
X795249Y492880D01*
X791049D01*
X790180Y493749D01*
Y503748D01*
X794568Y508136D01*
Y550270D01*
X791524Y553314D01*
X791488D01*
G01X823199Y550500D02*
X824327D01*
X825219Y549608D01*
Y510710D01*
X826120Y509809D01*
Y502709D01*
X833820Y495009D01*
Y467401D01*
X837612Y463609D01*
X839891D01*
X841040Y462460D01*
Y460958D01*
X839451Y459369D01*
X837240D01*
X835636Y457765D01*
Y455432D01*
X871200Y419868D01*
Y410204D01*
X891400Y390004D01*
Y384535D01*
X911261Y364674D01*
G01X828299Y553314D02*
X828324D01*
X831379Y550259D01*
Y504650D01*
X838680Y497349D01*
Y471452D01*
X847480Y462652D01*
Y460309D01*
X843480Y456309D01*
Y454691D01*
X844791Y453380D01*
X846575D01*
X849357Y456162D01*
X851468D01*
X853861Y453769D01*
Y451659D01*
X850799Y448598D01*
Y447372D01*
X852570Y445601D01*
X853797D01*
X856859Y448662D01*
X858968D01*
X861361Y446269D01*
Y444159D01*
X859795Y442594D01*
X858299Y441098D01*
Y439869D01*
X875760Y422408D01*
Y412041D01*
X895960Y391841D01*
Y386865D01*
X899260Y383565D01*
Y383564D01*
X910355Y372469D01*
G01X912787Y380873D02*
X908400Y385260D01*
Y387632D01*
X883114Y412918D01*
Y421658D01*
X886403Y424947D01*
Y427320D01*
X885793Y427930D01*
X883087D01*
X882477Y428540D01*
Y429930D01*
X883087Y430540D01*
X885793D01*
X886403Y431150D01*
Y433599D01*
X866305Y453697D01*
Y454405D01*
X866983Y455083D01*
X868115D01*
X874883Y448315D01*
X876015D01*
X877146Y449446D01*
Y450578D01*
X846300Y481424D01*
Y501164D01*
X842300Y505164D01*
Y510956D01*
X840900Y512356D01*
Y515900D01*
X842800Y517800D01*
Y519099D01*
X841832Y520067D01*
Y527832D01*
X842399Y528399D01*
Y529347D01*
X841299Y530447D01*
Y535342D01*
X842199Y536242D01*
Y537700D01*
X841800Y538099D01*
Y546700D01*
X842199Y547099D01*
Y548707D01*
X838799Y552107D01*
Y554599D01*
X840157Y555957D01*
G01X914566Y382652D02*
X910900Y386318D01*
Y389300D01*
X889300Y410900D01*
Y412872D01*
X888690Y413482D01*
X886164D01*
X885554Y414092D01*
Y415482D01*
X886164Y416092D01*
X888690D01*
X889300Y416702D01*
Y418092D01*
X888690Y418702D01*
X886164D01*
X885554Y419312D01*
Y420702D01*
X886164Y421312D01*
X888690D01*
X889300Y421922D01*
Y433747D01*
X878419Y444628D01*
Y445760D01*
X879550Y446891D01*
X880682D01*
X887346Y440227D01*
X888478D01*
X889609Y441358D01*
Y442490D01*
X851100Y480999D01*
Y481893D01*
X850300Y482693D01*
X849069D01*
X848243Y483519D01*
Y485119D01*
X849017Y485893D01*
X850300D01*
X851100Y486693D01*
Y488293D01*
X850300Y489093D01*
X849122D01*
X848322Y489893D01*
Y491493D01*
X849122Y492293D01*
X850300D01*
X851100Y493093D01*
Y494693D01*
X850300Y495493D01*
X848553D01*
X847925Y496121D01*
Y497721D01*
X848630Y498426D01*
X850127D01*
X850670Y498969D01*
Y500330D01*
X844800Y506200D01*
Y511558D01*
X845499Y512257D01*
Y516401D01*
X844949Y516951D01*
Y519300D01*
X845200Y519551D01*
Y527800D01*
X844949Y528051D01*
Y529697D01*
X845799Y530547D01*
Y535302D01*
X844799Y536302D01*
Y537500D01*
X845200Y537901D01*
Y546400D01*
X844799Y546801D01*
Y549670D01*
X843503Y550966D01*
Y550914D01*
G01X906947Y379641D02*
X898200Y388388D01*
Y392500D01*
X877700Y413000D01*
Y424175D01*
X862081Y439794D01*
Y441026D01*
X863212Y442157D01*
X864244D01*
X872583Y433818D01*
X873715D01*
X874846Y434949D01*
Y436754D01*
X850600Y461000D01*
Y463236D01*
X847539Y466297D01*
Y467329D01*
X848789Y468579D01*
Y469711D01*
X847658Y470842D01*
X846526D01*
X845276Y469592D01*
X844244D01*
X841300Y472536D01*
Y499092D01*
X835400Y504992D01*
Y511556D01*
X834500Y512456D01*
Y516558D01*
X835499Y517557D01*
Y519200D01*
X835100Y519599D01*
Y527700D01*
X835499Y528099D01*
Y529497D01*
X834426Y530570D01*
Y535169D01*
X835699Y536442D01*
Y537500D01*
X835100Y538099D01*
Y546500D01*
X835699Y547099D01*
Y548557D01*
X832799Y551457D01*
Y555292D01*
X833464Y555957D01*
G01X908656Y381468D02*
X900085Y390039D01*
Y393281D01*
X880400Y412966D01*
Y428646D01*
X879790Y429256D01*
X877147D01*
X876537Y429866D01*
Y431256D01*
X877147Y431866D01*
X879790D01*
X880400Y432476D01*
Y434736D01*
X853100Y462036D01*
Y463168D01*
X854231Y464299D01*
X855363D01*
X863165Y456497D01*
X864297D01*
X865428Y457628D01*
Y458760D01*
X855551Y468637D01*
X854689D01*
X853157Y467105D01*
X852295D01*
X850894Y468506D01*
Y469368D01*
X852426Y470900D01*
Y471762D01*
X848760Y475428D01*
X847898D01*
X845666Y473196D01*
X844804D01*
X843403Y474597D01*
Y475459D01*
X845635Y477691D01*
Y478553D01*
X843800Y480388D01*
Y500128D01*
X838199Y505729D01*
Y511257D01*
X839099Y512157D01*
Y516301D01*
X837999Y517401D01*
Y519500D01*
X838500Y520001D01*
Y528000D01*
X838299Y528201D01*
Y529697D01*
X838865Y530263D01*
Y535635D01*
X838199Y536301D01*
Y537699D01*
X838500Y538000D01*
Y546399D01*
X838199Y546700D01*
Y549568D01*
X838156D01*
X836810Y550914D01*
G01X911958Y398644D02*
X901300Y409302D01*
Y416899D01*
X893300Y424899D01*
Y444533D01*
X855100Y482733D01*
Y501900D01*
X848774Y508226D01*
Y510893D01*
X847978Y511689D01*
Y516557D01*
X848810Y517389D01*
Y529489D01*
X847762Y530537D01*
Y535144D01*
X848760Y536142D01*
Y548441D01*
X846307Y550894D01*
Y555414D01*
X846850Y555957D01*
G01X840157D02*
X838452Y557662D01*
Y567849D01*
X843503Y572900D01*
G01Y550914D02*
X843415D01*
X841729Y552600D01*
Y554292D01*
X841904Y554467D01*
Y557100D01*
X840792Y558212D01*
Y559288D01*
X841804Y560300D01*
Y561500D01*
X840792Y562512D01*
Y563588D01*
X841929Y564725D01*
Y565999D01*
X841229Y566699D01*
X840157D01*
G01X810039Y555957D02*
X808334Y557662D01*
Y567635D01*
X808956Y568257D01*
Y569445D01*
X812011Y572500D01*
X812999D01*
G01X810039Y566699D02*
X811111D01*
X811711Y566099D01*
Y565201D01*
X810674Y564164D01*
Y562936D01*
X811611Y561999D01*
Y560601D01*
X810674Y559664D01*
Y558336D01*
X811811Y557199D01*
Y555300D01*
X811311Y554800D01*
Y552600D01*
X812997Y550914D01*
X813085D01*
G01X833464Y555957D02*
X831759Y557662D01*
Y567849D01*
X836810Y572900D01*
G01Y550914D02*
X836722D01*
X835036Y552600D01*
Y554292D01*
X835211Y554467D01*
Y557100D01*
X834099Y558212D01*
Y559288D01*
X835111Y560300D01*
Y561500D01*
X834099Y562512D01*
Y563588D01*
X835236Y564725D01*
Y565999D01*
X834536Y566699D01*
X833464D01*
G01X846850Y555957D02*
X845145Y557662D01*
Y567635D01*
X845767Y568257D01*
Y569445D01*
X848822Y572500D01*
X849810D01*
G01X849896Y550914D02*
X849808D01*
X848122Y552600D01*
Y554800D01*
X848622Y555300D01*
Y557199D01*
X847485Y558336D01*
Y559664D01*
X848422Y560601D01*
Y561999D01*
X847485Y562936D01*
Y564164D01*
X848522Y565201D01*
Y566099D01*
X847922Y566699D01*
X846850D01*
G01X803346Y555957D02*
X801641Y557662D01*
Y567849D01*
X806692Y572900D01*
G01Y550914D02*
X806604D01*
X804918Y552600D01*
Y554292D01*
X805093Y554467D01*
Y557100D01*
X803981Y558212D01*
Y559288D01*
X804993Y560300D01*
Y561500D01*
X803981Y562512D01*
Y563588D01*
X805118Y564725D01*
Y565999D01*
X804418Y566699D01*
X803346D01*
G01X796653Y555957D02*
X794948Y557662D01*
Y567849D01*
X799999Y572900D01*
G01Y550914D02*
X799911D01*
X798225Y552600D01*
Y554292D01*
X798400Y554467D01*
Y557100D01*
X797288Y558212D01*
Y559288D01*
X798300Y560300D01*
Y561500D01*
X797288Y562512D01*
Y563588D01*
X798425Y564725D01*
Y565999D01*
X797725Y566699D01*
X796653D01*
G01X816732Y555957D02*
X815027Y557662D01*
Y569315D01*
X818212Y572500D01*
X819378D01*
G01Y550914D02*
X819290D01*
X817604Y552600D01*
Y554292D01*
X818511Y555199D01*
Y556792D01*
X817367Y557936D01*
Y559356D01*
X818211Y560200D01*
Y561900D01*
X817367Y562744D01*
Y563956D01*
X818311Y564900D01*
Y566100D01*
X817712Y566699D01*
X816732D01*
G01X791488Y571949D02*
X789783Y570244D01*
Y565300D01*
X788953Y564470D01*
Y557930D01*
X789783Y557100D01*
Y552131D01*
X791200Y550714D01*
X791488D01*
G01X823199Y553100D02*
X824911Y554812D01*
Y556400D01*
X823811Y557500D01*
X822861D01*
X822271Y558090D01*
Y559460D01*
X822791Y559980D01*
X823401D01*
X824011Y560590D01*
Y561980D01*
X823401Y562590D01*
X822821D01*
X822271Y563140D01*
Y564560D01*
X822911Y565200D01*
X824191D01*
X824930Y565939D01*
Y567845D01*
X823225Y569550D01*
G01X828299Y571949D02*
X826594Y570244D01*
Y565300D01*
X825764Y564470D01*
Y557930D01*
X826594Y557100D01*
Y552131D01*
X828011Y550714D01*
X828299D01*
G01X791488Y553314D02*
X793200Y555026D01*
Y556700D01*
X792200Y557700D01*
X790684D01*
X790013Y558371D01*
Y559648D01*
X790465Y560100D01*
X790800D01*
X791498Y560798D01*
Y561890D01*
X790790Y562598D01*
X790553D01*
X790013Y563138D01*
Y564029D01*
X790784Y564800D01*
X792300D01*
X793300Y565800D01*
Y567528D01*
X791488Y569340D01*
G01X823199Y572199D02*
X821211Y570211D01*
Y552200D01*
X822911Y550500D01*
X823199D01*
G01X828299Y569340D02*
X830111Y567528D01*
Y565800D01*
X829111Y564800D01*
X827595D01*
X826824Y564029D01*
Y563138D01*
X827364Y562598D01*
X827601D01*
X828311Y561888D01*
Y560800D01*
X827611Y560100D01*
X827276D01*
X826824Y559648D01*
Y558371D01*
X827495Y557700D01*
X829011D01*
X830011Y556700D01*
Y555026D01*
X828299Y553314D01*
G01X856189Y49914D02*
X857662Y48441D01*
Y35316D01*
X858278Y34700D01*
Y33356D01*
X856822Y31900D01*
X855422D01*
X853543Y30021D01*
Y27899D01*
G01X876968D02*
X878215Y29146D01*
Y30400D01*
X879515Y31700D01*
X880515D01*
X882315Y33500D01*
Y34900D01*
X881703Y35512D01*
Y48525D01*
X880314Y49914D01*
G01X870275Y27899D02*
X871522Y29146D01*
Y30400D01*
X872822Y31700D01*
X873822D01*
X875622Y33500D01*
Y34900D01*
X875010Y35512D01*
Y48525D01*
X873621Y49914D01*
G01X893000D02*
X894473Y48441D01*
Y35316D01*
X895089Y34700D01*
Y33356D01*
X893633Y31900D01*
X892233D01*
X890354Y30021D01*
Y27899D01*
G01X883661D02*
Y29453D01*
X885908Y31700D01*
X887132D01*
X888708Y33276D01*
Y34900D01*
X887933Y35675D01*
Y48688D01*
X886707Y49914D01*
G01X910432D02*
X911821Y48525D01*
Y35512D01*
X912433Y34900D01*
Y33500D01*
X910633Y31700D01*
X909633D01*
X908333Y30400D01*
Y29146D01*
X907086Y27899D01*
G01X860036Y30750D02*
X860806Y31520D01*
X861788D01*
X863116Y32848D01*
Y48994D01*
X860010Y52100D01*
G01X896847Y30750D02*
X897617Y31520D01*
X898599D01*
X899927Y32848D01*
Y48994D01*
X896821Y52100D01*
G01X865110Y30540D02*
X868302Y33732D01*
Y49122D01*
X865110Y52314D01*
G01X860010Y33399D02*
X860829Y32580D01*
X861345D01*
X862056Y33291D01*
Y36580D01*
X860136Y38500D01*
Y39500D01*
X860736Y40100D01*
X861236D01*
X862056Y40920D01*
Y41880D01*
X861336Y42600D01*
X860624D01*
X860122Y43102D01*
Y44434D01*
X860738Y45050D01*
X861086D01*
X862056Y46020D01*
Y48553D01*
X861109Y49500D01*
X860010D01*
G01X896821D02*
X897920D01*
X898867Y48553D01*
Y46020D01*
X897897Y45050D01*
X897549D01*
X896933Y44434D01*
Y43102D01*
X897435Y42600D01*
X898147D01*
X898867Y41880D01*
Y40920D01*
X898047Y40100D01*
X897547D01*
X896947Y39500D01*
Y38500D01*
X898867Y36580D01*
Y33291D01*
X898156Y32580D01*
X897640D01*
X896821Y33399D01*
G01X901921Y30540D02*
X905113Y33732D01*
Y49122D01*
X901921Y52314D01*
G01X856189Y33700D02*
X855322Y34567D01*
Y36868D01*
X853689Y38501D01*
Y39800D01*
X855039Y41150D01*
Y42050D01*
X853789Y43300D01*
Y44499D01*
X855322Y46032D01*
Y48000D01*
X852422Y50900D01*
Y53836D01*
X853543Y54957D01*
G01D02*
Y62843D01*
X855410Y64710D01*
Y66267D01*
X854260Y67417D01*
Y72059D01*
X855610Y73409D01*
Y85368D01*
X854260Y86718D01*
Y90960D01*
X855500Y92200D01*
Y93900D01*
X853310Y96090D01*
Y101346D01*
X857000Y105036D01*
Y117101D01*
X865706Y125807D01*
Y126668D01*
X864741Y127633D01*
Y128341D01*
X865879Y129479D01*
X866587D01*
X867551Y128515D01*
X868414D01*
X869398Y129499D01*
Y130361D01*
X867986Y131772D01*
Y132634D01*
X868970Y133618D01*
X869832D01*
X871244Y132207D01*
X872106D01*
X873090Y133191D01*
Y134052D01*
X872142Y135000D01*
Y135792D01*
X873196Y136846D01*
X873988D01*
X874935Y135899D01*
X875798D01*
X877656Y137757D01*
Y141893D01*
X897100Y161337D01*
Y171711D01*
X909350Y183961D01*
Y186812D01*
X910394Y187856D01*
G01X912152Y186099D02*
Y183227D01*
X899600Y170675D01*
Y160301D01*
X880724Y141425D01*
Y137473D01*
X859200Y115949D01*
Y102754D01*
X856250Y99804D01*
Y97604D01*
X858110Y95744D01*
Y64110D01*
X855610Y61610D01*
Y54610D01*
X854116Y53116D01*
Y51987D01*
X856189Y49914D01*
G01X880314Y34100D02*
X878747Y35667D01*
Y36868D01*
X877389Y38226D01*
Y39599D01*
X878589Y40799D01*
Y41925D01*
X877389Y43125D01*
Y44700D01*
X879189Y46500D01*
Y47558D01*
X875847Y50900D01*
Y53836D01*
X876968Y54957D01*
G01D02*
Y56169D01*
X879210Y58411D01*
Y66003D01*
X878410Y66803D01*
Y72611D01*
X878910Y73111D01*
Y85818D01*
X878310Y86418D01*
Y91118D01*
X879260Y92068D01*
Y115436D01*
X887424Y123600D01*
X899900D01*
X902145Y125845D01*
Y126707D01*
X901472Y127380D01*
Y128172D01*
X902526Y129226D01*
X903318D01*
X903991Y128553D01*
X904853D01*
X905837Y129537D01*
Y130399D01*
X904849Y131387D01*
Y132249D01*
X905833Y133233D01*
X906695D01*
X907683Y132245D01*
X908545D01*
X909529Y133229D01*
Y134091D01*
X908541Y135079D01*
Y135941D01*
X909525Y136925D01*
X910387D01*
X911375Y135937D01*
X912237D01*
X919000Y142700D01*
Y168570D01*
X931550Y181120D01*
Y182917D01*
X933025Y184392D01*
G01X880314Y49914D02*
X878410Y51818D01*
Y53418D01*
X881760Y56768D01*
Y66503D01*
X882310Y67053D01*
Y72491D01*
X881710Y73091D01*
Y85918D01*
X882410Y86618D01*
Y91018D01*
X881760Y91668D01*
Y114400D01*
X885139Y117779D01*
X891881D01*
X892491Y118389D01*
Y120690D01*
X893101Y121300D01*
X894491D01*
X895101Y120690D01*
Y118389D01*
X895711Y117779D01*
X897379D01*
X922400Y142800D01*
Y168434D01*
X934727Y180761D01*
Y182551D01*
G01X929519Y187958D02*
X926250Y184689D01*
Y182892D01*
X913300Y169942D01*
Y156548D01*
X891474Y134722D01*
Y133860D01*
X892186Y133148D01*
Y132286D01*
X891202Y131302D01*
X890340D01*
X889628Y132014D01*
X888766D01*
X871700Y114948D01*
Y112949D01*
X872260Y112389D01*
X873300D01*
X874100Y111589D01*
Y109989D01*
X873300Y109189D01*
X871800D01*
X871000Y108389D01*
Y106789D01*
X871800Y105989D01*
X873300D01*
X874100Y105189D01*
Y103589D01*
X873300Y102789D01*
X871800D01*
X871000Y101989D01*
Y100389D01*
X871800Y99589D01*
X873300D01*
X874100Y98789D01*
Y97189D01*
X873111Y96200D01*
X872532D01*
X871732Y95400D01*
Y94268D01*
X872110Y93890D01*
Y91618D01*
X871710Y91218D01*
Y86518D01*
X872100Y86128D01*
Y81104D01*
X872900Y80304D01*
X873400D01*
X874200Y79504D01*
Y77904D01*
X873400Y77104D01*
X872900D01*
X872100Y76304D01*
Y73001D01*
X871710Y72611D01*
Y66903D01*
X872310Y66303D01*
Y62690D01*
X873400Y61600D01*
Y59900D01*
X871450Y57950D01*
X869950D01*
X869182Y57182D01*
Y56050D01*
X870275Y54957D01*
G01D02*
X869347Y54029D01*
Y50901D01*
X872389Y47859D01*
Y46474D01*
X870714Y44799D01*
Y43676D01*
X872214Y42176D01*
Y40824D01*
X870714Y39324D01*
Y38101D01*
X872147Y36668D01*
Y35574D01*
X873621Y34100D01*
G01Y49914D02*
X871810Y51725D01*
Y53580D01*
X873260Y55030D01*
Y56160D01*
X876300Y59200D01*
Y63500D01*
X875100Y64700D01*
Y66443D01*
X875910Y67253D01*
Y72291D01*
X875010Y73191D01*
Y74700D01*
X876500Y76190D01*
Y82500D01*
X875010Y83990D01*
Y85718D01*
X875810Y86518D01*
Y91018D01*
X875110Y91718D01*
Y93610D01*
X876700Y95200D01*
Y116413D01*
X887137Y126850D01*
X892000D01*
X910641Y145491D01*
X911503D01*
X912866Y144128D01*
X913728D01*
X914712Y145112D01*
Y145974D01*
X913349Y147337D01*
Y148199D01*
X915750Y150600D01*
Y168856D01*
X929050Y182156D01*
Y183953D01*
X931242Y186145D01*
G01X890354Y112327D02*
X891063Y111618D01*
Y106124D01*
X892163Y105024D01*
Y92062D01*
X890763Y90662D01*
Y86874D01*
X892274Y85363D01*
Y73357D01*
X891074Y72157D01*
Y67414D01*
X892263Y66225D01*
Y64863D01*
X890354Y62954D01*
Y54957D01*
G01D02*
X889233Y53836D01*
Y50900D01*
X892133Y48000D01*
Y46032D01*
X890600Y44499D01*
Y43300D01*
X891850Y42050D01*
Y41150D01*
X890500Y39800D01*
Y38501D01*
X892133Y36868D01*
Y34567D01*
X893000Y33700D01*
G01Y106934D02*
X894913Y105021D01*
Y64313D01*
X892374Y61774D01*
Y54474D01*
X890974Y53074D01*
Y51940D01*
X893000Y49914D01*
G01X883661Y112327D02*
X884663Y111325D01*
Y106186D01*
X885563Y105286D01*
Y92062D01*
X884674Y91173D01*
Y86463D01*
X885563Y85574D01*
Y72959D01*
X884674Y72070D01*
Y67126D01*
X885563Y66237D01*
Y63359D01*
X883661Y61457D01*
Y54957D01*
G01D02*
X882733Y54029D01*
Y50901D01*
X885533Y48101D01*
Y46232D01*
X884150Y44849D01*
Y43450D01*
X885600Y42000D01*
Y40800D01*
X884100Y39300D01*
Y38101D01*
X885533Y36668D01*
Y34788D01*
X886621Y33700D01*
G01X886707Y49914D02*
X886203D01*
X884674Y51443D01*
Y53244D01*
X888263Y56833D01*
Y67059D01*
X888563Y67359D01*
Y72659D01*
X888263Y72959D01*
Y86074D01*
X888663Y86474D01*
Y91174D01*
X888363Y91474D01*
Y105628D01*
X886707Y107284D01*
G01X907086Y54957D02*
X909063Y56934D01*
Y66271D01*
X908263Y67071D01*
Y72363D01*
X909074Y73174D01*
Y85963D01*
X908263Y86774D01*
Y91074D01*
X909363Y92174D01*
Y104775D01*
X908463Y105675D01*
Y110950D01*
X907086Y112327D01*
G01X910432Y34100D02*
X908958Y35574D01*
Y36668D01*
X907525Y38101D01*
Y39324D01*
X909025Y40824D01*
Y42176D01*
X907525Y43676D01*
Y44799D01*
X909200Y46474D01*
Y47859D01*
X906158Y50901D01*
Y54029D01*
X907086Y54957D01*
G01X910432Y107284D02*
X911863Y105853D01*
Y91712D01*
X912563Y91012D01*
Y86674D01*
X911874Y85985D01*
Y73126D01*
X912463Y72537D01*
Y66947D01*
X911263Y65747D01*
Y56332D01*
X908632Y53701D01*
Y51714D01*
X910432Y49914D01*
G01X860010Y52100D02*
X861700Y53790D01*
Y55600D01*
X860600Y56700D01*
X859936D01*
X859216Y57420D01*
Y59288D01*
X860170Y60242D01*
X860806D01*
X861761Y61197D01*
Y61833D01*
X863090Y63162D01*
Y74275D01*
X863540Y74725D01*
Y76074D01*
X863090Y76524D01*
Y78026D01*
X863540Y78476D01*
Y79825D01*
X863090Y80275D01*
Y93980D01*
X863710Y94600D01*
Y95600D01*
X863090Y96220D01*
Y96980D01*
X863710Y97600D01*
Y98600D01*
X863090Y99220D01*
Y99980D01*
X863710Y100600D01*
Y101600D01*
X863090Y102220D01*
Y103568D01*
X863540Y104018D01*
Y105368D01*
X863090Y105818D01*
Y115558D01*
X884993Y137461D01*
Y140423D01*
X886389Y141819D01*
X889351D01*
X891360Y143828D01*
Y146790D01*
X892756Y148186D01*
X895718D01*
X897727Y150195D01*
Y153157D01*
X899123Y154553D01*
X902085D01*
X903280Y155748D01*
Y158352D01*
X903730Y158802D01*
Y160152D01*
X903280Y160602D01*
Y161951D01*
X903730Y162401D01*
Y163751D01*
X903280Y164201D01*
Y165549D01*
X903730Y165999D01*
Y167349D01*
X903280Y167799D01*
Y169148D01*
X906022Y171890D01*
X906658D01*
X907613Y172845D01*
Y173481D01*
X908566Y174434D01*
X909202D01*
X910157Y175389D01*
Y176025D01*
X911111Y176979D01*
X911747D01*
X912702Y177934D01*
Y178570D01*
X913655Y179523D01*
X914291D01*
X915246Y180478D01*
Y181114D01*
X916200Y182068D01*
Y184944D01*
X918572Y187316D01*
G01X896821Y52100D02*
X898547Y53826D01*
Y56072D01*
X897838Y56781D01*
Y59747D01*
X899838Y61747D01*
Y107497D01*
X896821Y110514D01*
G01X865110Y52314D02*
X866936Y54140D01*
Y55664D01*
X864916Y57684D01*
Y58588D01*
X868190Y61862D01*
Y115258D01*
X907080Y154148D01*
Y167448D01*
X912576Y172944D01*
X913094D01*
X914167Y174017D01*
Y174535D01*
X915121Y175489D01*
X915757D01*
X916712Y176444D01*
Y177080D01*
X917665Y178033D01*
X918301D01*
X919256Y178988D01*
Y179624D01*
X920210Y180578D01*
Y182292D01*
X923127Y185209D01*
G01X901921Y33149D02*
X903030D01*
X904053Y34172D01*
Y36793D01*
X903346Y37500D01*
X902548D01*
X901947Y38101D01*
Y39299D01*
X902548Y39900D01*
X903246D01*
X904053Y40707D01*
Y42080D01*
X903333Y42800D01*
X902833D01*
X902133Y43500D01*
Y44500D01*
X902833Y45200D01*
X903347D01*
X904053Y45906D01*
Y48681D01*
X903019Y49715D01*
X901921D01*
Y49714D01*
G01D02*
X900197Y51438D01*
Y55739D01*
X901978Y57520D01*
Y58192D01*
X903878Y60092D01*
Y106722D01*
X902945Y107655D01*
X901921D01*
G01X860010Y49500D02*
X858156Y51354D01*
Y59731D01*
X862030Y63605D01*
Y115998D01*
X883933Y137901D01*
Y140863D01*
X885638Y142568D01*
Y142571D01*
X885946Y142879D01*
X888908D01*
X890300Y144271D01*
Y147233D01*
X892313Y149246D01*
X895275D01*
X896667Y150638D01*
Y153600D01*
X898680Y155613D01*
X901642D01*
X902220Y156191D01*
Y169591D01*
X915137Y182508D01*
X915140D01*
Y185384D01*
X917821Y188065D01*
G01X896847Y107865D02*
X898778Y105934D01*
Y62190D01*
X896778Y60190D01*
Y57320D01*
X894847Y55389D01*
Y51474D01*
X896821Y49500D01*
G01X922377Y185959D02*
X919150Y182732D01*
Y181018D01*
X906022Y167890D01*
X906020Y167891D01*
Y154591D01*
X867130Y115701D01*
Y62305D01*
X863856Y59031D01*
Y58199D01*
X863386Y57729D01*
Y51438D01*
X865110Y49714D01*
G01D02*
Y49715D01*
X866208D01*
X867242Y48681D01*
Y45906D01*
X866536Y45200D01*
X866022D01*
X865322Y44500D01*
Y43500D01*
X866022Y42800D01*
X866522D01*
X867242Y42080D01*
Y40707D01*
X866435Y39900D01*
X865737D01*
X865136Y39299D01*
Y38101D01*
X865737Y37500D01*
X866535D01*
X867242Y36793D01*
Y34172D01*
X866219Y33149D01*
X865110D01*
G01X901921Y52314D02*
X903747Y54140D01*
Y55911D01*
X903038Y56620D01*
Y57749D01*
X904938Y59649D01*
Y108263D01*
X902937Y110264D01*
X901947D01*
G01X916533Y403235D02*
X908624Y411144D01*
Y417577D01*
X898300Y427901D01*
Y446605D01*
X860100Y484805D01*
Y503500D01*
X855592Y508008D01*
Y510725D01*
X854100Y512217D01*
Y516299D01*
X855376Y517575D01*
Y519534D01*
X854899Y520011D01*
Y527499D01*
X855410Y528010D01*
Y529467D01*
X854260Y530617D01*
Y535354D01*
X855455Y536549D01*
Y537805D01*
X854713Y538547D01*
Y545513D01*
X855243Y546043D01*
Y548874D01*
X852750Y551367D01*
Y555164D01*
X853543Y555957D01*
G01X918356Y404948D02*
X913291Y410013D01*
Y411250D01*
X912681Y411860D01*
X911382D01*
X910772Y412470D01*
Y413860D01*
X911382Y414470D01*
X912787D01*
X913397Y415080D01*
Y416404D01*
X900800Y429001D01*
Y447641D01*
X862600Y485841D01*
Y488601D01*
X864100Y490101D01*
Y490801D01*
X862600Y492301D01*
Y493601D01*
X864100Y495101D01*
Y496241D01*
X862600Y497741D01*
Y499441D01*
X864100Y500941D01*
Y502800D01*
X858110Y508790D01*
Y518910D01*
X859600Y520400D01*
Y521465D01*
X858990Y522075D01*
X857510D01*
X856900Y522685D01*
Y524665D01*
X857510Y525275D01*
X858990D01*
X859600Y525885D01*
Y527100D01*
X858110Y528590D01*
Y537810D01*
X858900Y538600D01*
Y540327D01*
X858290Y540937D01*
X857210D01*
X856600Y541547D01*
Y543527D01*
X857210Y544137D01*
X858290D01*
X858900Y544747D01*
Y546100D01*
X858110Y546890D01*
Y548993D01*
X856189Y550914D01*
G01X913826Y400312D02*
X903903Y410235D01*
Y411410D01*
X904513Y412020D01*
X906104D01*
X906714Y412630D01*
Y414020D01*
X906104Y414630D01*
X904513D01*
X903903Y415240D01*
Y416996D01*
X902683Y418216D01*
Y419078D01*
X903121Y419516D01*
Y420378D01*
X901720Y421779D01*
X900858D01*
X900421Y421343D01*
X899559D01*
X898158Y422744D01*
Y423605D01*
X898595Y424042D01*
Y424904D01*
X895800Y427699D01*
Y445569D01*
X857600Y483769D01*
Y502400D01*
X851300Y508700D01*
Y510799D01*
X852300Y511799D01*
Y516099D01*
X851205Y517194D01*
Y518895D01*
X851900Y519590D01*
Y527600D01*
X851510Y527990D01*
Y530197D01*
X852010Y530697D01*
Y534856D01*
X851410Y535456D01*
Y537500D01*
X851900Y537990D01*
Y546300D01*
X850600Y547600D01*
Y550210D01*
X849896Y550914D01*
G01X930606Y408201D02*
X929800Y409007D01*
Y414476D01*
X910900Y433376D01*
Y451520D01*
X898654Y463766D01*
Y470623D01*
X888388Y480889D01*
X882688D01*
X874200Y489377D01*
Y506901D01*
X872510Y508591D01*
Y511257D01*
X871710Y512057D01*
Y516957D01*
X872310Y517557D01*
Y519600D01*
X871900Y520010D01*
Y527800D01*
X872310Y528210D01*
Y529597D01*
X871237Y530670D01*
Y535169D01*
X872510Y536442D01*
Y537600D01*
X871900Y538210D01*
Y546800D01*
X872510Y547410D01*
Y548557D01*
X869610Y551457D01*
Y555292D01*
X870275Y555957D01*
G01X932561Y409796D02*
Y415304D01*
X913400Y434465D01*
Y452043D01*
X900701Y464742D01*
Y465604D01*
X901685Y466588D01*
X902547D01*
X906883Y462252D01*
X907745D01*
X908729Y463236D01*
Y464098D01*
X889438Y483389D01*
X883988D01*
X876700Y490677D01*
Y507500D01*
X875010Y509190D01*
Y511257D01*
X875910Y512157D01*
Y516489D01*
X874810Y517589D01*
Y519500D01*
X875300Y519990D01*
Y527900D01*
X875110Y528090D01*
Y529797D01*
X875676Y530363D01*
Y535425D01*
X875010Y536091D01*
Y537710D01*
X875300Y538000D01*
Y546600D01*
X875010Y546890D01*
Y549568D01*
X874967D01*
X873621Y550914D01*
G01X919271Y409283D02*
X917460Y411094D01*
Y417572D01*
X904480Y430552D01*
Y449329D01*
X867780Y486029D01*
Y504049D01*
X863090Y508739D01*
Y550020D01*
X860010Y553100D01*
G01X865110Y550714D02*
X866211D01*
X867130Y549795D01*
Y546880D01*
X866510Y546260D01*
Y545260D01*
X867130Y544640D01*
Y543640D01*
X866510Y543020D01*
Y542020D01*
X867130Y541400D01*
Y540400D01*
X866510Y539780D01*
Y538780D01*
X867130Y538160D01*
Y536326D01*
X866715Y535911D01*
Y534911D01*
X867130Y534496D01*
Y531209D01*
X866694Y530773D01*
Y529773D01*
X867130Y529337D01*
Y527707D01*
X866510Y527087D01*
Y526087D01*
X867130Y525467D01*
Y524467D01*
X866510Y523847D01*
Y522847D01*
X867130Y522227D01*
Y521227D01*
X866510Y520607D01*
Y519607D01*
X867130Y518987D01*
Y517724D01*
X866736Y517330D01*
Y516330D01*
X867130Y515936D01*
Y512499D01*
X866657Y512026D01*
Y511026D01*
X867130Y510553D01*
Y509237D01*
X867882Y508485D01*
Y507607D01*
X868589Y506900D01*
X869467D01*
X870626Y505741D01*
Y504476D01*
X870006Y503856D01*
Y502856D01*
X870626Y502236D01*
Y501236D01*
X870006Y500616D01*
Y499616D01*
X870626Y498996D01*
Y497996D01*
X870006Y497376D01*
Y496376D01*
X870626Y495756D01*
Y494756D01*
X870006Y494136D01*
Y493136D01*
X870626Y492516D01*
Y487219D01*
X881545Y476300D01*
X884606D01*
X885443Y477137D01*
X886667D01*
X888443Y475361D01*
Y474136D01*
X887133Y472826D01*
Y470712D01*
X889520Y468325D01*
X891628D01*
X892390Y469087D01*
X893636D01*
X895154Y467569D01*
Y462691D01*
X907220Y450625D01*
Y431849D01*
X907223D01*
X921557Y417515D01*
Y410857D01*
X923101Y409313D01*
G01X860010Y550500D02*
X861110D01*
X862030Y549580D01*
Y546827D01*
X861476Y546273D01*
Y545273D01*
X862030Y544719D01*
Y543546D01*
X861504Y543020D01*
Y542020D01*
X862030Y541494D01*
Y508299D01*
X866720Y503609D01*
Y485589D01*
X903420Y448889D01*
Y430109D01*
X916400Y417129D01*
Y410654D01*
X918521Y408533D01*
G01X865110Y553314D02*
X865111D01*
X868190Y550235D01*
Y509677D01*
X871686Y506181D01*
Y487659D01*
X877692Y481653D01*
X878258D01*
X879553Y480358D01*
Y479792D01*
X881985Y477360D01*
X884166D01*
X885003Y478197D01*
X887110D01*
X889503Y475804D01*
Y473693D01*
X888193Y472383D01*
Y471155D01*
X889963Y469385D01*
X891188D01*
X891950Y470147D01*
X894076D01*
X896214Y468009D01*
Y463131D01*
X908280Y451065D01*
Y432292D01*
X922617Y417955D01*
Y411297D01*
X923851Y410063D01*
G01X943315Y405382D02*
X940800Y407897D01*
Y410601D01*
X915900Y435501D01*
Y452461D01*
X910852Y457509D01*
Y464825D01*
X889788Y485889D01*
X885288D01*
X879200Y491977D01*
Y510867D01*
X878410Y511657D01*
Y517009D01*
X879210Y517809D01*
Y519400D01*
X878644Y519966D01*
Y527844D01*
X879073Y528273D01*
Y529406D01*
X878110Y530369D01*
Y535342D01*
X879010Y536242D01*
Y537600D01*
X878700Y537910D01*
Y546800D01*
X879010Y547110D01*
Y548707D01*
X875610Y552107D01*
Y554599D01*
X876968Y555957D01*
G01X944781Y407266D02*
Y410156D01*
X918400Y436537D01*
Y462679D01*
X917790Y463289D01*
X916400D01*
X915790Y462679D01*
Y457933D01*
X915180Y457323D01*
X913790D01*
X913180Y457933D01*
Y465787D01*
X896085Y482882D01*
Y483744D01*
X897742Y485401D01*
Y486263D01*
X896758Y487247D01*
X895896D01*
X894239Y485590D01*
X893377D01*
X890467Y488500D01*
X885500D01*
X881100Y492900D01*
Y511047D01*
X882310Y512257D01*
Y516807D01*
X881760Y517357D01*
Y519300D01*
X882000Y519540D01*
Y527600D01*
X881760Y527840D01*
Y529847D01*
X882610Y530697D01*
Y535390D01*
X881610Y536390D01*
Y537510D01*
X882000Y537900D01*
Y546400D01*
X881610Y546790D01*
Y549670D01*
X880314Y550966D01*
Y550914D01*
G01X889200Y495900D02*
X890900Y497600D01*
Y506977D01*
X892421Y508498D01*
Y510707D01*
X891071Y512057D01*
Y516307D01*
X892221Y517457D01*
Y519100D01*
X892000Y519321D01*
Y527900D01*
X892221Y528121D01*
Y529467D01*
X891121Y530567D01*
Y535321D01*
X892271Y536471D01*
Y537800D01*
X892000Y538071D01*
Y546800D01*
X892271Y547071D01*
Y548657D01*
X888921Y552007D01*
Y554524D01*
X890354Y555957D01*
G01X893000Y495694D02*
Y504078D01*
X894921Y505999D01*
Y519120D01*
X895400Y519599D01*
Y529300D01*
X894921Y529779D01*
Y537700D01*
X895400Y538179D01*
Y546500D01*
X894921Y546979D01*
Y548643D01*
X893000Y550564D01*
Y550914D01*
G01X882900Y498500D02*
Y501600D01*
X885721Y504421D01*
Y510757D01*
X884721Y511757D01*
Y516457D01*
X885477Y517213D01*
Y529523D01*
X884695Y530305D01*
Y535266D01*
X885501Y536072D01*
Y548727D01*
X883157Y551071D01*
Y555453D01*
X883661Y555957D01*
G01X886500Y490800D02*
X888221Y492521D01*
Y494080D01*
X886600Y495701D01*
Y502179D01*
X888221Y503800D01*
Y510657D01*
X888571Y511007D01*
Y517207D01*
X888321Y517457D01*
Y519200D01*
X888700Y519579D01*
Y527700D01*
X888321Y528079D01*
Y530197D01*
X888821Y530697D01*
Y534856D01*
X888221Y535456D01*
Y537400D01*
X888700Y537879D01*
Y546400D01*
X888221Y546879D01*
Y549400D01*
X886707Y550914D01*
G01X907086Y498487D02*
Y500787D01*
X909321Y503022D01*
Y511257D01*
X908521Y512057D01*
Y516957D01*
X909121Y517557D01*
Y519200D01*
X908800Y519521D01*
Y527500D01*
X909121Y527821D01*
Y529597D01*
X908048Y530670D01*
Y535169D01*
X909321Y536442D01*
Y537600D01*
X908800Y538121D01*
Y546200D01*
X909321Y546721D01*
Y548557D01*
X906421Y551457D01*
Y555292D01*
X907086Y555957D01*
G01X910432Y493744D02*
X909645Y492957D01*
X908243D01*
X907846Y493354D01*
Y494146D01*
X908800Y495100D01*
Y499399D01*
X911821Y502420D01*
Y511257D01*
X912721Y512157D01*
Y516557D01*
X911621Y517657D01*
Y519300D01*
X912700Y520379D01*
Y522400D01*
X911800Y523300D01*
Y524900D01*
X912700Y525800D01*
Y527400D01*
X911921Y528179D01*
Y529797D01*
X912487Y530363D01*
Y535513D01*
X911821Y536179D01*
Y537700D01*
X912900Y538779D01*
Y540800D01*
X911600Y542100D01*
Y543400D01*
X912900Y544700D01*
Y546100D01*
X911821Y547179D01*
Y549568D01*
X911778D01*
X910432Y550914D01*
G01X896836Y495909D02*
X897108D01*
X898465Y497266D01*
Y499436D01*
X897600Y500301D01*
Y502122D01*
X899901Y507677D01*
Y549899D01*
X896821Y552979D01*
Y553100D01*
G01X901921Y493214D02*
X900194Y494941D01*
Y499194D01*
X903941Y502941D01*
Y521060D01*
X902440Y522561D01*
Y525640D01*
X903941Y527141D01*
Y548695D01*
X901922Y550714D01*
X901921D01*
G01X896836Y493209D02*
X895094Y494951D01*
Y498841D01*
X898841Y507888D01*
Y549459D01*
X897800Y550500D01*
X896821D01*
G01X901921Y495814D02*
X902414D01*
X903700Y497100D01*
Y501200D01*
X905001Y502501D01*
Y521500D01*
X903500Y523001D01*
Y525200D01*
X905001Y526701D01*
Y550235D01*
X901922Y553314D01*
X901921D01*
G01X853543Y555957D02*
X851838Y557662D01*
Y569315D01*
X855023Y572500D01*
X856189D01*
G01Y550914D02*
X856101D01*
X854415Y552600D01*
Y554292D01*
X855322Y555199D01*
Y556792D01*
X854178Y557936D01*
Y559356D01*
X855022Y560200D01*
Y561900D01*
X854178Y562744D01*
Y563956D01*
X855122Y564900D01*
Y566100D01*
X854523Y566699D01*
X853543D01*
G01X876968Y555957D02*
X875263Y557662D01*
Y567849D01*
X880314Y572900D01*
G01Y550914D02*
X880226D01*
X878540Y552600D01*
Y554292D01*
X878715Y554467D01*
Y557100D01*
X877603Y558212D01*
Y559288D01*
X878615Y560300D01*
Y561500D01*
X877603Y562512D01*
Y563588D01*
X878740Y564725D01*
Y565999D01*
X878040Y566699D01*
X876968D01*
G01X873621Y572900D02*
X868570Y567849D01*
Y557662D01*
X870275Y555957D01*
G01D02*
Y555961D01*
G01X873621Y550914D02*
X873533D01*
X871847Y552600D01*
Y554292D01*
X872022Y554467D01*
Y557100D01*
X870910Y558212D01*
Y559288D01*
X871922Y560300D01*
Y561500D01*
X870910Y562512D01*
Y563588D01*
X872047Y564725D01*
Y565999D01*
X871347Y566699D01*
X870275D01*
G01X890354Y555957D02*
X888649Y557662D01*
Y569315D01*
X891834Y572500D01*
X893000D01*
G01Y550914D02*
X892912D01*
X891226Y552600D01*
Y554292D01*
X892133Y555199D01*
Y556792D01*
X890989Y557936D01*
Y559356D01*
X891833Y560200D01*
Y561900D01*
X890989Y562744D01*
Y563956D01*
X891933Y564900D01*
Y566100D01*
X891334Y566699D01*
X890354D01*
G01X883661Y555957D02*
X881956Y557662D01*
Y567635D01*
X882578Y568257D01*
Y569445D01*
X885633Y572500D01*
X886621D01*
G01X886707Y550914D02*
X886619D01*
X884933Y552600D01*
Y554800D01*
X885433Y555300D01*
Y557199D01*
X884296Y558336D01*
Y559664D01*
X885233Y560601D01*
Y561999D01*
X884296Y562936D01*
Y564164D01*
X885333Y565201D01*
Y566099D01*
X884733Y566699D01*
X883661D01*
G01X907086Y555957D02*
X905381Y557662D01*
Y567849D01*
X910432Y572900D01*
G01Y550914D02*
X910344D01*
X908658Y552600D01*
Y554292D01*
X908833Y554467D01*
Y557100D01*
X907721Y558212D01*
Y559288D01*
X908733Y560300D01*
Y561500D01*
X907721Y562512D01*
Y563588D01*
X908858Y564725D01*
Y565999D01*
X908158Y566699D01*
X907086D01*
G01X860010Y553100D02*
X861722Y554812D01*
Y556400D01*
X860622Y557500D01*
X859672D01*
X859082Y558090D01*
Y559460D01*
X859602Y559980D01*
X860212D01*
X860822Y560590D01*
Y561980D01*
X860212Y562590D01*
X859632D01*
X859082Y563140D01*
Y564560D01*
X859722Y565200D01*
X861002D01*
X861741Y565939D01*
Y567845D01*
X860036Y569550D01*
G01X896821Y553100D02*
X898533Y554812D01*
Y556400D01*
X897433Y557500D01*
X896483D01*
X895893Y558090D01*
Y559460D01*
X896413Y559980D01*
X897023D01*
X897633Y560590D01*
Y561980D01*
X897023Y562590D01*
X896443D01*
X895893Y563140D01*
Y564560D01*
X896533Y565200D01*
X897813D01*
X898552Y565939D01*
Y567845D01*
X896847Y569550D01*
G01X865110Y571949D02*
X863405Y570244D01*
Y565300D01*
X862575Y564470D01*
Y557930D01*
X863405Y557100D01*
Y552131D01*
X864822Y550714D01*
X865110D01*
G01X901921D02*
X901633D01*
X900216Y552131D01*
Y557100D01*
X899386Y557930D01*
Y564470D01*
X900216Y565300D01*
Y570244D01*
X901921Y571949D01*
G01X860010Y572199D02*
X858022Y570211D01*
Y552200D01*
X859722Y550500D01*
X860010D01*
G01X896821D02*
X896533D01*
X894833Y552200D01*
Y570211D01*
X896821Y572199D01*
G01X865110Y569340D02*
X866922Y567528D01*
Y565800D01*
X865922Y564800D01*
X864406D01*
X863635Y564029D01*
Y563138D01*
X864175Y562598D01*
X864412D01*
X865122Y561888D01*
Y560800D01*
X864422Y560100D01*
X864087D01*
X863635Y559648D01*
Y558371D01*
X864306Y557700D01*
X865822D01*
X866822Y556700D01*
Y555026D01*
X865110Y553314D01*
G01X901921D02*
X903633Y555026D01*
Y556700D01*
X902633Y557700D01*
X901117D01*
X900446Y558371D01*
Y559648D01*
X900898Y560100D01*
X901233D01*
X901933Y560800D01*
Y561888D01*
X901223Y562598D01*
X900986D01*
X900446Y563138D01*
Y564029D01*
X901217Y564800D01*
X902733D01*
X903733Y565800D01*
Y567528D01*
X901921Y569340D01*
G01X970669Y54857D02*
X970569D01*
X968950Y53238D01*
Y43953D01*
X969560Y43343D01*
X970483D01*
X971093Y42733D01*
Y40833D01*
X970483Y40223D01*
X969560D01*
X968950Y39613D01*
Y32165D01*
X969432Y31000D01*
X970669Y28014D01*
G01X963976D02*
Y32554D01*
X965700Y34278D01*
Y49740D01*
X965600Y49840D01*
Y55660D01*
X968000Y58060D01*
Y63901D01*
X969056Y64957D01*
Y67277D01*
X968474Y67859D01*
Y69159D01*
X968950Y69635D01*
Y83450D01*
X969274Y83774D01*
Y85574D01*
X968674Y86174D01*
Y88374D01*
X969274Y88974D01*
Y90974D01*
X968674Y91574D01*
Y94417D01*
X971938Y97681D01*
Y106338D01*
X994645Y129045D01*
Y198346D01*
G01X917125Y49914D02*
X918514Y48525D01*
Y35512D01*
X919126Y34900D01*
Y33500D01*
X917326Y31700D01*
X916326D01*
X915026Y30400D01*
Y29146D01*
X913779Y27899D01*
G01X964581Y194250D02*
Y193050D01*
X965081Y192550D01*
Y191650D01*
X964581Y191150D01*
Y188881D01*
X963945Y188245D01*
Y187537D01*
X963309Y186901D01*
X962601D01*
X961897Y186197D01*
Y185489D01*
X961261Y184853D01*
X960553D01*
X959917Y184217D01*
Y183509D01*
X959281Y182873D01*
X958573D01*
X957937Y182237D01*
Y181529D01*
X957301Y180893D01*
X956593D01*
X955922Y180222D01*
Y179514D01*
X955286Y178878D01*
X954578D01*
X953942Y178242D01*
Y177534D01*
X953306Y176898D01*
X952598D01*
X951962Y176262D01*
Y175554D01*
X951326Y174918D01*
X950618D01*
X949982Y174282D01*
Y173574D01*
X949346Y172938D01*
X948638D01*
X947660Y171960D01*
Y137042D01*
X946568Y135950D01*
X942732D01*
X942260Y135478D01*
Y133732D01*
X942732Y133260D01*
X946568D01*
X947660Y132168D01*
Y128240D01*
X936712Y117292D01*
Y60920D01*
X937332Y60300D01*
Y59300D01*
X936712Y58680D01*
Y57920D01*
X937332Y57300D01*
Y56300D01*
X936712Y55680D01*
Y25442D01*
X932838Y21568D01*
Y19620D01*
X933558Y18900D01*
X934558D01*
X935358Y18100D01*
Y16026D01*
X933632Y14300D01*
G01X970049Y196613D02*
Y185399D01*
X968700Y184050D01*
X965998D01*
X952000Y170052D01*
Y126590D01*
X941812Y116402D01*
Y24062D01*
X941096Y23346D01*
Y22470D01*
X940388Y21762D01*
X939512D01*
X938538Y20788D01*
Y19920D01*
X940558Y17900D01*
Y16340D01*
X938732Y14514D01*
G01X963521Y194250D02*
Y189321D01*
X946600Y172400D01*
Y137482D01*
X946128Y137010D01*
X942292D01*
X941200Y135918D01*
Y133292D01*
X942292Y132200D01*
X946128D01*
X946600Y131728D01*
Y128680D01*
X935652Y117732D01*
Y25885D01*
X931778Y22011D01*
Y13554D01*
X933632Y11700D01*
G01X938732Y11914D02*
X937008Y13638D01*
Y18009D01*
X937478Y18479D01*
Y21231D01*
X940752Y24505D01*
Y116842D01*
X950940Y127030D01*
Y170492D01*
X965558Y185110D01*
X968260D01*
X968989Y185839D01*
Y196613D01*
G01X958056Y197341D02*
Y191006D01*
X941850Y174800D01*
Y160695D01*
X940800Y159645D01*
Y157915D01*
X941850Y156865D01*
Y155475D01*
X941240Y154865D01*
X939460D01*
X938850Y154255D01*
Y152865D01*
X939460Y152255D01*
X941240D01*
X941850Y151645D01*
Y150255D01*
X941240Y149645D01*
X939460D01*
X938850Y149035D01*
Y147645D01*
X939460Y147035D01*
X941240D01*
X941850Y146425D01*
Y144499D01*
X936100Y138749D01*
Y126701D01*
X929200Y119801D01*
Y111642D01*
X927874Y110316D01*
Y106174D01*
X929232Y104816D01*
Y92332D01*
X927882Y90982D01*
Y86714D01*
X929232Y85364D01*
Y73433D01*
X927882Y72083D01*
Y67417D01*
X929232Y66067D01*
Y54532D01*
X927882Y53182D01*
Y48914D01*
X929232Y47564D01*
Y35533D01*
X927882Y34183D01*
Y29617D01*
X929032Y28467D01*
Y26633D01*
X926732Y24333D01*
Y17590D01*
X927165Y17157D01*
G01X960556Y197341D02*
Y189193D01*
X944350Y172987D01*
Y142499D01*
X938500Y136649D01*
Y125600D01*
X931732Y118832D01*
Y26033D01*
X929232Y23533D01*
Y16732D01*
X927738Y15238D01*
Y14187D01*
X929811Y12114D01*
G01X950590Y17157D02*
X952832Y19399D01*
Y28199D01*
X952032Y28999D01*
Y34831D01*
X952532Y35331D01*
Y48014D01*
X951932Y48614D01*
Y53314D01*
X952882Y54264D01*
Y65949D01*
X952032Y66799D01*
Y72631D01*
X952532Y73131D01*
Y85814D01*
X951932Y86414D01*
Y91164D01*
X952932Y92164D01*
Y103168D01*
X951974Y104126D01*
Y108474D01*
X952500Y109000D01*
Y116100D01*
X962245Y125845D01*
Y129030D01*
X962805Y129590D01*
X963540D01*
X964100Y130150D01*
Y131590D01*
X963540Y132150D01*
X962805D01*
X962245Y132710D01*
Y134150D01*
X962805Y134710D01*
X963540D01*
X964100Y135270D01*
Y136710D01*
X963540Y137270D01*
X962805D01*
X962245Y137830D01*
Y139270D01*
X962805Y139830D01*
X963540D01*
X964100Y140390D01*
Y141830D01*
X963540Y142390D01*
X962805D01*
X962245Y142950D01*
Y144390D01*
X962805Y144950D01*
X963540D01*
X964100Y145510D01*
Y146950D01*
X963540Y147510D01*
X962805D01*
X962245Y148070D01*
Y149510D01*
X962805Y150070D01*
X963540D01*
X964100Y150630D01*
Y152070D01*
X963540Y152630D01*
X962805D01*
X962245Y153190D01*
Y169072D01*
X970611Y177438D01*
X971338D01*
X977756Y183856D01*
Y197291D01*
G01X953936Y12114D02*
X952032Y14018D01*
Y15532D01*
X955382Y18882D01*
Y28699D01*
X955932Y29249D01*
Y34769D01*
X955332Y35369D01*
Y48064D01*
X955843Y48575D01*
Y53453D01*
X955382Y53914D01*
Y66499D01*
X955882Y66999D01*
Y72517D01*
X955332Y73067D01*
Y85914D01*
X955832Y86414D01*
Y91474D01*
X955000Y92306D01*
Y102900D01*
X955974Y103874D01*
Y112624D01*
X966200Y122850D01*
Y169414D01*
X971847Y175061D01*
X972561D01*
X980250Y182750D01*
Y197285D01*
X980256Y197291D01*
G01X953056Y197341D02*
X953150Y197247D01*
Y193100D01*
X931800Y171750D01*
Y162971D01*
X932360Y162411D01*
X933740D01*
X934300Y161851D01*
Y160411D01*
X933740Y159851D01*
X932360D01*
X931800Y159291D01*
Y157851D01*
X932360Y157291D01*
X933740D01*
X934300Y156731D01*
Y155291D01*
X933740Y154731D01*
X932360D01*
X931800Y154171D01*
Y143799D01*
X931150Y143149D01*
Y129999D01*
X923000Y121849D01*
Y114700D01*
X922432Y114132D01*
Y111674D01*
X921474Y110716D01*
Y106274D01*
X922432Y105316D01*
Y102744D01*
X921600Y101912D01*
Y99544D01*
X922432Y98712D01*
Y92114D01*
X921532Y91214D01*
Y86414D01*
X922532Y85414D01*
Y82409D01*
X921700Y81577D01*
Y79209D01*
X922532Y78377D01*
Y73099D01*
X921532Y72099D01*
Y67167D01*
X922432Y66267D01*
Y63885D01*
X921600Y63053D01*
Y60685D01*
X922432Y59853D01*
Y54314D01*
X921532Y53414D01*
Y48614D01*
X922532Y47614D01*
Y45014D01*
X921600Y44082D01*
Y41814D01*
X922532Y40882D01*
Y35299D01*
X921532Y34299D01*
Y29267D01*
X922300Y28499D01*
Y27100D01*
X920472Y25272D01*
Y17157D01*
G01X955556Y197341D02*
Y191856D01*
X936700Y173000D01*
Y169654D01*
X936140Y169094D01*
X934460D01*
X933900Y168534D01*
Y167094D01*
X934460Y166534D01*
X936140D01*
X936700Y165974D01*
Y144200D01*
X933900Y141400D01*
Y128301D01*
X925500Y119901D01*
Y113668D01*
X925032Y113200D01*
Y111074D01*
X925374Y110732D01*
Y105674D01*
X925032Y105332D01*
Y91764D01*
X925382Y91414D01*
Y86464D01*
X925032Y86114D01*
Y73199D01*
X925382Y72849D01*
Y66649D01*
X925132Y66399D01*
Y53864D01*
X925382Y53614D01*
Y48664D01*
X925032Y48314D01*
Y35399D01*
X925382Y35049D01*
Y28849D01*
X925132Y28599D01*
Y26232D01*
X923800Y24900D01*
Y17800D01*
X921600Y15600D01*
Y14032D01*
X923518Y12114D01*
G01X972756Y196691D02*
X972700Y196635D01*
Y184900D01*
X969399Y181599D01*
X967390D01*
X954950Y169159D01*
Y150316D01*
X955560Y149706D01*
X956881D01*
X957491Y149096D01*
Y147876D01*
X956881Y147266D01*
X955560D01*
X954950Y146656D01*
Y145436D01*
X955560Y144826D01*
X956881D01*
X957491Y144216D01*
Y142996D01*
X956881Y142386D01*
X955560D01*
X954950Y141776D01*
Y140556D01*
X955560Y139946D01*
X956881D01*
X957491Y139336D01*
Y138116D01*
X956881Y137506D01*
X955560D01*
X954950Y136896D01*
Y126066D01*
X946300Y117416D01*
Y109500D01*
X945166Y108366D01*
Y104234D01*
X945874Y103526D01*
Y101421D01*
X945000Y100547D01*
Y98221D01*
X945874Y97347D01*
Y91756D01*
X945332Y91214D01*
Y86514D01*
X946132Y85714D01*
Y73331D01*
X945332Y72531D01*
Y66899D01*
X945732Y66499D01*
Y53814D01*
X945332Y53414D01*
Y48714D01*
X946132Y47914D01*
Y35531D01*
X945332Y34731D01*
Y29099D01*
X945932Y28499D01*
Y19932D01*
X943897Y17897D01*
Y17157D01*
G01X947243Y12114D02*
X945332Y14025D01*
Y15672D01*
X948732Y19072D01*
Y25099D01*
X948432Y25399D01*
Y28399D01*
X949532Y29499D01*
Y34367D01*
X948632Y35267D01*
Y47914D01*
X949432Y48714D01*
Y53214D01*
X948732Y53914D01*
Y66499D01*
X949532Y67299D01*
Y72267D01*
X948632Y73167D01*
Y85714D01*
X949432Y86514D01*
Y91014D01*
X948674Y91772D01*
Y103774D01*
X949474Y104574D01*
Y108026D01*
X948732Y108768D01*
Y116432D01*
X957300Y125000D01*
Y133200D01*
X960050Y135950D01*
Y170723D01*
X968731Y179404D01*
X970204D01*
X975475Y184675D01*
Y196432D01*
X975256Y196651D01*
G01X996184Y198054D02*
Y122642D01*
X979100Y105558D01*
Y101988D01*
X973060Y95948D01*
Y92274D01*
X972060Y91274D01*
Y89224D01*
X973060Y88224D01*
Y86474D01*
X972060Y85474D01*
Y75239D01*
X972407Y74892D01*
Y72706D01*
X973060Y72053D01*
Y67559D01*
X972400Y66899D01*
Y60530D01*
X970669Y58799D01*
Y54857D01*
G01X989709Y197885D02*
Y133716D01*
X965629Y109636D01*
Y99859D01*
X959674Y93904D01*
Y92274D01*
X958674Y91274D01*
Y89224D01*
X959674Y88224D01*
Y86474D01*
X958674Y85474D01*
Y75127D01*
X959020Y74781D01*
Y72705D01*
X959674Y72051D01*
Y67559D01*
X958924Y66809D01*
Y52286D01*
X959600Y51610D01*
Y49600D01*
X959000Y49000D01*
Y37586D01*
X960629Y35957D01*
G01X993094Y198703D02*
Y130691D01*
X969705Y107302D01*
Y98277D01*
X965974Y94546D01*
Y91674D01*
X965274Y90974D01*
Y88874D01*
X965974Y88174D01*
Y86274D01*
X965374Y85674D01*
Y75359D01*
X965699Y75034D01*
Y72684D01*
X965374Y72359D01*
Y70059D01*
X965974Y69459D01*
Y67459D01*
X965609Y67094D01*
Y64892D01*
X965974Y64527D01*
Y58383D01*
X963976Y56385D01*
Y54857D01*
G01X991268Y197909D02*
Y132228D01*
X967618Y108578D01*
Y99019D01*
X962043Y93444D01*
Y91805D01*
X962774Y91074D01*
Y88974D01*
X962074Y88274D01*
Y86374D01*
X962574Y85874D01*
Y75074D01*
X962253Y74753D01*
Y72780D01*
X962574Y72459D01*
Y69959D01*
X961974Y69359D01*
Y67359D01*
X962356Y66977D01*
Y61936D01*
X961440Y61020D01*
Y56531D01*
X962356Y55615D01*
Y48641D01*
X960629Y46914D01*
G01X913779Y112327D02*
Y107270D01*
X915763Y105286D01*
Y91874D01*
X915174Y91285D01*
Y86463D01*
X915863Y85774D01*
Y73263D01*
X915063Y72463D01*
Y67071D01*
X915674Y66460D01*
Y61274D01*
X913779Y59379D01*
Y54957D01*
G01D02*
X912658Y53836D01*
Y50900D01*
X916000Y47558D01*
Y46500D01*
X914200Y44700D01*
Y43125D01*
X915400Y41925D01*
Y40799D01*
X914200Y39599D01*
Y38226D01*
X915558Y36868D01*
Y35667D01*
X917125Y34100D01*
G01Y107284D02*
X918363Y106046D01*
Y91986D01*
X919063Y91286D01*
Y86562D01*
X918363Y85862D01*
Y73237D01*
X919074Y72526D01*
Y66970D01*
X918463Y66359D01*
Y54144D01*
X919263Y53344D01*
Y52052D01*
X917125Y49914D01*
G01X965843Y405512D02*
Y413801D01*
X940980Y438664D01*
Y450052D01*
X937734Y453298D01*
Y453863D01*
X936439Y455158D01*
X935874D01*
X934580Y456452D01*
Y461378D01*
X934980Y461778D01*
Y463608D01*
X934580Y464008D01*
Y485009D01*
X936712Y487141D01*
Y587820D01*
X933632Y590900D01*
G01X968786Y409187D02*
Y414822D01*
X944049Y439558D01*
Y454575D01*
X943128Y455496D01*
X940512D01*
X939020Y456988D01*
Y459564D01*
X940512Y461056D01*
X942677D01*
X943177Y461556D01*
Y464220D01*
X942677Y464720D01*
X939112D01*
X937420Y466412D01*
Y483852D01*
X940752Y487184D01*
Y519146D01*
X940132Y519766D01*
Y520766D01*
X940752Y521386D01*
Y522386D01*
X940132Y523006D01*
Y524006D01*
X940752Y524626D01*
Y525626D01*
X940132Y526246D01*
Y527246D01*
X940752Y527866D01*
Y538293D01*
X940132Y538913D01*
Y539913D01*
X940752Y540533D01*
Y541533D01*
X940132Y542153D01*
Y543153D01*
X940752Y543773D01*
Y544773D01*
X940132Y545393D01*
Y546393D01*
X940752Y547013D01*
Y556987D01*
X940132Y557607D01*
Y558607D01*
X940752Y559227D01*
Y560227D01*
X940132Y560847D01*
Y561847D01*
X940752Y562467D01*
Y563626D01*
X940278Y564100D01*
Y565100D01*
X940752Y565574D01*
Y572284D01*
X940317Y572719D01*
Y573719D01*
X940752Y574154D01*
Y576292D01*
X940371Y576673D01*
Y577673D01*
X940752Y578054D01*
Y579293D01*
X940132Y579913D01*
Y580913D01*
X940752Y581533D01*
Y582533D01*
X940132Y583153D01*
Y584153D01*
X940752Y584773D01*
Y587594D01*
X939832Y588514D01*
X938732D01*
G01X933632Y588300D02*
X934732D01*
X935652Y587380D01*
Y584403D01*
X935032Y583783D01*
Y582783D01*
X935652Y582163D01*
Y581163D01*
X935032Y580543D01*
Y579543D01*
X935652Y578923D01*
Y577711D01*
X935244Y577303D01*
Y576303D01*
X935652Y575895D01*
Y564765D01*
X935099Y564212D01*
Y563212D01*
X935652Y562659D01*
Y561500D01*
X935138Y560986D01*
Y559986D01*
X935652Y559472D01*
Y487581D01*
X933520Y485449D01*
Y456009D01*
X939920Y449609D01*
Y438222D01*
X939922D01*
X964783Y413361D01*
Y405512D01*
G01X969846Y409187D02*
Y415262D01*
X945109Y439998D01*
Y455015D01*
X943568Y456556D01*
X940952D01*
X940080Y457428D01*
Y459124D01*
X940952Y459996D01*
X943117D01*
X944237Y461116D01*
Y464660D01*
X943117Y465780D01*
X939552D01*
X938480Y466852D01*
Y483409D01*
X941812Y486741D01*
Y588034D01*
X938732Y591114D01*
G01X959433Y400464D02*
Y411195D01*
X933300Y437328D01*
Y438460D01*
X933991Y439151D01*
Y440389D01*
X932860Y441520D01*
X931834D01*
X931037Y440723D01*
X929905D01*
X928300Y442328D01*
Y487900D01*
X927974Y488226D01*
Y493874D01*
X929016Y494916D01*
Y510923D01*
X927882Y512057D01*
Y516307D01*
X928963Y517388D01*
Y529513D01*
X927882Y530594D01*
Y535282D01*
X929232Y536632D01*
Y548507D01*
X927882Y549857D01*
Y554107D01*
X929032Y555257D01*
Y567267D01*
X927932Y568367D01*
Y573033D01*
X929082Y574183D01*
Y586457D01*
X927165Y588374D01*
Y593757D01*
G01X961933Y400312D02*
Y412368D01*
X937200Y437101D01*
Y449622D01*
X936282Y450540D01*
X934682D01*
X934000Y449858D01*
Y444343D01*
X933317Y443660D01*
X931717D01*
X930800Y444577D01*
Y486800D01*
X931732Y487732D01*
Y519432D01*
X932200Y519900D01*
Y527900D01*
X931732Y528368D01*
Y537700D01*
X932200Y538168D01*
Y546300D01*
X931732Y546768D01*
Y556500D01*
X932200Y556968D01*
Y562600D01*
X931732Y563068D01*
Y575600D01*
X932200Y576068D01*
Y583800D01*
X931732Y584268D01*
Y586443D01*
X929811Y588364D01*
Y588714D01*
G01X954133Y400162D02*
Y409167D01*
X923200Y440100D01*
Y465816D01*
X919100Y469916D01*
Y474022D01*
X919900Y474822D01*
X920676D01*
X921476Y475622D01*
Y477222D01*
X920676Y478022D01*
X919900D01*
X919100Y478822D01*
Y485899D01*
X921644Y488443D01*
Y494444D01*
X922400Y495200D01*
Y502600D01*
X922274Y502726D01*
Y511055D01*
X921532Y511797D01*
Y516505D01*
X922432Y517405D01*
Y529468D01*
X921532Y530368D01*
Y535242D01*
X922532Y536242D01*
Y548557D01*
X921532Y549557D01*
Y554309D01*
X922432Y555209D01*
Y567169D01*
X921384Y568217D01*
Y572944D01*
X922382Y573942D01*
Y586457D01*
X920472Y588367D01*
Y593757D01*
G01X956633Y400312D02*
Y410367D01*
X925800Y441200D01*
Y469239D01*
X925190Y469849D01*
X922521D01*
X921911Y470459D01*
Y472439D01*
X922521Y473049D01*
X925190D01*
X925800Y473659D01*
Y480132D01*
X925000Y480932D01*
X921737D01*
X920990Y481679D01*
Y483279D01*
X921843Y484132D01*
X925488D01*
X926100Y484744D01*
Y494500D01*
X925400Y495200D01*
Y506200D01*
X925174Y506426D01*
Y511539D01*
X925382Y511747D01*
Y517207D01*
X925132Y517457D01*
Y519100D01*
X925500Y519468D01*
Y527600D01*
X925132Y527968D01*
Y529992D01*
X925382Y530242D01*
Y535192D01*
X925032Y535542D01*
Y537500D01*
X925500Y537968D01*
Y546600D01*
X925032Y547068D01*
Y548885D01*
X925382Y549235D01*
Y555007D01*
X925132Y555257D01*
Y556900D01*
X925500Y557268D01*
Y565700D01*
X925132Y566068D01*
Y567997D01*
X925632Y568497D01*
Y572656D01*
X925032Y573256D01*
Y575732D01*
X925500Y576200D01*
Y584400D01*
X925032Y584868D01*
Y587200D01*
X923518Y588714D01*
G01X972712Y403924D02*
Y416100D01*
X947552Y441260D01*
Y465226D01*
X941100Y471678D01*
Y482400D01*
X946132Y487432D01*
Y493868D01*
X945600Y494400D01*
Y501200D01*
X945776Y501376D01*
Y511613D01*
X945332Y512057D01*
Y516957D01*
X945732Y517357D01*
Y529842D01*
X945332Y530242D01*
Y535832D01*
X945775Y536275D01*
Y549414D01*
X945332Y549857D01*
Y554757D01*
X945932Y555357D01*
Y557200D01*
X945600Y557532D01*
Y565600D01*
X945932Y565932D01*
Y567397D01*
X944859Y568470D01*
Y572969D01*
X946029Y574139D01*
Y575271D01*
X945600Y575700D01*
Y584400D01*
X946132Y584932D01*
Y586357D01*
X943400Y589089D01*
Y593260D01*
X943897Y593757D01*
G01X975212Y403862D02*
Y417136D01*
X949992Y442356D01*
Y445511D01*
X950910Y446429D01*
X951773D01*
X952383Y447039D01*
Y449019D01*
X951773Y449629D01*
X950935D01*
X950325Y450239D01*
Y452219D01*
X950935Y452829D01*
X951773D01*
X952383Y453439D01*
Y455419D01*
X951773Y456029D01*
X950406D01*
X949796Y456639D01*
Y458619D01*
X950406Y459229D01*
X951614D01*
X952224Y459839D01*
Y461819D01*
X951614Y462429D01*
X950459D01*
X949902Y462986D01*
Y464966D01*
X950565Y465629D01*
X951773D01*
X952383Y466239D01*
Y468219D01*
X951773Y468829D01*
X947471D01*
X943800Y472500D01*
Y481760D01*
X948632Y486592D01*
Y493732D01*
X949900Y495000D01*
Y498100D01*
X948632Y499368D01*
Y511257D01*
X949532Y512157D01*
Y516557D01*
X948732Y517357D01*
Y529842D01*
X949432Y530542D01*
Y535468D01*
X948632Y536268D01*
Y537832D01*
X948900Y538100D01*
Y546200D01*
X948632Y546468D01*
Y549057D01*
X949532Y549957D01*
Y554357D01*
X948432Y555457D01*
Y557031D01*
X948900Y557499D01*
Y566000D01*
X948732Y566168D01*
Y567597D01*
X949298Y568163D01*
Y573401D01*
X948632Y574067D01*
Y575632D01*
X948900Y575900D01*
Y584500D01*
X948632Y584768D01*
Y587368D01*
X948589D01*
X947243Y588714D01*
G01X978216Y405717D02*
Y417668D01*
X954372Y441512D01*
Y469622D01*
X948242Y475752D01*
Y482595D01*
X952800Y487153D01*
Y493500D01*
X952300Y494000D01*
Y500100D01*
X950600Y501800D01*
Y507500D01*
X952532Y509432D01*
Y511157D01*
X951891Y511798D01*
Y516832D01*
X952882Y517823D01*
Y519200D01*
X952300Y519782D01*
Y528000D01*
X952882Y528582D01*
Y529416D01*
X951932Y530366D01*
Y535932D01*
X952532Y536532D01*
Y537900D01*
X952300Y538132D01*
Y546300D01*
X952532Y546532D01*
Y548957D01*
X952032Y549457D01*
Y554857D01*
X952832Y555657D01*
Y557100D01*
X952266Y557666D01*
Y565666D01*
X952832Y566232D01*
Y567297D01*
X951732Y568397D01*
Y573142D01*
X952632Y574042D01*
Y575700D01*
X952300Y576032D01*
Y584500D01*
X952632Y584832D01*
Y586507D01*
X950100Y589039D01*
Y593267D01*
X950590Y593757D01*
G01X980512Y405921D02*
Y418908D01*
X956904Y442516D01*
Y477096D01*
X956060Y477940D01*
X951835D01*
X951017Y478758D01*
Y480898D01*
X951975Y481856D01*
X954451D01*
X955332Y482737D01*
Y486160D01*
X955942Y486770D01*
X959042D01*
X959652Y487380D01*
Y489360D01*
X959042Y489970D01*
X955942D01*
X955332Y490580D01*
Y491652D01*
X956800Y493120D01*
Y499400D01*
X955332Y500868D01*
Y503107D01*
X954532Y503907D01*
X953300D01*
X952500Y504707D01*
Y506307D01*
X953300Y507107D01*
X954532D01*
X955332Y507907D01*
Y511657D01*
X955848Y512173D01*
Y516891D01*
X955382Y517357D01*
Y519782D01*
X955900Y520300D01*
Y535800D01*
X955332Y536368D01*
Y537800D01*
X955900Y538368D01*
Y546500D01*
X955332Y547068D01*
Y549457D01*
X955932Y550057D01*
Y554607D01*
X955382Y555157D01*
Y557381D01*
X955874Y557873D01*
Y573526D01*
X954532Y574868D01*
Y588118D01*
X953936Y588714D01*
G01X990354Y401003D02*
Y474546D01*
X965400Y499500D01*
Y511300D01*
X965900Y511800D01*
Y513800D01*
X965400Y514300D01*
Y516500D01*
X965800Y516900D01*
Y527700D01*
X965607Y527893D01*
Y535807D01*
X965695Y535895D01*
Y543405D01*
X962257Y546843D01*
Y551757D01*
X962360Y551860D01*
Y567840D01*
X960629Y569571D01*
Y574757D01*
G01X992354Y400788D02*
Y475446D01*
X969500Y498300D01*
Y511100D01*
X968800Y511800D01*
Y513800D01*
X969200Y514200D01*
Y516500D01*
X968700Y517000D01*
Y527500D01*
X969045Y527845D01*
Y530555D01*
X968957Y530643D01*
Y543443D01*
X965710Y546690D01*
Y549510D01*
X965900Y549700D01*
Y551400D01*
X965200Y552100D01*
Y554633D01*
X963976Y555857D01*
G01X988354Y400454D02*
Y473546D01*
X963100Y498800D01*
Y510900D01*
X962000Y512000D01*
Y513600D01*
X962600Y514200D01*
Y516600D01*
X961450Y517750D01*
Y527050D01*
X962347Y527947D01*
Y535353D01*
X962242Y535458D01*
Y543759D01*
X960629Y545372D01*
Y547914D01*
G01X913779Y498487D02*
X915721Y500429D01*
Y511157D01*
X915221Y511657D01*
Y517057D01*
X916000Y517836D01*
Y519221D01*
X915500Y519721D01*
Y527800D01*
X916021Y528321D01*
Y529497D01*
X914921Y530597D01*
Y535342D01*
X915821Y536242D01*
Y537600D01*
X915500Y537921D01*
Y546800D01*
X915821Y547121D01*
Y548707D01*
X912421Y552107D01*
Y554599D01*
X913779Y555957D01*
G01X917192Y493919D02*
X918521Y495248D01*
Y511657D01*
X919121Y512257D01*
Y516807D01*
X918571Y517357D01*
Y519200D01*
X918800Y519429D01*
Y527800D01*
X918571Y528029D01*
Y529847D01*
X919421Y530697D01*
Y535478D01*
X918421Y536478D01*
Y538280D01*
X917300Y539401D01*
Y540799D01*
X918400Y541899D01*
Y543000D01*
X917504Y543896D01*
Y545404D01*
X918400Y546300D01*
Y549691D01*
X917125Y550966D01*
Y550914D01*
G01X970669Y555857D02*
Y566814D01*
G01X996398Y397118D02*
Y482150D01*
X991067Y487481D01*
X990205D01*
X989351Y486627D01*
X988555D01*
X987571Y487611D01*
Y488539D01*
X988359Y489327D01*
Y490189D01*
X987375Y491173D01*
X986513D01*
X985439Y490099D01*
X984577D01*
X983593Y491083D01*
Y491945D01*
X984667Y493019D01*
Y493881D01*
X983683Y494865D01*
X982821D01*
X981758Y493802D01*
X980841D01*
X979857Y494786D01*
Y495593D01*
X980975Y496711D01*
Y497573D01*
X979300Y499248D01*
Y506146D01*
X976000Y509446D01*
Y510900D01*
X975400Y511500D01*
Y513800D01*
X976000Y514400D01*
Y516400D01*
X975500Y516900D01*
Y520892D01*
X975657Y521049D01*
Y532957D01*
X975700Y533000D01*
Y543400D01*
X972394Y546706D01*
Y549294D01*
X972601Y549501D01*
Y553925D01*
X970669Y555857D01*
G01X994398Y396937D02*
Y476502D01*
X972100Y498800D01*
Y511200D01*
X972500Y511600D01*
Y513900D01*
X972000Y514400D01*
Y516300D01*
X972600Y516900D01*
Y519300D01*
X972400Y519500D01*
Y530700D01*
X972835Y531135D01*
Y535555D01*
X972395Y535995D01*
Y538105D01*
X971700Y538800D01*
Y543458D01*
X968957Y546201D01*
Y549543D01*
X968600Y549900D01*
Y552602D01*
X969059Y553061D01*
Y559557D01*
X963976Y564640D01*
Y566814D01*
G01X913779Y555957D02*
X912074Y557662D01*
Y567849D01*
X917125Y572900D01*
G01Y550914D02*
X917037D01*
X915351Y552600D01*
Y554292D01*
X915526Y554467D01*
Y557100D01*
X914414Y558212D01*
Y559288D01*
X915426Y560300D01*
Y561500D01*
X914414Y562512D01*
Y563588D01*
X915551Y564725D01*
Y565999D01*
X914851Y566699D01*
X913779D01*
G01X974015Y54857D02*
Y53486D01*
X978970Y48531D01*
Y32969D01*
X974015Y28014D01*
G01X1030490Y191050D02*
Y104516D01*
X1031280Y103726D01*
Y80820D01*
X1033400Y78700D01*
Y53900D01*
X1031280Y51780D01*
Y45992D01*
X1028200Y42912D01*
Y39885D01*
X1020034Y31719D01*
X1014190D01*
X1012954Y30483D01*
Y29233D01*
X1014173Y28014D01*
G01X1029430Y191170D02*
Y104076D01*
X1030220Y103286D01*
Y80380D01*
X1032340Y78260D01*
Y54340D01*
X1030220Y52220D01*
Y46432D01*
X1027140Y43352D01*
Y40325D01*
X1019594Y32779D01*
X1013750D01*
X1011894Y30923D01*
Y29082D01*
X1010826Y28014D01*
G01X1004134Y54857D02*
X1002500Y53223D01*
Y51800D01*
X1002300Y51600D01*
Y48218D01*
X1002500Y48018D01*
Y34499D01*
X1004134Y32865D01*
Y28023D01*
X1004133Y28022D01*
G01X1000787Y54857D02*
Y52164D01*
X1000300Y51677D01*
Y49142D01*
X999060Y47902D01*
Y45979D01*
X1000300Y44739D01*
Y38191D01*
X999067Y36958D01*
Y31612D01*
X1000787Y29892D01*
Y28022D01*
G01X994094Y54857D02*
X992470Y50936D01*
Y46232D01*
X991040Y44802D01*
Y38096D01*
X992487Y36649D01*
Y33870D01*
X993340Y31811D01*
X993501Y31000D01*
X994094Y28022D01*
G01X990748D02*
Y30692D01*
X989600Y31840D01*
Y34401D01*
X989017Y34984D01*
Y53126D01*
X990748Y54857D01*
G01X997796Y198224D02*
Y121425D01*
X981208Y104837D01*
Y101267D01*
X975429Y95488D01*
Y91805D01*
X976160Y91074D01*
Y88974D01*
X975460Y88274D01*
Y86374D01*
X975960Y85874D01*
Y83900D01*
X975746Y83686D01*
Y72673D01*
X975960Y72459D01*
Y69959D01*
X975360Y69359D01*
Y67359D01*
X975627Y67092D01*
Y60968D01*
X972400Y57741D01*
Y51876D01*
X977362Y46914D01*
G01D02*
X975700Y45252D01*
Y36857D01*
X976600Y35957D01*
X977362D01*
G01X999796Y198928D02*
Y117750D01*
X996246Y114200D01*
X995538D01*
X994726Y115012D01*
X993864D01*
X992519Y113667D01*
Y112805D01*
X993616Y111708D01*
Y110846D01*
X992271Y109501D01*
X991409D01*
X990312Y110598D01*
X989450D01*
X988105Y109253D01*
Y108391D01*
X989202Y107294D01*
Y106432D01*
X987857Y105087D01*
X986995D01*
X986037Y106045D01*
X985329D01*
X983830Y104546D01*
Y103838D01*
X984584Y103084D01*
Y101814D01*
X980060Y97290D01*
Y92374D01*
X978660Y90974D01*
Y88874D01*
X979360Y88174D01*
Y86274D01*
X978760Y85674D01*
Y84039D01*
X979001Y83798D01*
Y72600D01*
X978760Y72359D01*
Y70059D01*
X979360Y69459D01*
Y67459D01*
X979095Y67194D01*
Y60955D01*
X974015Y55875D01*
Y54857D01*
G01X1020954Y189046D02*
Y106423D01*
X1019310Y104779D01*
X1019307D01*
X1018279Y103751D01*
Y102147D01*
X1010338Y94206D01*
Y90944D01*
X1010260Y90866D01*
Y86271D01*
X1012560Y83971D01*
Y82591D01*
X1013170Y81981D01*
X1016638D01*
X1017897Y80722D01*
Y78452D01*
X1016696Y77251D01*
X1013170D01*
X1012560Y76641D01*
Y72176D01*
X1014376Y70360D01*
X1017080D01*
X1019456Y67984D01*
Y62846D01*
X1016866Y60256D01*
X1014899D01*
X1013054Y58411D01*
Y55961D01*
X1014173Y54842D01*
G01X1027554Y189046D02*
Y102279D01*
X1027980Y101853D01*
Y49752D01*
X1023452Y45224D01*
Y42599D01*
X1021363Y40510D01*
X1018489D01*
X1017369Y41630D01*
Y42595D01*
X1016633Y43331D01*
X1014149D01*
X1012954Y42136D01*
Y37161D01*
X1014173Y35942D01*
G01X1024254Y188846D02*
Y104826D01*
X1021880Y102452D01*
Y72320D01*
X1024080Y70120D01*
Y57491D01*
X1017989Y51400D01*
X1015999D01*
X1012954Y48355D01*
Y47833D01*
X1013873Y46914D01*
G01X1010826Y54842D02*
X1011994Y56010D01*
Y58851D01*
X1014459Y61316D01*
X1016426D01*
X1018396Y63286D01*
Y67544D01*
X1016640Y69300D01*
X1013936D01*
X1011500Y71736D01*
Y77081D01*
X1012730Y78311D01*
X1016256D01*
X1016837Y78892D01*
Y80282D01*
X1016198Y80921D01*
X1012730D01*
X1011500Y82151D01*
Y83531D01*
X1009200Y85831D01*
Y91306D01*
X1009278Y91384D01*
Y94646D01*
X1017219Y102587D01*
Y104191D01*
X1019894Y106866D01*
Y188926D01*
G01X1026494D02*
Y101839D01*
X1026920Y101413D01*
Y50192D01*
X1022392Y45664D01*
Y43039D01*
X1020923Y41570D01*
X1018929D01*
X1018429Y42070D01*
Y43035D01*
X1017073Y44391D01*
X1013709D01*
X1011894Y42576D01*
Y37010D01*
X1010826Y35942D01*
G01X1023194Y188726D02*
Y105266D01*
X1020820Y102892D01*
Y71880D01*
X1023020Y69680D01*
Y57931D01*
X1017549Y52460D01*
X1015559D01*
X1011894Y48795D01*
Y47682D01*
X1011126Y46914D01*
G01X1015700Y192683D02*
Y109998D01*
X1015017Y109315D01*
X1012115D01*
X1010984Y108184D01*
Y107052D01*
X1012053Y105983D01*
Y104851D01*
X1010922Y103720D01*
X1009790D01*
X1008721Y104789D01*
X1007589D01*
X1006458Y103658D01*
Y102526D01*
X1007527Y101457D01*
Y100325D01*
X1006396Y99194D01*
X1004521D01*
X1002201Y96874D01*
Y91805D01*
X1002932Y91074D01*
Y88974D01*
X1001500Y87542D01*
Y86500D01*
X1002732Y85268D01*
Y83732D01*
X1002513Y83513D01*
Y69740D01*
X1002132Y69359D01*
Y67359D01*
X1002500Y66991D01*
Y58400D01*
X1004134Y56766D01*
Y54857D01*
G01X1004133Y46922D02*
Y52233D01*
X1006441Y54541D01*
Y58079D01*
X1005582Y58938D01*
Y60411D01*
X1006082Y60911D01*
X1008364D01*
X1008974Y61521D01*
Y63421D01*
X1008364Y64031D01*
X1006371D01*
X1005761Y64641D01*
Y66630D01*
X1005236Y67155D01*
Y72559D01*
X1006132Y73455D01*
Y82930D01*
X1005532Y83530D01*
Y85674D01*
X1005775Y85917D01*
Y88531D01*
X1005432Y88874D01*
Y90974D01*
X1005790Y91332D01*
Y94392D01*
X1014235Y102837D01*
Y104204D01*
X1017700Y107669D01*
Y192974D01*
G01X1004134Y35957D02*
X1005807Y37630D01*
Y40392D01*
X1004133Y42066D01*
Y46922D01*
G01X1013700Y192561D02*
Y113729D01*
X1000082Y100111D01*
Y92524D01*
X998987Y91429D01*
Y89069D01*
X999241Y88815D01*
Y85883D01*
X998987Y85629D01*
Y83512D01*
X999072Y83427D01*
Y72599D01*
X998987Y72514D01*
Y70104D01*
X999168Y69923D01*
Y58833D01*
X1001400Y56601D01*
Y55470D01*
X1000787Y54857D01*
G01X1011700Y192853D02*
Y114559D01*
X998082Y100941D01*
Y95944D01*
X995446Y93308D01*
Y91574D01*
X996046Y90974D01*
Y88974D01*
X995446Y88374D01*
Y86174D01*
X996046Y85574D01*
Y83700D01*
X995752Y83406D01*
Y72453D01*
X996046Y72159D01*
Y69959D01*
X995246Y69159D01*
Y67759D01*
X995722Y67283D01*
Y59378D01*
X999150Y55950D01*
Y54120D01*
X998200Y53170D01*
Y49770D01*
X997441Y49011D01*
Y46922D01*
G01D02*
Y45272D01*
X998631Y44082D01*
Y38926D01*
X997441Y37736D01*
Y35957D01*
G01X994094D02*
X995197D01*
X995763Y36523D01*
Y37539D01*
X995164Y38138D01*
X993281D01*
X992671Y38748D01*
Y39738D01*
X993281Y40348D01*
X996379D01*
X996989Y40958D01*
Y41948D01*
X996379Y42558D01*
X993228D01*
X992670Y43116D01*
Y44106D01*
X993332Y44768D01*
X995185D01*
X995815Y45398D01*
Y46422D01*
X995315Y46922D01*
X994094D01*
G01D02*
Y50000D01*
X995724Y51630D01*
Y56675D01*
X992428Y59971D01*
Y72641D01*
X992481Y72694D01*
Y74820D01*
X992146Y75155D01*
Y85674D01*
X992746Y86274D01*
Y88174D01*
X992337Y88583D01*
Y91265D01*
X992548Y91476D01*
Y98237D01*
X1009700Y115389D01*
Y192853D01*
G01X1005796Y198807D02*
Y192638D01*
X1007700Y190734D01*
Y116218D01*
X988948Y97466D01*
Y91672D01*
X990000Y90620D01*
Y89428D01*
X988846Y88274D01*
Y86374D01*
X989346Y85874D01*
Y83330D01*
X989024Y83008D01*
Y72781D01*
X990009Y71796D01*
Y69462D01*
X989142Y68595D01*
Y65085D01*
X990630Y63597D01*
Y62549D01*
X989884Y61803D01*
X988351D01*
X987741Y61193D01*
Y60203D01*
X988351Y59593D01*
X990458D01*
X994094Y55957D01*
Y54857D01*
G01X987401Y35957D02*
Y37001D01*
X986826Y37576D01*
X983865D01*
X982981Y38460D01*
Y44417D01*
X983570Y45006D01*
X984560D01*
X985191Y44375D01*
Y40308D01*
X985801Y39698D01*
X986791D01*
X987401Y40308D01*
Y46914D01*
G01D02*
X985315Y49000D01*
X983010D01*
X982138Y49872D01*
Y52238D01*
X982400Y52500D01*
Y67219D01*
X981860Y67759D01*
Y71829D01*
X982425Y72394D01*
Y85809D01*
X982060Y86174D01*
Y88374D01*
X982504Y88818D01*
Y91130D01*
X982060Y91574D01*
Y96461D01*
X1001796Y116197D01*
Y199049D01*
G01X990748Y54857D02*
Y56017D01*
X989985Y56780D01*
X985418D01*
X984647Y57551D01*
Y63038D01*
X985675Y64066D01*
Y66788D01*
X986748Y67861D01*
Y71565D01*
X985700Y72613D01*
Y83046D01*
X985446Y83300D01*
Y85474D01*
X986446Y86474D01*
Y88224D01*
X985446Y89224D01*
Y91274D01*
X986900Y92728D01*
Y93600D01*
X985116Y95384D01*
Y96516D01*
X1005700Y117100D01*
Y189905D01*
X1003796Y191809D01*
Y198734D01*
G01X1032122Y195289D02*
Y106734D01*
X1033886Y104970D01*
Y98414D01*
X1035835Y96465D01*
X1038721D01*
X1042400Y92786D01*
Y65300D01*
X1039300Y62200D01*
Y58800D01*
X1042300Y55800D01*
Y51582D01*
X1044290Y49592D01*
G01X1054331Y54857D02*
X1053743D01*
X1050550Y58050D01*
X1049373Y62966D01*
Y66971D01*
X1049368Y66994D01*
Y74445D01*
X1049000Y74813D01*
Y82452D01*
X1049991Y83443D01*
Y85339D01*
X1049000Y86330D01*
Y88033D01*
X1050307Y89340D01*
Y90674D01*
X1047200Y93781D01*
Y98186D01*
X1035327Y110059D01*
Y200166D01*
G01X1041634Y192547D02*
Y125067D01*
X1055800Y110901D01*
Y102500D01*
X1062500Y95800D01*
Y91400D01*
X1062823Y91077D01*
Y88823D01*
X1062569Y88569D01*
Y86079D01*
X1062823Y85825D01*
Y83824D01*
X1062634Y83635D01*
Y72399D01*
X1062764Y72269D01*
Y64764D01*
X1062508Y64508D01*
Y59792D01*
X1065990Y56310D01*
Y51344D01*
X1069457Y47877D01*
Y45051D01*
X1070083Y44425D01*
Y37621D01*
X1069457Y36995D01*
Y33006D01*
X1068396Y31945D01*
X1067410D01*
X1066281Y33074D01*
X1065217D01*
X1064371Y32228D01*
Y28022D01*
G01X1047637Y54842D02*
Y57766D01*
X1046576Y58827D01*
X1042200D01*
X1041400Y59627D01*
Y61227D01*
X1042200Y62027D01*
X1045028D01*
X1045700Y62699D01*
Y66628D01*
X1047095Y68023D01*
Y70932D01*
X1044992Y73035D01*
Y76202D01*
X1046546Y77756D01*
Y83144D01*
X1045555Y84135D01*
Y86055D01*
X1046231Y86731D01*
Y88168D01*
X1045100Y89299D01*
Y96897D01*
X1044448Y97549D01*
X1043509D01*
X1042474Y96514D01*
X1041292D01*
X1040211Y97595D01*
Y98777D01*
X1041444Y100010D01*
Y101142D01*
X1040313Y102273D01*
X1039181D01*
X1038116Y101208D01*
X1036683D01*
X1035552Y102339D01*
Y103170D01*
X1037238Y104856D01*
Y105778D01*
X1033744Y109272D01*
Y195798D01*
G01X1038614Y191891D02*
Y118086D01*
X1049000Y107700D01*
Y102390D01*
X1055800Y95590D01*
Y91040D01*
X1056130Y90710D01*
Y89218D01*
X1055800Y88888D01*
Y85675D01*
X1056300Y85175D01*
Y75101D01*
X1055966Y74767D01*
Y71974D01*
X1056130Y71810D01*
Y70318D01*
X1055800Y69988D01*
Y66775D01*
X1055944Y66631D01*
Y58256D01*
X1057243Y56957D01*
X1058695D01*
X1059305Y56347D01*
Y53953D01*
X1064371Y48887D01*
Y46922D01*
G01X1037104Y199996D02*
Y111396D01*
X1038088Y110412D01*
X1038950D01*
X1040720Y112182D01*
X1041429D01*
X1042903Y110708D01*
Y109951D01*
X1041157Y108205D01*
Y107343D01*
X1042502Y105998D01*
X1043364D01*
X1044265Y106899D01*
X1044973D01*
X1046472Y105400D01*
Y104692D01*
X1045571Y103791D01*
Y102929D01*
X1049483Y99017D01*
Y96685D01*
X1050668Y95500D01*
X1051811D01*
X1053169Y94142D01*
Y92397D01*
X1052300Y91528D01*
Y88621D01*
X1052783Y88138D01*
Y86646D01*
X1052300Y86163D01*
Y83300D01*
X1052700Y82900D01*
Y80374D01*
X1051570Y79244D01*
Y76502D01*
X1052700Y75372D01*
Y73032D01*
X1052701Y73029D01*
X1051618Y71946D01*
Y68507D01*
X1052648Y67477D01*
Y58953D01*
X1056644Y54957D01*
X1057562D01*
X1057677Y54842D01*
G01X1000398Y407015D02*
Y482948D01*
X983500Y499846D01*
Y510300D01*
X982200Y511600D01*
Y514000D01*
X982600Y514400D01*
Y516500D01*
X982100Y517000D01*
Y519200D01*
X982400Y519500D01*
Y530400D01*
X982092Y530708D01*
Y535692D01*
X982444Y536044D01*
Y542832D01*
X977362Y547914D01*
G01X1035800Y406737D02*
Y488670D01*
X1047228Y500098D01*
Y507044D01*
X1049600Y509416D01*
Y511200D01*
X1049100Y511700D01*
Y513700D01*
X1050100Y514700D01*
Y515900D01*
X1049100Y516900D01*
Y519300D01*
X1049352Y519552D01*
Y542674D01*
X1052673Y545995D01*
Y552787D01*
X1054331Y554445D01*
Y555857D01*
G01X998398Y397365D02*
Y482570D01*
X981500Y499468D01*
Y506776D01*
X978700Y509576D01*
Y510900D01*
X979300Y511500D01*
Y514100D01*
X978700Y514700D01*
Y516400D01*
X979400Y517100D01*
Y518900D01*
X979094Y519206D01*
Y530388D01*
X978991Y530491D01*
Y543509D01*
X975700Y546800D01*
Y548900D01*
X975100Y549500D01*
Y554030D01*
X974015Y555115D01*
Y555857D01*
G01X1024852Y409402D02*
Y504969D01*
X1027927Y508044D01*
Y509346D01*
X1027119Y510154D01*
X1026210D01*
X1025090Y511274D01*
Y513764D01*
X1026210Y514884D01*
X1027066D01*
X1028220Y516038D01*
Y520772D01*
X1027772Y521220D01*
Y523050D01*
X1028220Y523498D01*
Y525328D01*
X1027772Y525776D01*
Y527606D01*
X1028220Y528054D01*
Y529884D01*
X1027772Y530332D01*
Y532162D01*
X1028220Y532610D01*
Y534440D01*
X1027772Y534888D01*
Y536718D01*
X1028220Y537166D01*
Y549660D01*
X1027340Y550540D01*
Y554820D01*
X1026892Y555268D01*
Y557098D01*
X1027340Y557546D01*
Y559376D01*
X1026892Y559824D01*
Y561654D01*
X1027340Y562102D01*
Y563932D01*
X1026547Y564725D01*
X1025919D01*
X1024625Y566019D01*
Y566647D01*
X1023342Y567930D01*
X1022735D01*
X1021441Y569224D01*
Y569831D01*
X1020652Y570620D01*
X1018586D01*
X1018139Y570173D01*
X1016309D01*
X1015862Y570620D01*
X1013814D01*
X1012941Y569747D01*
Y568046D01*
X1014173Y566814D01*
G01X1021820Y409466D02*
Y520219D01*
X1023544Y521943D01*
Y524433D01*
X1023096Y524881D01*
Y526711D01*
X1023544Y527159D01*
Y528989D01*
X1023096Y529437D01*
Y531267D01*
X1023544Y531715D01*
Y533545D01*
X1023096Y533993D01*
Y535823D01*
X1023544Y536271D01*
Y538101D01*
X1023096Y538549D01*
Y540379D01*
X1023544Y540827D01*
Y542657D01*
X1023096Y543105D01*
Y544935D01*
X1023544Y545383D01*
Y547213D01*
X1023096Y547661D01*
Y549491D01*
X1023544Y549939D01*
Y551769D01*
X1023096Y552217D01*
Y554047D01*
X1023544Y554495D01*
Y556325D01*
X1022724Y557145D01*
X1022211Y557146D01*
X1021081Y558276D01*
Y558788D01*
X1020349Y559520D01*
X1018891D01*
X1018445Y559074D01*
X1016615D01*
X1016169Y559520D01*
X1014055D01*
X1012903Y558368D01*
Y557112D01*
X1014173Y555842D01*
G01X1028274Y409306D02*
Y485929D01*
X1027826Y486377D01*
Y488207D01*
X1028274Y488655D01*
Y490485D01*
X1027826Y490933D01*
Y492763D01*
X1028274Y493211D01*
Y495041D01*
X1027826Y495489D01*
Y497319D01*
X1028274Y497767D01*
Y499597D01*
X1031424Y502747D01*
Y504613D01*
X1031012Y505025D01*
Y506855D01*
X1031424Y507267D01*
Y511551D01*
X1031047Y511928D01*
Y513758D01*
X1031424Y514135D01*
Y551730D01*
X1031012Y552142D01*
Y553972D01*
X1031424Y554384D01*
Y556160D01*
X1030240Y557344D01*
Y565502D01*
X1029917Y565825D01*
Y567655D01*
X1030240Y567978D01*
Y569629D01*
X1027593Y572276D01*
X1026960D01*
X1025665Y573571D01*
Y574204D01*
X1024371Y575498D01*
X1023738D01*
X1022443Y576793D01*
Y577426D01*
X1021149Y578720D01*
X1018961D01*
X1018513Y578272D01*
X1016683D01*
X1016235Y578720D01*
X1014405D01*
X1013112Y577427D01*
Y575803D01*
X1014173Y574742D01*
G01X1018518Y409472D02*
Y502296D01*
X1018070Y502744D01*
Y504574D01*
X1018518Y505022D01*
Y506852D01*
X1018070Y507300D01*
Y509130D01*
X1018518Y509578D01*
Y511408D01*
X1018070Y511856D01*
Y513686D01*
X1018518Y514134D01*
Y515964D01*
X1017161Y517321D01*
X1014475D01*
X1013041Y518755D01*
Y522050D01*
X1014366Y523375D01*
X1015271D01*
X1015691Y523795D01*
X1017521D01*
X1017941Y523375D01*
X1018852D01*
X1019720Y524243D01*
Y525540D01*
X1019273Y525987D01*
Y527817D01*
X1019720Y528264D01*
Y529840D01*
X1019272Y530288D01*
Y532118D01*
X1019720Y532566D01*
Y534396D01*
X1019272Y534844D01*
Y536674D01*
X1019720Y537122D01*
Y538450D01*
X1019110Y539060D01*
X1018055D01*
X1017608Y538613D01*
X1015778D01*
X1015331Y539060D01*
X1014109D01*
X1012843Y540326D01*
Y542596D01*
X1014037Y543790D01*
X1015276D01*
X1015722Y544236D01*
X1017552D01*
X1017998Y543790D01*
X1019110D01*
X1019720Y544400D01*
Y548180D01*
X1016460Y551440D01*
X1013636D01*
X1012680Y550484D01*
Y549107D01*
X1013873Y547914D01*
G01X1025912Y409402D02*
Y504529D01*
X1028987Y507604D01*
Y509786D01*
X1027559Y511214D01*
X1026650D01*
X1026150Y511714D01*
Y513324D01*
X1026650Y513824D01*
X1027506D01*
X1029280Y515598D01*
Y550100D01*
X1028400Y550980D01*
Y564372D01*
X1021092Y571680D01*
X1013374D01*
X1011881Y570187D01*
Y567869D01*
X1010826Y566814D01*
G01X1022880Y409466D02*
Y519779D01*
X1024604Y521503D01*
Y556768D01*
X1020792Y560580D01*
X1013615D01*
X1011843Y558808D01*
Y556859D01*
X1010928Y555944D01*
Y555842D01*
G01X1029334Y409186D02*
Y499157D01*
X1032484Y502307D01*
Y556600D01*
X1031300Y557784D01*
Y570072D01*
X1021592Y579780D01*
X1013965D01*
X1012052Y577867D01*
Y575968D01*
X1010826Y574742D01*
G01X1011126Y547914D02*
X1011620Y548408D01*
Y550924D01*
X1013196Y552500D01*
X1016900D01*
X1020780Y548620D01*
Y543960D01*
X1019550Y542730D01*
X1014477D01*
X1013903Y542156D01*
Y540766D01*
X1014549Y540120D01*
X1019550D01*
X1020780Y538890D01*
Y523803D01*
X1019292Y522315D01*
X1014806D01*
X1014101Y521610D01*
Y519195D01*
X1014915Y518381D01*
X1017601D01*
X1019578Y516404D01*
Y409511D01*
G01X1039800Y406540D02*
Y487010D01*
X1048995Y496205D01*
X1048994D01*
X1052900Y500111D01*
Y503130D01*
X1051502Y504528D01*
Y505660D01*
X1052942Y507100D01*
X1055912D01*
X1057100Y508288D01*
Y510300D01*
X1055800Y511600D01*
Y513900D01*
X1056200Y514300D01*
Y516500D01*
X1055215Y517485D01*
Y520165D01*
X1055825Y520775D01*
X1057453D01*
X1058063Y521385D01*
Y522775D01*
X1057453Y523385D01*
X1055551D01*
X1054747Y524189D01*
Y525796D01*
X1055957Y527006D01*
Y530643D01*
X1055553Y531047D01*
Y535453D01*
X1055964Y535864D01*
Y538064D01*
X1056600Y538700D01*
Y543800D01*
X1059387Y546587D01*
Y549087D01*
X1059500Y549200D01*
Y553934D01*
X1059291Y554143D01*
Y556652D01*
X1060594Y557955D01*
X1062686D01*
X1064371Y559640D01*
Y566822D01*
G01X1033800Y406734D02*
Y489158D01*
X1035844Y491202D01*
Y493144D01*
X1033800Y495188D01*
Y496302D01*
X1035129Y497631D01*
X1036079D01*
X1038439Y495271D01*
X1039571D01*
X1040702Y496402D01*
Y497534D01*
X1038322Y499914D01*
Y500622D01*
X1039877Y502177D01*
X1040585D01*
X1042965Y499797D01*
X1044097D01*
X1045228Y500928D01*
Y502060D01*
X1042759Y504529D01*
Y505661D01*
X1045100Y508002D01*
Y510500D01*
X1046606Y512006D01*
Y513594D01*
X1044941Y515259D01*
Y517681D01*
X1045922Y518662D01*
Y529724D01*
X1046193Y529995D01*
Y532707D01*
X1045929Y532971D01*
Y546961D01*
X1045837Y547053D01*
Y549063D01*
X1047637Y550863D01*
Y555842D01*
G01X1043800Y406684D02*
Y480353D01*
X1049744Y486297D01*
Y491295D01*
X1051185Y492736D01*
X1052048D01*
X1053656Y491128D01*
X1054497D01*
X1055481Y492112D01*
Y492994D01*
X1053893Y494582D01*
Y495444D01*
X1063100Y504651D01*
Y510800D01*
X1062500Y511400D01*
Y514200D01*
X1062900Y514600D01*
Y516100D01*
X1062500Y516500D01*
Y527700D01*
X1062737Y527937D01*
Y530363D01*
X1062500Y530600D01*
Y532700D01*
X1062634Y532834D01*
Y543499D01*
X1064371Y545236D01*
Y547922D01*
G01X1037800Y406629D02*
Y487840D01*
X1050900Y500940D01*
Y502301D01*
X1049228Y503973D01*
Y506215D01*
X1052400Y509387D01*
Y511300D01*
X1052900Y511800D01*
Y513800D01*
X1052300Y514400D01*
Y516200D01*
X1053000Y516900D01*
Y519300D01*
X1052658Y519642D01*
Y535258D01*
X1052700Y535300D01*
Y543200D01*
X1055949Y546449D01*
Y552670D01*
X1057677Y554398D01*
Y555842D01*
G01X1014398Y408465D02*
Y498700D01*
X1013537Y499561D01*
X1010839D01*
X1009708Y500692D01*
Y501824D01*
X1010826Y502942D01*
Y504074D01*
X1009695Y505205D01*
X1008563D01*
X1007686Y504328D01*
X1006072D01*
X1004532Y505868D01*
Y510858D01*
X1005680Y512006D01*
Y513464D01*
X1005043Y514101D01*
Y516599D01*
X1006300Y517856D01*
Y520250D01*
X1005564Y520986D01*
Y523894D01*
X1006300Y524630D01*
Y527400D01*
X1005769Y527931D01*
Y530469D01*
X1005350Y530888D01*
Y535890D01*
X1005762Y536302D01*
Y542838D01*
X1002500Y546100D01*
Y551800D01*
X1003763Y553063D01*
Y555486D01*
X1004134Y555857D01*
G01X1016398Y408694D02*
Y500114D01*
X1014844Y501668D01*
Y505929D01*
X1013713Y507060D01*
X1007382D01*
X1006678Y507764D01*
Y510678D01*
X1007327Y511327D01*
Y514114D01*
X1006852Y514589D01*
Y515858D01*
X1008300Y517306D01*
Y526900D01*
X1009400Y528000D01*
Y539268D01*
X1008600Y540068D01*
Y542377D01*
X1004133Y546844D01*
Y547922D01*
G01X1012398Y408331D02*
Y494801D01*
X1002800Y504399D01*
Y511100D01*
X1001779Y512121D01*
Y513379D01*
X1002727Y514327D01*
Y516173D01*
X1002300Y516600D01*
Y519800D01*
X1002513Y520013D01*
Y539339D01*
X1001300Y540552D01*
Y544100D01*
X999062Y546338D01*
Y549262D01*
X1000183Y550383D01*
Y553119D01*
X1000787Y553723D01*
Y555857D01*
G01X1010398Y408385D02*
Y493972D01*
X998000Y506370D01*
Y510300D01*
X999400Y511700D01*
Y513700D01*
X998800Y514300D01*
Y516000D01*
X999400Y516600D01*
Y519000D01*
X999164Y519236D01*
Y533036D01*
X998900Y533300D01*
Y535800D01*
X999046Y535946D01*
Y543454D01*
X997441Y545059D01*
Y547922D01*
G01X1008398Y408586D02*
Y493252D01*
X1007043Y494607D01*
X1005671D01*
X1004419Y493355D01*
X1003187D01*
X1002056Y494486D01*
Y495518D01*
X1003473Y496935D01*
Y498067D01*
X1002342Y499198D01*
X1001210D01*
X1000059Y498047D01*
X998955D01*
X997824Y499178D01*
Y500338D01*
X998767Y501281D01*
Y502773D01*
X996000Y505540D01*
Y510780D01*
X995008Y511772D01*
Y513408D01*
X996104Y514504D01*
Y516420D01*
X995185Y517339D01*
Y520157D01*
X995726Y520698D01*
Y530374D01*
X995500Y530600D01*
Y532900D01*
X995800Y533200D01*
Y543800D01*
X994094Y545506D01*
Y547922D01*
G01X1006398Y407982D02*
Y487272D01*
X994000Y499670D01*
Y507662D01*
X992303Y509359D01*
Y511303D01*
X992559Y511559D01*
Y513841D01*
X992260Y514140D01*
Y516560D01*
X992559Y516859D01*
Y519241D01*
X992400Y519400D01*
Y530400D01*
X992700Y530700D01*
Y533100D01*
X992133Y533667D01*
Y535533D01*
X992473Y535873D01*
Y551954D01*
X994094Y553575D01*
Y555857D01*
G01X1002398Y407700D02*
Y485612D01*
X1001403Y486607D01*
X999593D01*
X998235Y487965D01*
Y489775D01*
X996877Y491133D01*
X995067D01*
X993709Y492491D01*
Y494301D01*
X988137Y499873D01*
X986391D01*
X985656Y500608D01*
Y502666D01*
X986300Y503310D01*
X988538D01*
X989338Y504110D01*
Y505710D01*
X988538Y506510D01*
X986300D01*
X985500Y507310D01*
Y511300D01*
X985974Y511774D01*
Y513726D01*
X985500Y514200D01*
Y516500D01*
X985900Y516900D01*
Y527700D01*
X985676Y527924D01*
Y530476D01*
X985764Y530564D01*
Y546277D01*
X987401Y547914D01*
G01X1004398Y407727D02*
Y486442D01*
X992000Y498840D01*
Y506833D01*
X989300Y509533D01*
Y511500D01*
X988800Y512000D01*
Y513800D01*
X989400Y514400D01*
Y516500D01*
X988948Y516952D01*
Y527848D01*
X989115Y528015D01*
Y530485D01*
X988947Y530653D01*
Y532747D01*
X989026Y532826D01*
Y551926D01*
X990748Y553648D01*
Y555857D01*
G01X1031800Y407043D02*
Y496600D01*
X1037600Y502400D01*
Y503600D01*
X1042490Y508490D01*
Y548792D01*
X1044290Y550592D01*
G01X977362Y547914D02*
Y552462D01*
X979079Y554179D01*
Y570421D01*
X977362Y572138D01*
Y574757D01*
G01X974015Y555857D02*
Y566814D01*
G01X1004134Y555857D02*
Y566821D01*
X1004133Y566822D01*
G01Y547922D02*
X1004134Y547923D01*
Y550592D01*
X1005379Y551837D01*
Y554563D01*
X1005813Y554997D01*
Y568343D01*
X1004134Y570022D01*
Y574757D01*
G01X1000787Y555857D02*
Y566822D01*
G01X997441Y547922D02*
Y550592D01*
X998300Y551451D01*
Y553800D01*
X999164Y554664D01*
Y570040D01*
X997441Y571763D01*
Y574757D01*
G01X994094Y547922D02*
Y550074D01*
X995711Y551691D01*
Y557220D01*
X997257Y558766D01*
Y563773D01*
X995711Y565319D01*
Y568753D01*
X994094Y570370D01*
Y574757D01*
G01Y555857D02*
Y557536D01*
X993484Y558146D01*
X989987D01*
X989441Y558692D01*
Y559682D01*
X990115Y560356D01*
X994979D01*
X995547Y560924D01*
Y561914D01*
X994895Y562566D01*
X990221D01*
X989590Y563197D01*
Y564187D01*
X990179Y564776D01*
X993484D01*
X994094Y565386D01*
Y566822D01*
G01X987401Y547914D02*
Y550499D01*
X985662Y552238D01*
Y552934D01*
X984452Y554144D01*
X983356D01*
X982394Y555106D01*
Y567737D01*
X983516Y568859D01*
X984352D01*
X985931Y570438D01*
Y573287D01*
X987401Y574757D01*
G01X990748Y555857D02*
X989958D01*
X987757Y558058D01*
Y559559D01*
X987147Y560169D01*
X985859D01*
X985227Y560801D01*
Y561791D01*
X985815Y562379D01*
X987147D01*
X987757Y562989D01*
Y564378D01*
X987231Y564904D01*
X986284D01*
X985683Y565505D01*
Y567650D01*
X987976Y569943D01*
Y571427D01*
X988628Y572079D01*
X990671D01*
X991365Y571385D01*
Y567439D01*
X990748Y566822D01*
G01X1054331Y28022D02*
X1054330Y28023D01*
Y32686D01*
X1052668Y34348D01*
Y52582D01*
X1054331Y54245D01*
Y54857D01*
G01X1047522Y195410D02*
Y127668D01*
X1066429Y108761D01*
Y101471D01*
X1073300Y94600D01*
Y92017D01*
X1072296Y91013D01*
Y89035D01*
X1072919Y88412D01*
Y86236D01*
X1072274Y85591D01*
Y76426D01*
X1072684Y76016D01*
Y71532D01*
X1073247Y70969D01*
Y67449D01*
X1072700Y66902D01*
Y58900D01*
X1076026Y55574D01*
Y53674D01*
X1076141Y53559D01*
Y34959D01*
X1081102Y29998D01*
Y28007D01*
G01X1053961Y195531D02*
Y132549D01*
X1079400Y107110D01*
Y102180D01*
X1086300Y95280D01*
Y91400D01*
X1085700Y90800D01*
Y89300D01*
X1086500Y88500D01*
Y86400D01*
X1085600Y85500D01*
Y83500D01*
X1086100Y83000D01*
Y72500D01*
X1085600Y72000D01*
Y70300D01*
X1086400Y69500D01*
Y67500D01*
X1086166Y67266D01*
Y59930D01*
X1089413Y56683D01*
Y49608D01*
X1089421Y49600D01*
Y35079D01*
X1094488Y30012D01*
Y28022D01*
G01X1047637Y28007D02*
Y30236D01*
X1049360Y31959D01*
Y47828D01*
X1047637Y49551D01*
Y52164D01*
X1048427Y52954D01*
Y54052D01*
X1047637Y54842D01*
G01X1057677D02*
X1055958Y53123D01*
Y40149D01*
X1059397Y36710D01*
Y34986D01*
X1059659Y34724D01*
Y29989D01*
X1057677Y28007D01*
G01X1043556Y192984D02*
Y125975D01*
X1060200Y109331D01*
Y101400D01*
X1066396Y95204D01*
Y91912D01*
X1065571Y91087D01*
Y89077D01*
X1066274Y88374D01*
Y86374D01*
X1065789Y85889D01*
Y83711D01*
X1066006Y83494D01*
Y64594D01*
X1066350Y64250D01*
Y58779D01*
X1069452Y55677D01*
Y53748D01*
X1070428Y52772D01*
X1071732D01*
X1072690Y51814D01*
Y34590D01*
X1074409Y32871D01*
Y28007D01*
G01X1050858Y195652D02*
Y129992D01*
X1073300Y107550D01*
Y101100D01*
X1079587Y94813D01*
Y91487D01*
X1079174Y91074D01*
Y88974D01*
X1079605Y88543D01*
Y86105D01*
X1079160Y85660D01*
Y83388D01*
X1079362Y83186D01*
Y72347D01*
X1079074Y72059D01*
Y70159D01*
X1079381Y69852D01*
Y60331D01*
X1082739Y56973D01*
Y53561D01*
X1081321Y52143D01*
Y49779D01*
X1082840Y48260D01*
Y35060D01*
X1087797Y30103D01*
Y28022D01*
G01X1055600Y194366D02*
Y133740D01*
X1081500Y107840D01*
Y102909D01*
X1089060Y95349D01*
Y91740D01*
X1090100Y90700D01*
Y89100D01*
X1088866Y87866D01*
Y86734D01*
X1089900Y85700D01*
Y75100D01*
X1089436Y74636D01*
Y72264D01*
X1089800Y71900D01*
Y70100D01*
X1088900Y69200D01*
Y67500D01*
X1089419Y66981D01*
Y59881D01*
X1092864Y56436D01*
Y53164D01*
X1092300Y52600D01*
Y48970D01*
X1092864Y47607D01*
Y37583D01*
X1094490Y35957D01*
G01X1040124Y192316D02*
Y120974D01*
X1041304Y119794D01*
X1044077D01*
X1044968Y118903D01*
Y117773D01*
X1043963Y116769D01*
Y115639D01*
X1045096Y114506D01*
X1046226D01*
X1047231Y115510D01*
X1048361D01*
X1049494Y114377D01*
Y113247D01*
X1048489Y112243D01*
Y111113D01*
X1049622Y109980D01*
X1050752D01*
X1051640Y110868D01*
X1052807D01*
X1053600Y110075D01*
Y101800D01*
X1059561Y95839D01*
Y91761D01*
X1059152Y91352D01*
Y88796D01*
X1059528Y88420D01*
Y86428D01*
X1058847Y85747D01*
Y82915D01*
X1059401Y82361D01*
Y72408D01*
X1060100Y71709D01*
Y67985D01*
X1059411Y67296D01*
Y59817D01*
X1064371Y54857D01*
G01X1049145Y195507D02*
Y128875D01*
X1068500Y109520D01*
Y102400D01*
X1075300Y95600D01*
Y92199D01*
X1076457Y91042D01*
Y89224D01*
X1075457Y88224D01*
Y86474D01*
X1076571Y85360D01*
Y83135D01*
X1076128Y82692D01*
Y59816D01*
X1081102Y54842D01*
G01X1094488Y54859D02*
Y57812D01*
X1092882Y59418D01*
Y60895D01*
X1093492Y61505D01*
X1094232D01*
X1094842Y62115D01*
Y63505D01*
X1094232Y64115D01*
X1093492D01*
X1092882Y64725D01*
Y67620D01*
X1093492Y68230D01*
X1094190D01*
X1094800Y68840D01*
Y70230D01*
X1094190Y70840D01*
X1093492D01*
X1092882Y71450D01*
Y75166D01*
X1092015Y76033D01*
Y78397D01*
X1092626Y79008D01*
X1094107D01*
X1094717Y79618D01*
Y81008D01*
X1094107Y81618D01*
X1092820D01*
X1092174Y82264D01*
Y85279D01*
X1093470Y86575D01*
Y88177D01*
X1092297Y89350D01*
Y90619D01*
X1094464Y92786D01*
Y96426D01*
X1093414Y97476D01*
X1090124D01*
X1089134Y98466D01*
Y99598D01*
X1090287Y100751D01*
Y101883D01*
X1089156Y103014D01*
X1088024D01*
X1086871Y101861D01*
X1085739D01*
X1084608Y102992D01*
Y104124D01*
X1085761Y105277D01*
Y106409D01*
X1057225Y134945D01*
Y194172D01*
G01X1094488Y46922D02*
X1094786Y47220D01*
Y51946D01*
X1096600Y53760D01*
Y67241D01*
X1096440Y67401D01*
Y98559D01*
X1058763Y136236D01*
Y194050D01*
G01X1064371Y46922D02*
Y46219D01*
X1063401Y45249D01*
X1059143D01*
X1058131Y44237D01*
Y40839D01*
X1058797Y40173D01*
X1060751D01*
X1061251Y40673D01*
Y41628D01*
X1061751Y42128D01*
X1066721D01*
X1067200Y41649D01*
Y39218D01*
X1066296Y38314D01*
X1064987D01*
X1064371Y37698D01*
Y35957D01*
G01X1045357Y192972D02*
Y127004D01*
X1062200Y110161D01*
Y102300D01*
X1069200Y95300D01*
Y91631D01*
X1069757Y91074D01*
Y75359D01*
X1069452Y75054D01*
Y72664D01*
X1069469Y72647D01*
Y71783D01*
X1069157Y71471D01*
Y67459D01*
X1069450Y67166D01*
Y64650D01*
X1068580Y63780D01*
Y60120D01*
X1073858Y54842D01*
X1074409D01*
G01X1052414Y195555D02*
Y131266D01*
X1075300Y108380D01*
Y102100D01*
X1082261Y95139D01*
Y91787D01*
X1082947Y91101D01*
Y88847D01*
X1082579Y88479D01*
Y85969D01*
X1082808Y85740D01*
Y72627D01*
X1081344Y71163D01*
Y68153D01*
X1082827Y66670D01*
Y59827D01*
X1087795Y54859D01*
G01X1044290Y49592D02*
X1045500Y48382D01*
Y46200D01*
X1046100Y45600D01*
Y37765D01*
X1044292Y35957D01*
G01X1071998Y178498D02*
Y145331D01*
X1087419Y129910D01*
Y129118D01*
X1085948Y127647D01*
X1085156D01*
X1082072Y130731D01*
X1081280D01*
X1079770Y129221D01*
Y128429D01*
X1109674Y98525D01*
Y92011D01*
X1108591Y90928D01*
Y86718D01*
X1109941Y85368D01*
Y73341D01*
X1108591Y71991D01*
Y67409D01*
X1109741Y66259D01*
Y65020D01*
X1106600Y61879D01*
Y56231D01*
X1107874Y54957D01*
G01X1110520Y49914D02*
X1108447Y51987D01*
Y53048D01*
X1109941Y54542D01*
Y61942D01*
X1112441Y64442D01*
Y99873D01*
X1089628Y122686D01*
Y123478D01*
X1090849Y124699D01*
X1091641D01*
X1094421Y121919D01*
X1095488D01*
X1096683Y123114D01*
Y124182D01*
X1074498Y146367D01*
Y178501D01*
G01X1090318Y179831D02*
X1090375Y179774D01*
Y171799D01*
X1090985Y171189D01*
X1092140D01*
X1092700Y170629D01*
Y168639D01*
X1092140Y168079D01*
X1090985D01*
X1090375Y167469D01*
Y152325D01*
X1133591Y109109D01*
Y100905D01*
X1132791Y100105D01*
X1131710D01*
X1131150Y99545D01*
Y97465D01*
X1131710Y96905D01*
X1132791D01*
X1133591Y96105D01*
Y92068D01*
X1132641Y91118D01*
Y86418D01*
X1133241Y85818D01*
Y73041D01*
X1132741Y72541D01*
Y66803D01*
X1133541Y66003D01*
Y57819D01*
X1131299Y55577D01*
Y54957D01*
G01X1092818Y179831D02*
X1092875Y179774D01*
Y176219D01*
X1095578Y173516D01*
Y165039D01*
X1092875Y162336D01*
Y153425D01*
X1136091Y110209D01*
Y91668D01*
X1136741Y91018D01*
Y86618D01*
X1136041Y85918D01*
Y73059D01*
X1136641Y72459D01*
Y67053D01*
X1136091Y66503D01*
Y56768D01*
X1132741Y53418D01*
Y51818D01*
X1134645Y49914D01*
G01X1067274Y178774D02*
Y142494D01*
X1074718Y135050D01*
Y134040D01*
X1073465Y132787D01*
X1072455D01*
X1071567Y133675D01*
X1070775D01*
X1069435Y132335D01*
Y131543D01*
X1103600Y97378D01*
Y96600D01*
X1102300Y95300D01*
Y94600D01*
X1103600Y93300D01*
Y92577D01*
X1102241Y91218D01*
Y86418D01*
X1103241Y85418D01*
Y73103D01*
X1102241Y72103D01*
Y67159D01*
X1102981Y66419D01*
Y64482D01*
X1101181Y62682D01*
Y54957D01*
G01X1069498Y178501D02*
Y144295D01*
X1078600Y135193D01*
Y133935D01*
X1075400Y130735D01*
Y129264D01*
X1106074Y98590D01*
Y91105D01*
X1106077Y91102D01*
Y89871D01*
X1106091Y89857D01*
Y86468D01*
X1105741Y86118D01*
Y73203D01*
X1106091Y72853D01*
Y66653D01*
X1106074Y66636D01*
Y64475D01*
X1103900Y62301D01*
Y54701D01*
X1102377Y53178D01*
Y51414D01*
X1104227Y49564D01*
G01X1085306Y179831D02*
Y150195D01*
X1108046Y127455D01*
Y126324D01*
X1107377Y125655D01*
Y124525D01*
X1108510Y123392D01*
X1110409D01*
X1111903Y121898D01*
Y119999D01*
X1113036Y118866D01*
X1114166D01*
X1114835Y119536D01*
X1115965D01*
X1117098Y118403D01*
Y117272D01*
X1116429Y116603D01*
Y115473D01*
X1117562Y114340D01*
X1118692D01*
X1119361Y115010D01*
X1120491D01*
X1121624Y113877D01*
Y112746D01*
X1120955Y112077D01*
Y110947D01*
X1122088Y109814D01*
X1123218D01*
X1123887Y110484D01*
X1125017D01*
X1125500Y110001D01*
Y94600D01*
X1126441Y93659D01*
Y91618D01*
X1126041Y91218D01*
Y86518D01*
X1126841Y85718D01*
Y73341D01*
X1126041Y72541D01*
Y66903D01*
X1126406Y66538D01*
Y64306D01*
X1125600Y63500D01*
Y61700D01*
X1126406Y60894D01*
Y59407D01*
X1123847Y56848D01*
Y55716D01*
X1124606Y54957D01*
G01X1087818Y179831D02*
X1087875Y179774D01*
Y151226D01*
X1129200Y109901D01*
Y108300D01*
X1128000Y107100D01*
Y96000D01*
X1129499Y94501D01*
Y91660D01*
X1130141Y91018D01*
Y86518D01*
X1129341Y85718D01*
Y73059D01*
X1130241Y72159D01*
Y67253D01*
X1129499Y66511D01*
Y57640D01*
X1127591Y55732D01*
Y55160D01*
X1126041Y53610D01*
Y51825D01*
X1127952Y49914D01*
G01X1078389Y179041D02*
Y176959D01*
X1078889Y176459D01*
Y175459D01*
X1078389Y174959D01*
Y147683D01*
X1100380Y125692D01*
Y122350D01*
X1101581Y121149D01*
Y121146D01*
X1102780Y119947D01*
Y116537D01*
X1105051Y114266D01*
X1108033D01*
X1109994Y112305D01*
Y110202D01*
X1108776Y108984D01*
Y107752D01*
X1110543Y105985D01*
X1111774D01*
X1113204Y107415D01*
X1115315D01*
X1117708Y105022D01*
Y102912D01*
X1116276Y101481D01*
Y99396D01*
X1117421Y98251D01*
Y82820D01*
X1118041Y82200D01*
Y81200D01*
X1117421Y80580D01*
Y79820D01*
X1118041Y79200D01*
Y78200D01*
X1117421Y77580D01*
Y76820D01*
X1118041Y76200D01*
Y75200D01*
X1117420Y74579D01*
Y63488D01*
X1113546Y59614D01*
Y57420D01*
X1114266Y56700D01*
X1115266D01*
X1116066Y55900D01*
Y53826D01*
X1114340Y52100D01*
G01X1081667Y179495D02*
Y177155D01*
X1081167Y176655D01*
Y175655D01*
X1081667Y175155D01*
Y173906D01*
X1081167Y173406D01*
Y172406D01*
X1081667Y171906D01*
Y148465D01*
X1103520Y126612D01*
Y123174D01*
X1121461Y105233D01*
Y63194D01*
X1117686Y59419D01*
Y51468D01*
X1119440Y49714D01*
G01X1077329Y179041D02*
Y147243D01*
X1099320Y125252D01*
Y121910D01*
X1100830Y120400D01*
Y120397D01*
X1101720Y119507D01*
Y116097D01*
X1104611Y113206D01*
X1107593D01*
X1108934Y111865D01*
Y110642D01*
X1107716Y109424D01*
Y107312D01*
X1110103Y104925D01*
X1112217D01*
X1113647Y106355D01*
X1114872D01*
X1116648Y104579D01*
Y103356D01*
X1115216Y101924D01*
Y98953D01*
X1116360Y97809D01*
Y63931D01*
X1112486Y60057D01*
Y51354D01*
X1114340Y49500D01*
G01X1082727Y179495D02*
Y148905D01*
X1104580Y127052D01*
Y123617D01*
X1122521Y105676D01*
Y77120D01*
X1123141Y76500D01*
Y75500D01*
X1122521Y74880D01*
Y62751D01*
X1121627Y61857D01*
Y60981D01*
X1120919Y60273D01*
X1120043D01*
X1118746Y58976D01*
Y57554D01*
X1119500Y56800D01*
X1120700D01*
X1121266Y56234D01*
Y54140D01*
X1119440Y52314D01*
G01X1144685Y17157D02*
Y24786D01*
X1146552Y26653D01*
Y28447D01*
X1145402Y29597D01*
Y34203D01*
X1146752Y35553D01*
Y47564D01*
X1145402Y48914D01*
Y53102D01*
X1146752Y54452D01*
Y66047D01*
X1145402Y67397D01*
Y72103D01*
X1146752Y73453D01*
Y85364D01*
X1145402Y86714D01*
Y90914D01*
X1146752Y92264D01*
Y104796D01*
X1145374Y106174D01*
Y110374D01*
X1146700Y111700D01*
Y113472D01*
X1130703Y129469D01*
Y130601D01*
X1133335Y133233D01*
Y134365D01*
X1132204Y135496D01*
X1131072D01*
X1129934Y134358D01*
X1129142D01*
X1127560Y135940D01*
Y136732D01*
X1128698Y137870D01*
Y139002D01*
X1127567Y140133D01*
X1126435D01*
X1124497Y138195D01*
X1123705D01*
X1122046Y139854D01*
Y140646D01*
X1124078Y142678D01*
Y143810D01*
X1104300Y163588D01*
Y184800D01*
G01X1147331Y12114D02*
X1145469Y13976D01*
Y15369D01*
X1146792Y16692D01*
Y23393D01*
X1149252Y25853D01*
Y114456D01*
X1140000Y123708D01*
Y125600D01*
X1142300Y127900D01*
Y129124D01*
X1141014Y130410D01*
X1139290D01*
X1137619Y132081D01*
Y133805D01*
X1106800Y164624D01*
Y184900D01*
G01X1137992Y17157D02*
Y25256D01*
X1139952Y27216D01*
Y28447D01*
X1139052Y29347D01*
Y34299D01*
X1140052Y35299D01*
Y47614D01*
X1139052Y48614D01*
Y53414D01*
X1139952Y54314D01*
Y66247D01*
X1139052Y67147D01*
Y72099D01*
X1140052Y73099D01*
Y85414D01*
X1139052Y86414D01*
Y91214D01*
X1140100Y92262D01*
Y105200D01*
X1139000Y106300D01*
Y110300D01*
X1140100Y111400D01*
Y113200D01*
X1138400Y114900D01*
X1138200D01*
X1109800Y143300D01*
Y144898D01*
X1112293Y147391D01*
Y148523D01*
X1111018Y149798D01*
X1109886D01*
X1108240Y148152D01*
X1107448D01*
X1105977Y149623D01*
Y150415D01*
X1107623Y152061D01*
Y153193D01*
X1106492Y154324D01*
X1105360D01*
X1103914Y152878D01*
X1103122D01*
X1101651Y154349D01*
Y155141D01*
X1103097Y156587D01*
Y157719D01*
X1099300Y161516D01*
Y183700D01*
G01X1141038Y12114D02*
X1139052Y14100D01*
Y15514D01*
X1140800Y17262D01*
Y24368D01*
X1142885Y26453D01*
Y28832D01*
X1142902Y28849D01*
Y35049D01*
X1142552Y35399D01*
Y48314D01*
X1142902Y48664D01*
Y53614D01*
X1142652Y53864D01*
Y66399D01*
X1142902Y66649D01*
Y72849D01*
X1142552Y73199D01*
Y86114D01*
X1142838Y86400D01*
Y91478D01*
X1142735Y91581D01*
Y105961D01*
X1142900Y106126D01*
Y111000D01*
X1142600Y111300D01*
Y114036D01*
X1118000Y138636D01*
Y140136D01*
X1120432Y142568D01*
Y143920D01*
X1119224Y145128D01*
X1118092D01*
X1116628Y143664D01*
X1115836D01*
X1114365Y145135D01*
Y145927D01*
X1115829Y147391D01*
Y148523D01*
X1101800Y162552D01*
Y184000D01*
G01X1049800Y407615D02*
Y478476D01*
X1061830Y490506D01*
Y494894D01*
X1072255Y505319D01*
Y511255D01*
X1073200Y512200D01*
Y513700D01*
X1072500Y514400D01*
Y516300D01*
X1073000Y516800D01*
Y519300D01*
X1072700Y519600D01*
Y530400D01*
X1073100Y530800D01*
Y535190D01*
X1072684Y535606D01*
Y543384D01*
X1076136Y546836D01*
Y548964D01*
X1075700Y549400D01*
Y551244D01*
X1079479Y555023D01*
Y565184D01*
X1081102Y566807D01*
G01X1057800Y405358D02*
Y475826D01*
X1069830Y487856D01*
Y491578D01*
X1085936Y507684D01*
Y511336D01*
X1086300Y511700D01*
Y514000D01*
X1085900Y514400D01*
Y516500D01*
X1086300Y516900D01*
Y519500D01*
X1086127Y519673D01*
Y532873D01*
X1086083Y532917D01*
Y543483D01*
X1089418Y546818D01*
Y551418D01*
X1092856Y554856D01*
Y557244D01*
X1092700Y557400D01*
Y565034D01*
X1094488Y566822D01*
G01X1063800Y406826D02*
Y473230D01*
X1096405Y505835D01*
Y510895D01*
X1095500Y511800D01*
Y513600D01*
X1096405Y514505D01*
Y519750D01*
X1096093Y520062D01*
Y530307D01*
X1096178Y530392D01*
Y538778D01*
X1096600Y539200D01*
Y548500D01*
X1095400Y549700D01*
Y551200D01*
X1096400Y552200D01*
Y557300D01*
X1096750Y557650D01*
Y567450D01*
X1094488Y569712D01*
Y574755D01*
X1094490Y574757D01*
G01X1041800Y406612D02*
Y486180D01*
X1042510Y486890D01*
X1043642D01*
X1045350Y485182D01*
X1046482D01*
X1047613Y486313D01*
Y487445D01*
X1045905Y489153D01*
Y490285D01*
X1056575Y500955D01*
Y502087D01*
X1056051Y502611D01*
Y503985D01*
X1057244Y505178D01*
X1059129D01*
X1060407Y506456D01*
Y508183D01*
X1059189Y509401D01*
Y511089D01*
X1059600Y511500D01*
Y513700D01*
X1059100Y514200D01*
Y516600D01*
X1059800Y517300D01*
Y526800D01*
X1059387Y527213D01*
Y530487D01*
X1059600Y530700D01*
Y535600D01*
X1059401Y535799D01*
Y543601D01*
X1062708Y546908D01*
Y554194D01*
X1064371Y555857D01*
G01X1051800Y407687D02*
Y477868D01*
X1063830Y489898D01*
Y494065D01*
X1076500Y506735D01*
Y510850D01*
X1075520Y511830D01*
Y513090D01*
X1076951Y514521D01*
Y516149D01*
X1075328Y517772D01*
Y521440D01*
X1076122Y522234D01*
Y530451D01*
X1076620Y530949D01*
Y534647D01*
X1076122Y535145D01*
Y543922D01*
X1079384Y547184D01*
Y551446D01*
X1081102Y553164D01*
Y555842D01*
G01X1059800Y405805D02*
Y475109D01*
X1071830Y487139D01*
Y490749D01*
X1089980Y508899D01*
Y510920D01*
X1088881Y512019D01*
Y513381D01*
X1089900Y514400D01*
Y516200D01*
X1089418Y516682D01*
Y530682D01*
X1089403Y530697D01*
Y543303D01*
X1092871Y546771D01*
Y551547D01*
X1094488Y553164D01*
Y555859D01*
G01X1061800Y406100D02*
Y473892D01*
X1092200Y504292D01*
Y510900D01*
X1092941Y511641D01*
Y513859D01*
X1092688Y514112D01*
Y516688D01*
X1092941Y516941D01*
Y519459D01*
X1092848Y519552D01*
Y530548D01*
X1092871Y530571D01*
Y543771D01*
X1094488Y545388D01*
Y547922D01*
G01X1073816Y418511D02*
Y462094D01*
X1076616Y464894D01*
Y466023D01*
X1075739Y466900D01*
Y468004D01*
X1076872Y469137D01*
X1078029D01*
X1078879Y468287D01*
X1080009D01*
X1081142Y469420D01*
Y470549D01*
X1079973Y471718D01*
Y472848D01*
X1081106Y473981D01*
X1082237D01*
X1083405Y472813D01*
X1084535D01*
X1107322Y495600D01*
Y507022D01*
X1109941Y509641D01*
Y510707D01*
X1108591Y512057D01*
Y516307D01*
X1109741Y517457D01*
Y519000D01*
X1108701Y520040D01*
Y526801D01*
X1109741Y527841D01*
Y529459D01*
X1108641Y530559D01*
Y535341D01*
X1109791Y536491D01*
Y538000D01*
X1108410Y539381D01*
Y545610D01*
X1109791Y546991D01*
Y548657D01*
X1106441Y552007D01*
Y554524D01*
X1107874Y555957D01*
G01X1076316Y418521D02*
Y461051D01*
X1111244Y495979D01*
Y500851D01*
X1111804Y501411D01*
X1111829D01*
X1112439Y502021D01*
Y503411D01*
X1111829Y504021D01*
X1110080D01*
X1109470Y504631D01*
Y505750D01*
X1110030Y506310D01*
X1110950D01*
X1111511Y506871D01*
Y507911D01*
X1112441Y508841D01*
Y518738D01*
X1114058Y520355D01*
Y521431D01*
X1113448Y522041D01*
X1111459D01*
X1110876Y522624D01*
Y524014D01*
X1111513Y524651D01*
X1113448D01*
X1114058Y525261D01*
Y526454D01*
X1112441Y528071D01*
Y537740D01*
X1114138Y539437D01*
Y540471D01*
X1113528Y541081D01*
X1111221D01*
X1110611Y541691D01*
Y543081D01*
X1111221Y543691D01*
X1113528D01*
X1114138Y544301D01*
Y545462D01*
X1112441Y547159D01*
Y548643D01*
X1110520Y550564D01*
Y550914D01*
G01X1091426Y410424D02*
Y453250D01*
X1115088Y476912D01*
Y479788D01*
X1131800Y496500D01*
Y507400D01*
X1133018Y508618D01*
Y511282D01*
X1132805Y511495D01*
Y517121D01*
X1133203Y517519D01*
Y529595D01*
X1132441Y530357D01*
Y535342D01*
X1133071Y535972D01*
Y548977D01*
X1129941Y552107D01*
Y554599D01*
X1131299Y555957D01*
G01X1093926Y409681D02*
Y452214D01*
X1122225Y480513D01*
Y481375D01*
X1121237Y482363D01*
Y483225D01*
X1122221Y484209D01*
X1123083D01*
X1124071Y483221D01*
X1124933D01*
X1125917Y484205D01*
Y485067D01*
X1124929Y486055D01*
Y486917D01*
X1125913Y487901D01*
X1126775D01*
X1127763Y486913D01*
X1128625D01*
X1129609Y487897D01*
Y488759D01*
X1128750Y489618D01*
Y490326D01*
X1129888Y491464D01*
X1130596D01*
X1131455Y490605D01*
X1132317D01*
X1134300Y492588D01*
Y501500D01*
X1136041Y503241D01*
Y511041D01*
X1136641Y511641D01*
Y516807D01*
X1135700Y517748D01*
Y519401D01*
X1136300Y520001D01*
Y527900D01*
X1136091Y528109D01*
Y529619D01*
X1136941Y530469D01*
Y535258D01*
X1135941Y536258D01*
Y537540D01*
X1136300Y537899D01*
Y546400D01*
X1135941Y546759D01*
Y549670D01*
X1134645Y550966D01*
Y550914D01*
G01X1068816Y417842D02*
Y469042D01*
X1102982Y503208D01*
Y511016D01*
X1102241Y511757D01*
Y516507D01*
X1103141Y517407D01*
Y529359D01*
X1102310Y530190D01*
Y535361D01*
X1103091Y536142D01*
Y548657D01*
X1100639Y551109D01*
Y555415D01*
X1101181Y555957D01*
G01X1071316Y418081D02*
Y468093D01*
X1081487Y478264D01*
X1082619D01*
X1083837Y477046D01*
X1085069D01*
X1086100Y478077D01*
Y479309D01*
X1084882Y480527D01*
Y481659D01*
X1085976Y482753D01*
X1087108D01*
X1088492Y481369D01*
X1089491D01*
X1105100Y496978D01*
Y510800D01*
X1106091Y511791D01*
Y517207D01*
X1105841Y517457D01*
Y519100D01*
X1106200Y519459D01*
Y527300D01*
X1105841Y527659D01*
Y530197D01*
X1106341Y530697D01*
Y534856D01*
X1105741Y535456D01*
Y537600D01*
X1106200Y538059D01*
Y546500D01*
X1105741Y546959D01*
Y549400D01*
X1104227Y550914D01*
G01X1086416Y411022D02*
Y456780D01*
X1126600Y496964D01*
Y511000D01*
X1125600Y512000D01*
Y516100D01*
X1127000Y517500D01*
Y519141D01*
X1126300Y519841D01*
Y527800D01*
X1126784Y528284D01*
Y529416D01*
X1125200Y531000D01*
Y535101D01*
X1126841Y536742D01*
Y537700D01*
X1126275Y538266D01*
Y546475D01*
X1126841Y547041D01*
Y548821D01*
X1123941Y551721D01*
Y555292D01*
X1124606Y555957D01*
G01X1088916Y411535D02*
Y456516D01*
X1095354Y462954D01*
X1096216D01*
X1096854Y462316D01*
X1097716D01*
X1099117Y463717D01*
Y464579D01*
X1098479Y465217D01*
Y466079D01*
X1099880Y467480D01*
X1100742D01*
X1101380Y466842D01*
X1102242D01*
X1103643Y468243D01*
Y469105D01*
X1103005Y469743D01*
Y470605D01*
X1104406Y472006D01*
X1105268D01*
X1105906Y471368D01*
X1106768D01*
X1108169Y472769D01*
Y473631D01*
X1107531Y474269D01*
Y475131D01*
X1108932Y476532D01*
X1109794D01*
X1110432Y475894D01*
X1111294D01*
X1112695Y477295D01*
Y478157D01*
X1112057Y478795D01*
Y479657D01*
X1129100Y496700D01*
Y511016D01*
X1130500Y512416D01*
Y516000D01*
X1129000Y517500D01*
Y519359D01*
X1130000Y520359D01*
Y522200D01*
X1128800Y523400D01*
Y525100D01*
X1129900Y526200D01*
Y527500D01*
X1129441Y527959D01*
Y529655D01*
X1130007Y530221D01*
Y535493D01*
X1129341Y536159D01*
Y537740D01*
X1130000Y538399D01*
Y540100D01*
X1128934Y541166D01*
Y543534D01*
X1130000Y544600D01*
Y546400D01*
X1129341Y547059D01*
Y549568D01*
X1129298D01*
X1127952Y550914D01*
G01X1080341Y419187D02*
Y459869D01*
X1115197Y494725D01*
Y506565D01*
X1117421Y508789D01*
Y550020D01*
X1114341Y553100D01*
G01X1082731Y419537D02*
Y458302D01*
X1111500Y487071D01*
Y487949D01*
X1112208Y488656D01*
X1113085D01*
X1113792Y489363D01*
Y490241D01*
X1114499Y490948D01*
X1115377D01*
X1117081Y492652D01*
Y495079D01*
X1118579Y496577D01*
X1120648D01*
X1121520Y497449D01*
Y499145D01*
X1120648Y500017D01*
X1118857D01*
X1117474Y501400D01*
Y504782D01*
X1118922Y506230D01*
X1120860D01*
X1121661Y507031D01*
Y508840D01*
X1121041Y509460D01*
Y510460D01*
X1121661Y511080D01*
Y512496D01*
X1121187Y512970D01*
Y513970D01*
X1121661Y514444D01*
Y515604D01*
X1121108Y516157D01*
Y517157D01*
X1121661Y517710D01*
Y518934D01*
X1121041Y519554D01*
Y520554D01*
X1121661Y521174D01*
Y522174D01*
X1121041Y522794D01*
Y523794D01*
X1121661Y524414D01*
Y525414D01*
X1121041Y526034D01*
Y527034D01*
X1121661Y527654D01*
Y529233D01*
X1121041Y529853D01*
Y530853D01*
X1121661Y531473D01*
Y534152D01*
X1121041Y534772D01*
Y535772D01*
X1121661Y536392D01*
Y537947D01*
X1121041Y538567D01*
Y539567D01*
X1121661Y540187D01*
Y541187D01*
X1121041Y541807D01*
Y542807D01*
X1121661Y543427D01*
Y544427D01*
X1121041Y545047D01*
Y546047D01*
X1121661Y546667D01*
Y549594D01*
X1120541Y550714D01*
X1119440D01*
G01X1079281Y419187D02*
Y460309D01*
X1114137Y495165D01*
Y507005D01*
X1116361Y509229D01*
Y538696D01*
X1115896Y539161D01*
Y540161D01*
X1116361Y540626D01*
Y541626D01*
X1115896Y542091D01*
Y543091D01*
X1116361Y543556D01*
Y544556D01*
X1115896Y545021D01*
Y546021D01*
X1116361Y546486D01*
Y549580D01*
X1115441Y550500D01*
X1114340D01*
G01X1083791Y419537D02*
Y457862D01*
X1118141Y492212D01*
Y494639D01*
X1119019Y495517D01*
X1121088D01*
X1122580Y497009D01*
Y499585D01*
X1121088Y501077D01*
X1119297D01*
X1118534Y501840D01*
Y504342D01*
X1119362Y505170D01*
X1121300D01*
X1122721Y506591D01*
Y550034D01*
X1119441Y553314D01*
G01X1074409Y566807D02*
X1072728Y565126D01*
Y555016D01*
X1071539Y553827D01*
X1070289D01*
X1069200Y552738D01*
Y549400D01*
X1069377Y549223D01*
Y546577D01*
X1065998Y543198D01*
Y535698D01*
X1066006Y535690D01*
Y527894D01*
X1066300Y527600D01*
Y516800D01*
X1065900Y516400D01*
Y514500D01*
X1066500Y513900D01*
Y511800D01*
X1065400Y510700D01*
Y504122D01*
X1057700Y496422D01*
Y491534D01*
X1045800Y479634D01*
Y406935D01*
G01X1053800Y407669D02*
Y477262D01*
X1065830Y489292D01*
Y493236D01*
X1078600Y506006D01*
Y510400D01*
X1079600Y511400D01*
Y514100D01*
X1079000Y514700D01*
Y516400D01*
X1079735Y517135D01*
Y519365D01*
X1079397Y519703D01*
Y533103D01*
X1079368Y533132D01*
Y543068D01*
X1082821Y546521D01*
Y548831D01*
X1085333Y551343D01*
Y554033D01*
X1086156Y554856D01*
Y565181D01*
X1087797Y566822D01*
G01X1047800Y407132D02*
Y478968D01*
X1059830Y490998D01*
Y495723D01*
X1069470Y505363D01*
Y511230D01*
X1069102Y511598D01*
Y513902D01*
X1069543Y514343D01*
Y516557D01*
X1069163Y516937D01*
Y527563D01*
X1069437Y527837D01*
Y529963D01*
X1069200Y530200D01*
Y535326D01*
X1069437Y535563D01*
Y543637D01*
X1072698Y546898D01*
Y548898D01*
X1073600Y549800D01*
Y552453D01*
X1074409Y553262D01*
Y555842D01*
G01X1055800Y405734D02*
Y476600D01*
X1067830Y488630D01*
Y492407D01*
X1082888Y507465D01*
Y511112D01*
X1082500Y511500D01*
Y513900D01*
X1082972Y514372D01*
Y516728D01*
X1082524Y517176D01*
Y519424D01*
X1082821Y519721D01*
Y530179D01*
X1081381Y531619D01*
Y534373D01*
X1082835Y535827D01*
Y543535D01*
X1086112Y546812D01*
Y549112D01*
X1087795Y550795D01*
Y555859D01*
G01X1054331Y555857D02*
Y566822D01*
G01X1047637Y555842D02*
Y566807D01*
G01X1064371Y547922D02*
X1065984Y549535D01*
Y571016D01*
X1064369Y572631D01*
X1064371Y572633D01*
Y574757D01*
G01X1057677Y555842D02*
X1056791D01*
X1055981Y556652D01*
Y561287D01*
X1056757Y562063D01*
X1057719D01*
X1058276Y561506D01*
Y560251D01*
X1058886Y559641D01*
X1061490D01*
X1062131Y560282D01*
Y563720D01*
X1061417Y564434D01*
X1056698D01*
X1056088Y565044D01*
Y566132D01*
X1056763Y566807D01*
X1057677D01*
G01X1044290Y550592D02*
Y553090D01*
X1046003Y554803D01*
Y557197D01*
X1045400Y557800D01*
Y567800D01*
X1046300Y568700D01*
Y570300D01*
X1044290Y572310D01*
Y574755D01*
X1044292Y574757D01*
G01X1107874Y27899D02*
Y30021D01*
X1109753Y31900D01*
X1111153D01*
X1112609Y33356D01*
Y34700D01*
X1111993Y35316D01*
Y48441D01*
X1110520Y49914D01*
G01X1134645D02*
X1136034Y48525D01*
Y35512D01*
X1136646Y34900D01*
Y33500D01*
X1134846Y31700D01*
X1133846D01*
X1132546Y30400D01*
Y29146D01*
X1131299Y27899D01*
G01X1104227Y49564D02*
X1104237D01*
X1105453Y48348D01*
Y35675D01*
X1106228Y34900D01*
Y33276D01*
X1104652Y31700D01*
X1103428D01*
X1101181Y29453D01*
Y27899D01*
G01X1127952Y49914D02*
X1129341Y48525D01*
Y35512D01*
X1129953Y34900D01*
Y33500D01*
X1128153Y31700D01*
X1127153D01*
X1125853Y30400D01*
Y29146D01*
X1124606Y27899D01*
G01X1114340Y52100D02*
X1117446Y48994D01*
Y32848D01*
X1116118Y31520D01*
X1115136D01*
X1114366Y30750D01*
G01X1114340Y49500D02*
X1115439D01*
X1116386Y48553D01*
Y46020D01*
X1115416Y45050D01*
X1115068D01*
X1114452Y44434D01*
Y43102D01*
X1114954Y42600D01*
X1115666D01*
X1116386Y41880D01*
Y40920D01*
X1115566Y40100D01*
X1115066D01*
X1114466Y39500D01*
Y38500D01*
X1116386Y36580D01*
Y33291D01*
X1115675Y32580D01*
X1115159D01*
X1114340Y33399D01*
G01X1119440Y52314D02*
X1122632Y49122D01*
Y33732D01*
X1119440Y30540D01*
G01X1151152Y14300D02*
X1152878Y16026D01*
Y18100D01*
X1152078Y18900D01*
X1151078D01*
X1150358Y19620D01*
Y20688D01*
X1154232Y24562D01*
Y36580D01*
X1154852Y37200D01*
Y38200D01*
X1154232Y38820D01*
Y39580D01*
X1154852Y40200D01*
Y41200D01*
X1154232Y41820D01*
Y118695D01*
X1154798Y119261D01*
Y121490D01*
X1152523Y123765D01*
X1150298D01*
X1148271Y121738D01*
X1147230D01*
X1145367Y123601D01*
Y124830D01*
X1147478Y126941D01*
Y129154D01*
X1121307Y155325D01*
Y155961D01*
X1120599Y156669D01*
X1119963D01*
X1119256Y157376D01*
Y158012D01*
X1118548Y158720D01*
X1117912D01*
X1116981Y159651D01*
Y160287D01*
X1116273Y160995D01*
X1115637D01*
X1114901Y161731D01*
Y162367D01*
X1114193Y163075D01*
X1113557D01*
X1112514Y164118D01*
Y164754D01*
X1111806Y165462D01*
X1111170D01*
X1110463Y166169D01*
Y170112D01*
X1110913Y170562D01*
Y171562D01*
X1110463Y172012D01*
Y173012D01*
X1110913Y173462D01*
Y174462D01*
X1110463Y174912D01*
Y175912D01*
X1110913Y176362D01*
Y177362D01*
X1110463Y177812D01*
Y178812D01*
X1110913Y179262D01*
Y180262D01*
X1110463Y180712D01*
Y182127D01*
X1110913Y182577D01*
Y183577D01*
X1110463Y184027D01*
Y186124D01*
G01X1156252Y14514D02*
X1158078Y16340D01*
Y17900D01*
X1156058Y19920D01*
Y20788D01*
X1157032Y21762D01*
X1157908D01*
X1158616Y22470D01*
Y23346D01*
X1159497Y24227D01*
Y37080D01*
X1160117Y37700D01*
Y38700D01*
X1159497Y39320D01*
Y113934D01*
X1158680Y114751D01*
Y123352D01*
X1114372Y167660D01*
Y186124D01*
G01X1109403D02*
Y165729D01*
X1146418Y128714D01*
Y127381D01*
X1144307Y125270D01*
Y123161D01*
X1146790Y120678D01*
X1148711D01*
X1150738Y122705D01*
X1152083D01*
X1153738Y121050D01*
Y119704D01*
X1153172Y119138D01*
Y25005D01*
X1149298Y21131D01*
Y13554D01*
X1151152Y11700D01*
G01X1156252Y11914D02*
X1154528Y13638D01*
Y18529D01*
X1154998Y18999D01*
Y21231D01*
X1158437Y24670D01*
Y113491D01*
X1157620Y114308D01*
Y122909D01*
X1113312Y167217D01*
Y186124D01*
G01X1107874Y54957D02*
X1106753Y53836D01*
Y50900D01*
X1109653Y48000D01*
Y46032D01*
X1108120Y44499D01*
Y43300D01*
X1109370Y42050D01*
Y41150D01*
X1108020Y39800D01*
Y38501D01*
X1109653Y36868D01*
Y34567D01*
X1110520Y33700D01*
G01X1131299Y54957D02*
X1130178Y53836D01*
Y50900D01*
X1133520Y47558D01*
Y46500D01*
X1131720Y44700D01*
Y43125D01*
X1132920Y41925D01*
Y40799D01*
X1131720Y39599D01*
Y38226D01*
X1133078Y36868D01*
Y35667D01*
X1134645Y34100D01*
G01X1101181Y54957D02*
X1100253Y54029D01*
Y50901D01*
X1103053Y48101D01*
Y46232D01*
X1101670Y44849D01*
Y43450D01*
X1103120Y42000D01*
Y40800D01*
X1101620Y39300D01*
Y38101D01*
X1103053Y36668D01*
Y34788D01*
X1104141Y33700D01*
G01X1124606Y54957D02*
X1123678Y54029D01*
Y50901D01*
X1126720Y47859D01*
Y46474D01*
X1125045Y44799D01*
Y43676D01*
X1126545Y42176D01*
Y40824D01*
X1125045Y39324D01*
Y38101D01*
X1126478Y36668D01*
Y35574D01*
X1127952Y34100D01*
G01X1119440Y49714D02*
Y49715D01*
X1120538D01*
X1121572Y48681D01*
Y45906D01*
X1120866Y45200D01*
X1120352D01*
X1119652Y44500D01*
Y43500D01*
X1120352Y42800D01*
X1120852D01*
X1121572Y42080D01*
Y40707D01*
X1120765Y39900D01*
X1120067D01*
X1119466Y39299D01*
Y38101D01*
X1120067Y37500D01*
X1120865D01*
X1121572Y36793D01*
Y34172D01*
X1120549Y33149D01*
X1119440D01*
G01X1168110Y17157D02*
X1170352Y19399D01*
Y28199D01*
X1169552Y28999D01*
Y34851D01*
X1170052Y35351D01*
Y39447D01*
X1168600Y40899D01*
Y42647D01*
X1170052Y44099D01*
Y48014D01*
X1169452Y48614D01*
Y53314D01*
X1170402Y54264D01*
Y65949D01*
X1169600Y66751D01*
Y72599D01*
X1170052Y73051D01*
Y85814D01*
X1169452Y86414D01*
Y91114D01*
X1170452Y92114D01*
Y104548D01*
X1168700Y106300D01*
Y110400D01*
X1170074Y111774D01*
Y113774D01*
X1171700Y115400D01*
Y121164D01*
X1164840Y128024D01*
Y129156D01*
X1165526Y129842D01*
Y130974D01*
X1164395Y132105D01*
X1163263D01*
X1162577Y131419D01*
X1161445D01*
X1160314Y132550D01*
Y133682D01*
X1161000Y134368D01*
Y135500D01*
X1159869Y136631D01*
X1158737D01*
X1158051Y135945D01*
X1156919D01*
X1121992Y170872D01*
Y185598D01*
G01X1171456Y12114D02*
X1169552Y14018D01*
Y15614D01*
X1172902Y18964D01*
Y28699D01*
X1173452Y29249D01*
Y34547D01*
X1172852Y35147D01*
Y48114D01*
X1173552Y48814D01*
Y53214D01*
X1172902Y53864D01*
Y66499D01*
X1173452Y67049D01*
Y72447D01*
X1172852Y73047D01*
Y85914D01*
X1173552Y86614D01*
Y91274D01*
X1172900Y91926D01*
Y105600D01*
X1173274Y105974D01*
Y110974D01*
X1172574Y111674D01*
Y112974D01*
X1174200Y114600D01*
Y125900D01*
X1160900Y139200D01*
X1159052D01*
X1124492Y173760D01*
Y186158D01*
G01X1161417Y17157D02*
Y18017D01*
X1163452Y20052D01*
Y28499D01*
X1162852Y29099D01*
Y34751D01*
X1163652Y35551D01*
Y41421D01*
X1162300Y42773D01*
Y44621D01*
X1163652Y45973D01*
Y47914D01*
X1162852Y48714D01*
Y53414D01*
X1163252Y53814D01*
Y59047D01*
X1162100Y60199D01*
Y62247D01*
X1163252Y63399D01*
Y66499D01*
X1162852Y66899D01*
Y72451D01*
X1163652Y73251D01*
Y77684D01*
X1162400Y78936D01*
Y80884D01*
X1163652Y82136D01*
Y85714D01*
X1162852Y86514D01*
Y91214D01*
X1163500Y91862D01*
Y105000D01*
X1162400Y106100D01*
Y110300D01*
X1163500Y111400D01*
Y113100D01*
X1161438Y115162D01*
Y116206D01*
X1162176Y116944D01*
X1164540D01*
X1165100Y117504D01*
Y119584D01*
X1164540Y120144D01*
X1162100D01*
X1161300Y120944D01*
Y122100D01*
X1162100Y122900D01*
Y123692D01*
X1116992Y168800D01*
Y185192D01*
G01X1164763Y12114D02*
X1162852Y14025D01*
Y15692D01*
X1165952Y18792D01*
Y28399D01*
X1167052Y29499D01*
Y34447D01*
X1166152Y35347D01*
Y47914D01*
X1166952Y48714D01*
Y53214D01*
X1166252Y53914D01*
Y66499D01*
X1167052Y67299D01*
Y72047D01*
X1166152Y72947D01*
Y85714D01*
X1166952Y86514D01*
Y91014D01*
X1166000Y91966D01*
Y105400D01*
X1166874Y106274D01*
Y110774D01*
X1166000Y111648D01*
Y113300D01*
X1167000Y114300D01*
Y122328D01*
X1119492Y169836D01*
Y185408D01*
G01X1131900Y195894D02*
X1149764Y178030D01*
X1158490D01*
X1195154Y141366D01*
Y139720D01*
X1192576Y137142D01*
Y136010D01*
X1193707Y134879D01*
X1194839D01*
X1196409Y136449D01*
X1197201D01*
X1198867Y134783D01*
Y133991D01*
X1197300Y132424D01*
Y131286D01*
X1221600Y106986D01*
Y105339D01*
X1220800Y104539D01*
X1219500D01*
X1218700Y103739D01*
Y102139D01*
X1219500Y101339D01*
X1220800D01*
X1221600Y100539D01*
Y98939D01*
X1220800Y98139D01*
X1219500D01*
X1218700Y97339D01*
Y95739D01*
X1220250Y94189D01*
Y92119D01*
X1220246D01*
X1219024Y90897D01*
Y86718D01*
X1220374Y85368D01*
Y73473D01*
X1219024Y72123D01*
Y67394D01*
X1220174Y66244D01*
Y64674D01*
X1218307Y62807D01*
Y54957D01*
G01X1133395Y197065D02*
X1150545Y179915D01*
X1160141D01*
X1201900Y138156D01*
Y133489D01*
X1200833Y132422D01*
Y131289D01*
X1224100Y108022D01*
Y95300D01*
X1222874Y94074D01*
Y64174D01*
X1220374Y61674D01*
Y54574D01*
X1218880Y53080D01*
Y51987D01*
X1220953Y49914D01*
G01X1241732Y54957D02*
Y56133D01*
X1243974Y58375D01*
Y66003D01*
X1243174Y66803D01*
Y72575D01*
X1243674Y73075D01*
Y85818D01*
X1243074Y86418D01*
Y91118D01*
X1243600Y91644D01*
Y96918D01*
X1244450Y97768D01*
Y99848D01*
X1243890Y100408D01*
X1243160D01*
X1242600Y100968D01*
Y103048D01*
X1243160Y103608D01*
X1243690D01*
X1244250Y104168D01*
Y106248D01*
X1243690Y106808D01*
X1243000D01*
X1242200Y107608D01*
Y109208D01*
X1243000Y110008D01*
X1243840D01*
X1244400Y110568D01*
Y112648D01*
X1243840Y113208D01*
X1243000D01*
X1242200Y114008D01*
Y119374D01*
X1170114Y191460D01*
X1161423D01*
X1148018Y204865D01*
G01X1148099Y207450D02*
X1162204Y193345D01*
X1171765D01*
X1246625Y118485D01*
Y91567D01*
X1247174Y91018D01*
Y86618D01*
X1246474Y85918D01*
Y73227D01*
X1247074Y72627D01*
Y67053D01*
X1246524Y66503D01*
Y56768D01*
X1243174Y53418D01*
Y51818D01*
X1245078Y49914D01*
G01X1129160Y193302D02*
X1148202Y174260D01*
X1155188D01*
X1181800Y147648D01*
Y139714D01*
X1187810Y133704D01*
Y132572D01*
X1186685Y131447D01*
Y130315D01*
X1187816Y129184D01*
X1188948D01*
X1190073Y130309D01*
X1191205D01*
X1192336Y129178D01*
Y128046D01*
X1191211Y126921D01*
Y125789D01*
X1192342Y124658D01*
X1193474D01*
X1194599Y125783D01*
X1195731D01*
X1196862Y124652D01*
Y123520D01*
X1195737Y122395D01*
Y121263D01*
X1196868Y120132D01*
X1198000D01*
X1199125Y121257D01*
X1200257D01*
X1201388Y120126D01*
Y118994D01*
X1200263Y117869D01*
Y116737D01*
X1201394Y115606D01*
X1202526D01*
X1203651Y116731D01*
X1204783D01*
X1213414Y108100D01*
Y91958D01*
X1212674Y91218D01*
Y86274D01*
X1213674Y85274D01*
Y73103D01*
X1212674Y72103D01*
Y67127D01*
X1213574Y66227D01*
Y56917D01*
X1211614Y54957D01*
G01X1130493Y194635D02*
X1148983Y176145D01*
X1156839D01*
X1184300Y148684D01*
Y144250D01*
X1187182Y141368D01*
X1187974D01*
X1189086Y142480D01*
X1190218D01*
X1191349Y141349D01*
Y140217D01*
X1188657Y137525D01*
Y136393D01*
X1216000Y109050D01*
Y91942D01*
X1217174Y90768D01*
Y86374D01*
X1216174Y85374D01*
Y73203D01*
X1216524Y72853D01*
Y66653D01*
X1215700Y65829D01*
Y56344D01*
X1212674Y53318D01*
Y51718D01*
X1213624Y50768D01*
X1213806D01*
X1214660Y49914D01*
G01X1145135Y202415D02*
X1159860Y187690D01*
X1166624D01*
X1167400Y186917D01*
X1222400Y132101D01*
Y124376D01*
X1223175Y123601D01*
X1224307D01*
X1225832Y125126D01*
X1226624D01*
X1228095Y123655D01*
Y122863D01*
X1226570Y121338D01*
Y120206D01*
X1227701Y119075D01*
X1228833D01*
X1230808Y121050D01*
X1231600D01*
X1233071Y119579D01*
Y118787D01*
X1231096Y116812D01*
Y115680D01*
X1235600Y111176D01*
Y95474D01*
X1236839Y94235D01*
Y91583D01*
X1236474Y91218D01*
Y86518D01*
X1237274Y85718D01*
Y73375D01*
X1236474Y72575D01*
Y66903D01*
X1236900Y66477D01*
Y59044D01*
X1235039Y57183D01*
Y54957D01*
G01X1145116Y205100D02*
X1160641Y189575D01*
X1168463D01*
X1238100Y119938D01*
Y118299D01*
X1239000Y117399D01*
Y114499D01*
X1238100Y113599D01*
Y111899D01*
X1239900Y110099D01*
Y91692D01*
X1240574Y91018D01*
Y86518D01*
X1239774Y85718D01*
Y73127D01*
X1240200Y72701D01*
Y66779D01*
X1239800Y66379D01*
Y58408D01*
X1238024Y56632D01*
Y55194D01*
X1236474Y53644D01*
Y51825D01*
X1238385Y49914D01*
G01X1136169Y199771D02*
X1136876Y199064D01*
X1137512D01*
X1138220Y198356D01*
Y197720D01*
X1138986Y196954D01*
X1139622D01*
X1140330Y196246D01*
Y195610D01*
X1141037Y194903D01*
X1141673D01*
X1142381Y194195D01*
Y193559D01*
X1143178Y192762D01*
X1143815D01*
X1144523Y192054D01*
Y191417D01*
X1145388Y190552D01*
X1146024D01*
X1146732Y189844D01*
Y189208D01*
X1147439Y188501D01*
X1148075D01*
X1148783Y187793D01*
Y187157D01*
X1149727Y186213D01*
X1150363D01*
X1151071Y185505D01*
Y184869D01*
X1153080Y182860D01*
X1162457D01*
X1208412Y136905D01*
Y134794D01*
X1206001Y132383D01*
Y131256D01*
X1207784Y129473D01*
X1209094D01*
X1211140Y131519D01*
X1213249D01*
X1215637Y129131D01*
Y127019D01*
X1213757Y125139D01*
Y123913D01*
X1227854Y109816D01*
Y96020D01*
X1228474Y95400D01*
Y94400D01*
X1227854Y93780D01*
Y83320D01*
X1228474Y82700D01*
Y81700D01*
X1227854Y81080D01*
Y80320D01*
X1228474Y79700D01*
Y78700D01*
X1227854Y78080D01*
Y77320D01*
X1228474Y76700D01*
Y75700D01*
X1227854Y75080D01*
Y63122D01*
X1223980Y59248D01*
Y57420D01*
X1224700Y56700D01*
X1225700D01*
X1226500Y55900D01*
Y53826D01*
X1224774Y52100D01*
G01X1139260Y203840D02*
X1157295Y185805D01*
X1164912D01*
X1219780Y130937D01*
Y123291D01*
X1221686Y121386D01*
X1232954Y110117D01*
Y71620D01*
X1233574Y71000D01*
Y70000D01*
X1232954Y69380D01*
Y68620D01*
X1233574Y68000D01*
Y67000D01*
X1232954Y66380D01*
Y62382D01*
X1229180Y58608D01*
Y57620D01*
X1230000Y56800D01*
X1231100D01*
X1231700Y56200D01*
Y54140D01*
X1229874Y52314D01*
G01X1135420Y199020D02*
X1152640Y181800D01*
X1162017D01*
X1207352Y136465D01*
Y135234D01*
X1204941Y132823D01*
Y130816D01*
X1207344Y128413D01*
X1209534D01*
X1211580Y130459D01*
X1212809D01*
X1214577Y128691D01*
Y127462D01*
X1212697Y125582D01*
Y123470D01*
X1226794Y109373D01*
Y63565D01*
X1222920Y59691D01*
Y51354D01*
X1224774Y49500D01*
G01X1138511Y203089D02*
X1139232Y202368D01*
Y201731D01*
X1139940Y201023D01*
X1140577D01*
X1141767Y199833D01*
Y199196D01*
X1142475Y198488D01*
X1143112D01*
X1143977Y197623D01*
Y196987D01*
X1144685Y196279D01*
X1145321D01*
X1156855Y184745D01*
X1164472D01*
X1218720Y130497D01*
Y122851D01*
X1219300Y122271D01*
X1220936Y120636D01*
X1224536Y117036D01*
X1225617Y115954D01*
Y115953D01*
X1231894Y109676D01*
Y62825D01*
X1228120Y59051D01*
Y51468D01*
X1229874Y49714D01*
G01X1133640Y423105D02*
Y438040D01*
X1146300Y450700D01*
X1157166D01*
X1179008Y472542D01*
X1203299Y477397D01*
X1220374Y494472D01*
Y510707D01*
X1219024Y512057D01*
Y516307D01*
X1220174Y517457D01*
Y519300D01*
X1220000Y519474D01*
Y527700D01*
X1220174Y527874D01*
Y529444D01*
X1218963Y530655D01*
Y535264D01*
X1220224Y536525D01*
Y537700D01*
X1220000Y537924D01*
Y546800D01*
X1220224Y547024D01*
Y548657D01*
X1217400Y551481D01*
Y555050D01*
X1218307Y555957D01*
G01X1136100Y422864D02*
Y427000D01*
X1137250Y428150D01*
X1157119D01*
X1193096Y464127D01*
Y464989D01*
X1190590Y467495D01*
Y468357D01*
X1191574Y469341D01*
X1192436D01*
X1194942Y466835D01*
X1195804D01*
X1196788Y467819D01*
Y468681D01*
X1194282Y471187D01*
Y472049D01*
X1195266Y473033D01*
X1196128D01*
X1198634Y470527D01*
X1199496D01*
X1222874Y493905D01*
Y519274D01*
X1223400Y519800D01*
Y527200D01*
X1222874Y527726D01*
Y537700D01*
X1223300Y538126D01*
Y546800D01*
X1222874Y547226D01*
Y548643D01*
X1220953Y550564D01*
Y550914D01*
G01X1151589Y414534D02*
X1152355Y415300D01*
X1162663D01*
X1211627Y464264D01*
X1217258D01*
X1243545Y490551D01*
Y511286D01*
X1243174Y511657D01*
Y517057D01*
X1243543Y517426D01*
Y529756D01*
X1242874Y530425D01*
Y535342D01*
X1243650Y536118D01*
Y548831D01*
X1241369Y551112D01*
Y555594D01*
X1241732Y555957D01*
G01X1245078Y550914D02*
X1246374Y549618D01*
Y536526D01*
X1246964Y535936D01*
Y530133D01*
X1246433Y529602D01*
Y517448D01*
X1247074Y516807D01*
Y512257D01*
X1246063Y511246D01*
Y508476D01*
X1246912Y507627D01*
X1248662D01*
X1249272Y507017D01*
Y505627D01*
X1248662Y505017D01*
X1246341D01*
X1245678Y504354D01*
Y502964D01*
X1246235Y502407D01*
X1248662D01*
X1249272Y501797D01*
Y500407D01*
X1248662Y499797D01*
X1246744D01*
X1245744Y498797D01*
Y489516D01*
X1217892Y461664D01*
X1211827D01*
X1162954Y412791D01*
X1153382D01*
G01X1128640Y422710D02*
Y440234D01*
X1143312Y454906D01*
X1154610D01*
X1184525Y484821D01*
X1202705D01*
X1213674Y495790D01*
Y510757D01*
X1212674Y511757D01*
Y516457D01*
X1213574Y517357D01*
Y519200D01*
X1213300Y519474D01*
Y527800D01*
X1213574Y528074D01*
Y529425D01*
X1212526Y530473D01*
Y535144D01*
X1213524Y536142D01*
Y537900D01*
X1213300Y538124D01*
Y546300D01*
X1213524Y546524D01*
Y548657D01*
X1210374Y551807D01*
Y554717D01*
X1211614Y555957D01*
G01X1131140Y423140D02*
Y440068D01*
X1144093Y453021D01*
X1156120D01*
X1185277Y482178D01*
X1192967D01*
X1193577Y481568D01*
Y480022D01*
X1194187Y479412D01*
X1195577D01*
X1196187Y480022D01*
Y481568D01*
X1196797Y482178D01*
X1198187D01*
X1198797Y481568D01*
Y480022D01*
X1199407Y479412D01*
X1200797D01*
X1201407Y480022D01*
Y481568D01*
X1202017Y482178D01*
X1205006D01*
X1216174Y493346D01*
Y510973D01*
X1216600Y511399D01*
Y517131D01*
X1216274Y517457D01*
Y519500D01*
X1216700Y519926D01*
Y527500D01*
X1216274Y527926D01*
Y530197D01*
X1216774Y530697D01*
Y534856D01*
X1216174Y535456D01*
Y537600D01*
X1216600Y538026D01*
Y546600D01*
X1216174Y547026D01*
Y549400D01*
X1215000Y550574D01*
X1214874D01*
G01X1147671Y417688D02*
X1149333Y419350D01*
X1161113D01*
X1211523Y469760D01*
X1216442D01*
X1235429Y488747D01*
Y507309D01*
X1236861Y508741D01*
Y511670D01*
X1236474Y512057D01*
Y516957D01*
X1237074Y517557D01*
Y519500D01*
X1236700Y519874D01*
Y527600D01*
X1237074Y527974D01*
Y529511D01*
X1236001Y530584D01*
Y535169D01*
X1237274Y536442D01*
Y537400D01*
X1236700Y537974D01*
Y546200D01*
X1237274Y546774D01*
Y548557D01*
X1234374Y551457D01*
Y555292D01*
X1235039Y555957D01*
G01X1149521Y416002D02*
X1150919Y417400D01*
X1161963D01*
X1211671Y467108D01*
X1217080D01*
X1239831Y489859D01*
Y496615D01*
X1239221Y497225D01*
X1237842D01*
X1237232Y497835D01*
Y499225D01*
X1237842Y499835D01*
X1239221D01*
X1239831Y500445D01*
Y501835D01*
X1239221Y502445D01*
X1237842D01*
X1237232Y503055D01*
Y504445D01*
X1237842Y505055D01*
X1239221D01*
X1239831Y505665D01*
Y511314D01*
X1240674Y512157D01*
Y516557D01*
X1239574Y517657D01*
Y518688D01*
X1241394Y520508D01*
Y521346D01*
X1240784Y521956D01*
X1239701D01*
X1239091Y522566D01*
Y524546D01*
X1239701Y525156D01*
X1240784D01*
X1241394Y525766D01*
Y526622D01*
X1239874Y528142D01*
Y529633D01*
X1240440Y530199D01*
Y535761D01*
X1239774Y536427D01*
Y537674D01*
X1240100Y538000D01*
Y546500D01*
X1239774Y546826D01*
Y549568D01*
X1239731D01*
X1238385Y550914D01*
G01X1141566Y421696D02*
X1144610Y424740D01*
X1158270D01*
X1227854Y494324D01*
Y550020D01*
X1224774Y553100D01*
G01X1149787Y422405D02*
X1159102D01*
X1211335Y474638D01*
X1216266D01*
X1220288Y478660D01*
Y480976D01*
X1222172Y482860D01*
X1224498D01*
X1225482Y483844D01*
Y484716D01*
X1224776Y485422D01*
Y487162D01*
X1226384Y488770D01*
X1228124D01*
X1228830Y488064D01*
X1229692D01*
X1231894Y490266D01*
Y493415D01*
X1231274Y494035D01*
Y495035D01*
X1231894Y495655D01*
Y496655D01*
X1231274Y497275D01*
Y498275D01*
X1231894Y498895D01*
Y499895D01*
X1231274Y500515D01*
Y501515D01*
X1231894Y502135D01*
Y503135D01*
X1231274Y503755D01*
Y504755D01*
X1231894Y505375D01*
Y506375D01*
X1231274Y506995D01*
Y507995D01*
X1231894Y508615D01*
Y510432D01*
X1231341Y510985D01*
Y511985D01*
X1231894Y512538D01*
Y519067D01*
X1231274Y519687D01*
Y520687D01*
X1231894Y521307D01*
Y522307D01*
X1231274Y522927D01*
Y523927D01*
X1231894Y524547D01*
Y525547D01*
X1231274Y526167D01*
Y527167D01*
X1231894Y527787D01*
Y529287D01*
X1231420Y529761D01*
Y530761D01*
X1231894Y531235D01*
Y534458D01*
X1231460Y534892D01*
Y535892D01*
X1231894Y536326D01*
Y537841D01*
X1231274Y538461D01*
Y539461D01*
X1231894Y540081D01*
Y541081D01*
X1231274Y541701D01*
Y542701D01*
X1231894Y543321D01*
Y544321D01*
X1231274Y544941D01*
Y545941D01*
X1231894Y546561D01*
Y549794D01*
X1230974Y550714D01*
X1229874D01*
G01X1140815Y422445D02*
X1144170Y425800D01*
X1157830D01*
X1226794Y494764D01*
Y538398D01*
X1226333Y538859D01*
Y539859D01*
X1226794Y540320D01*
Y541479D01*
X1226174Y542099D01*
Y543099D01*
X1226794Y543719D01*
Y544719D01*
X1226174Y545339D01*
Y546339D01*
X1226794Y546959D01*
Y549580D01*
X1225874Y550500D01*
X1224774D01*
G01X1149787Y421345D02*
X1159542D01*
X1211775Y473578D01*
X1216706D01*
X1221348Y478220D01*
Y480536D01*
X1222612Y481800D01*
X1224938D01*
X1226542Y483404D01*
Y485156D01*
X1225836Y485862D01*
Y486722D01*
X1226824Y487710D01*
X1227684D01*
X1228390Y487004D01*
X1230132D01*
X1232954Y489826D01*
Y550234D01*
X1229874Y553314D01*
G01X1103850Y422014D02*
Y446053D01*
X1113209Y455412D01*
Y459391D01*
X1137473Y483655D01*
X1138854D01*
X1144800Y489601D01*
Y493900D01*
X1146574Y495674D01*
Y499610D01*
X1148000Y501036D01*
Y507300D01*
X1146574Y508726D01*
Y510885D01*
X1145402Y512057D01*
Y516307D01*
X1146752Y517657D01*
Y519300D01*
X1146100Y519952D01*
Y527600D01*
X1146752Y528252D01*
Y529248D01*
X1145402Y530598D01*
Y535202D01*
X1146752Y536552D01*
Y537700D01*
X1145700Y538752D01*
Y545300D01*
X1146752Y546352D01*
Y548507D01*
X1145402Y549857D01*
Y554107D01*
X1146600Y555305D01*
Y557252D01*
X1146400Y557452D01*
Y565800D01*
X1146552Y565952D01*
Y567247D01*
X1145452Y568347D01*
Y573053D01*
X1146602Y574203D01*
Y586457D01*
X1144685Y588374D01*
Y593757D01*
G01X1106240Y422124D02*
Y445475D01*
X1116843Y456078D01*
Y456940D01*
X1115849Y457934D01*
Y458796D01*
X1116833Y459780D01*
X1117695D01*
X1118689Y458786D01*
X1119551D01*
X1120535Y459770D01*
Y460632D01*
X1119541Y461626D01*
Y462488D01*
X1120525Y463472D01*
X1121387D01*
X1122381Y462478D01*
X1123243D01*
X1124227Y463462D01*
Y464324D01*
X1123233Y465318D01*
Y466180D01*
X1124217Y467164D01*
X1125079D01*
X1126073Y466170D01*
X1126935D01*
X1127919Y467154D01*
Y468016D01*
X1126925Y469010D01*
Y469872D01*
X1127909Y470856D01*
X1128771D01*
X1129765Y469862D01*
X1130627D01*
X1131611Y470846D01*
Y471708D01*
X1130617Y472702D01*
Y473564D01*
X1138693Y481640D01*
X1142087D01*
X1149100Y488653D01*
Y499700D01*
X1150552Y501152D01*
Y508048D01*
X1149274Y509326D01*
Y518874D01*
X1149700Y519300D01*
Y527600D01*
X1149274Y528026D01*
Y537900D01*
X1149700Y538326D01*
Y540400D01*
X1148400Y541700D01*
Y543500D01*
X1149700Y544800D01*
Y546500D01*
X1149274Y546926D01*
Y556774D01*
X1149700Y557200D01*
Y559000D01*
X1148900Y559800D01*
Y562200D01*
X1149700Y563000D01*
Y565700D01*
X1149274Y566126D01*
Y586771D01*
X1147331Y588714D01*
G01X1121340Y422124D02*
Y442384D01*
X1144261Y465305D01*
X1150625D01*
X1165158Y479838D01*
Y484690D01*
X1168700Y488232D01*
Y494600D01*
X1169300Y495200D01*
Y497078D01*
X1170052Y497830D01*
Y511157D01*
X1169552Y511657D01*
Y517057D01*
X1170300Y517805D01*
Y519202D01*
X1169800Y519702D01*
Y527800D01*
X1170402Y528402D01*
Y529288D01*
X1169452Y530238D01*
Y535952D01*
X1170052Y536552D01*
Y537700D01*
X1169800Y537952D01*
Y546400D01*
X1170052Y546652D01*
Y548957D01*
X1169552Y549457D01*
Y554857D01*
X1170352Y555657D01*
Y557000D01*
X1169785Y557567D01*
Y565485D01*
X1170352Y566052D01*
Y567297D01*
X1169252Y568397D01*
Y573142D01*
X1170152Y574042D01*
Y586507D01*
X1168110Y588549D01*
Y593757D01*
G01X1123840Y422124D02*
X1123900Y422184D01*
Y441708D01*
X1145189Y462997D01*
X1151445D01*
X1163667Y475219D01*
X1164529D01*
X1165104Y474644D01*
X1165812D01*
X1166950Y475782D01*
Y476490D01*
X1166375Y477065D01*
Y477927D01*
X1169182Y480734D01*
Y481596D01*
X1168204Y482574D01*
Y483282D01*
X1169342Y484420D01*
X1170050D01*
X1170855Y483615D01*
X1171784D01*
X1173006Y484837D01*
Y491494D01*
X1172400Y492100D01*
Y502848D01*
X1172852Y503300D01*
Y511657D01*
X1173452Y512257D01*
Y516807D01*
X1172902Y517357D01*
Y519400D01*
X1173100Y519598D01*
Y527800D01*
X1172902Y527998D01*
Y529608D01*
X1173552Y530258D01*
Y535448D01*
X1172852Y536148D01*
Y537500D01*
X1173100Y537748D01*
Y546700D01*
X1172852Y546948D01*
Y549457D01*
G01X1172400Y555659D02*
Y567145D01*
X1173752Y568497D01*
Y573248D01*
X1172752Y574248D01*
Y587470D01*
X1171456Y588766D01*
Y588714D01*
G01X1098740Y422124D02*
Y450631D01*
X1136561Y488452D01*
X1137974D01*
X1139174Y489652D01*
Y494674D01*
X1139952Y495452D01*
Y500000D01*
X1139100Y500852D01*
Y502398D01*
X1139900Y503198D01*
X1140600D01*
X1141400Y503998D01*
Y505598D01*
X1140600Y506398D01*
X1139900D01*
X1139100Y507198D01*
Y508600D01*
X1139952Y509452D01*
Y510897D01*
X1139052Y511797D01*
Y516353D01*
X1140300Y517601D01*
Y519452D01*
X1139700Y520052D01*
Y527800D01*
X1139952Y528052D01*
Y529448D01*
X1139052Y530348D01*
Y535242D01*
X1140052Y536242D01*
Y537700D01*
X1139700Y538052D01*
Y546900D01*
X1140052Y547252D01*
Y548557D01*
X1139052Y549557D01*
Y554257D01*
X1140300Y555505D01*
Y557200D01*
X1139700Y557800D01*
Y565700D01*
X1139952Y565952D01*
Y567249D01*
X1138300Y568901D01*
Y572340D01*
X1140115Y574155D01*
Y575287D01*
X1135833Y579569D01*
Y586929D01*
X1137992Y589088D01*
Y593757D01*
G01X1101240Y422124D02*
Y450179D01*
X1103558Y452497D01*
X1104420D01*
X1105412Y451505D01*
X1106275D01*
X1107259Y452489D01*
Y453351D01*
X1106266Y454344D01*
Y455205D01*
X1107250Y456189D01*
X1108112D01*
X1109104Y455197D01*
X1109967D01*
X1110951Y456181D01*
Y457043D01*
X1109958Y458036D01*
Y458897D01*
X1137013Y485952D01*
X1138452D01*
X1142800Y490300D01*
Y494500D01*
X1142200Y495100D01*
Y499026D01*
X1145600Y502426D01*
Y505800D01*
X1142674Y508726D01*
Y511724D01*
X1143300Y512350D01*
Y516101D01*
X1142100Y517301D01*
Y519200D01*
X1143000Y520100D01*
Y527652D01*
X1142300Y528352D01*
Y529700D01*
X1143000Y530400D01*
Y535600D01*
X1142392Y536208D01*
Y537340D01*
X1143000Y537948D01*
Y546200D01*
X1142214Y546986D01*
Y548915D01*
X1143400Y550101D01*
Y554509D01*
X1142400Y555509D01*
Y556948D01*
X1143000Y557548D01*
Y565700D01*
X1142652Y566048D01*
Y567997D01*
X1143152Y568497D01*
Y572656D01*
X1142552Y573256D01*
Y575400D01*
X1143000Y575848D01*
Y578954D01*
X1142390Y579564D01*
X1139572D01*
X1138962Y580174D01*
Y582154D01*
X1139572Y582764D01*
X1142390D01*
X1143000Y583374D01*
Y584600D01*
X1141038Y586562D01*
Y588714D01*
G01X1116340Y422124D02*
Y443164D01*
X1150945Y477769D01*
X1157149D01*
X1161101Y481721D01*
Y487395D01*
X1161600Y487894D01*
Y493700D01*
X1163100Y495200D01*
Y504500D01*
X1163652Y505052D01*
Y511257D01*
X1162852Y512057D01*
Y516957D01*
X1163252Y517357D01*
Y519400D01*
X1163100Y519552D01*
Y527800D01*
X1163252Y527952D01*
Y529650D01*
X1162852Y530050D01*
Y535752D01*
X1163652Y536552D01*
Y537500D01*
X1163085Y538067D01*
Y546985D01*
X1163652Y547552D01*
Y549057D01*
X1162852Y549857D01*
Y554757D01*
X1163452Y555357D01*
Y557000D01*
X1163100Y557352D01*
Y565600D01*
X1163452Y565952D01*
Y567397D01*
X1162379Y568470D01*
Y572969D01*
X1163652Y574242D01*
Y586357D01*
X1161417Y588592D01*
Y593757D01*
G01X1109961Y422387D02*
Y444316D01*
X1154232Y488587D01*
Y587820D01*
X1151152Y590900D01*
G01X1112601Y423137D02*
Y443843D01*
X1151510Y482752D01*
X1153971D01*
X1155392Y481331D01*
X1156443D01*
X1157703Y482591D01*
Y483296D01*
X1155542Y485457D01*
Y487242D01*
X1158272Y489972D01*
Y518908D01*
X1157652Y519528D01*
Y520528D01*
X1158272Y521148D01*
Y522148D01*
X1157652Y522768D01*
Y523768D01*
X1158272Y524388D01*
Y525388D01*
X1157652Y526008D01*
Y527008D01*
X1158272Y527628D01*
Y537842D01*
X1157652Y538462D01*
Y539462D01*
X1158272Y540082D01*
Y541082D01*
X1157652Y541702D01*
Y542702D01*
X1158272Y543322D01*
Y544322D01*
X1157652Y544942D01*
Y545942D01*
X1158272Y546562D01*
Y551124D01*
X1157904Y551492D01*
Y552492D01*
X1158272Y552860D01*
Y556881D01*
X1157652Y557501D01*
Y558501D01*
X1158272Y559121D01*
Y560121D01*
X1157652Y560741D01*
Y561741D01*
X1158272Y562361D01*
Y563361D01*
X1157652Y563981D01*
Y564981D01*
X1158272Y565601D01*
Y575921D01*
X1157652Y576541D01*
Y577541D01*
X1158272Y578161D01*
Y579161D01*
X1157652Y579781D01*
Y580781D01*
X1158272Y581401D01*
Y582401D01*
X1157652Y583021D01*
Y584021D01*
X1158272Y584641D01*
Y587594D01*
X1157352Y588514D01*
X1156252D01*
G01X1108901Y422387D02*
Y444756D01*
X1153172Y489027D01*
Y575949D01*
X1152817Y576304D01*
Y577304D01*
X1153172Y577659D01*
Y579070D01*
X1152725Y579517D01*
Y580517D01*
X1153172Y580964D01*
Y582137D01*
X1152552Y582757D01*
Y583757D01*
X1153172Y584377D01*
Y587380D01*
X1152252Y588300D01*
X1151152D01*
G01X1113661Y423137D02*
Y443403D01*
X1151950Y481692D01*
X1153531D01*
X1154952Y480271D01*
X1156883D01*
X1158763Y482151D01*
Y483736D01*
X1156602Y485897D01*
Y486802D01*
X1159332Y489532D01*
Y588034D01*
X1156252Y591114D01*
G01X1118840Y422124D02*
Y442694D01*
X1144211Y468065D01*
X1145073D01*
X1145931Y467207D01*
X1146639D01*
X1147777Y468345D01*
Y469053D01*
X1146919Y469911D01*
Y470773D01*
X1147903Y471757D01*
X1148765D01*
X1150817Y469705D01*
X1151525D01*
X1152663Y470843D01*
Y471551D01*
X1150611Y473603D01*
Y474465D01*
X1151740Y475594D01*
X1157838D01*
X1163169Y480925D01*
Y486308D01*
X1166152Y489291D01*
Y494348D01*
X1165300Y495200D01*
Y503500D01*
X1166152Y504352D01*
Y511257D01*
X1167052Y512157D01*
Y516557D01*
X1166252Y517357D01*
Y519200D01*
X1166400Y519348D01*
Y527800D01*
X1166252Y527948D01*
Y529650D01*
X1166952Y530350D01*
Y535548D01*
X1166152Y536348D01*
Y537752D01*
X1166500Y538100D01*
Y545900D01*
X1166152Y546248D01*
Y549057D01*
X1167052Y549957D01*
Y554357D01*
X1165952Y555457D01*
Y557151D01*
X1166500Y557699D01*
Y565300D01*
X1166252Y565548D01*
Y567597D01*
X1166818Y568163D01*
Y573481D01*
X1166152Y574147D01*
Y587368D01*
X1166109D01*
X1164763Y588714D01*
G01X1107874Y555957D02*
X1106169Y557662D01*
Y569315D01*
X1109354Y572500D01*
X1110520D01*
G01Y550914D02*
X1110432D01*
X1108746Y552600D01*
Y554292D01*
X1109653Y555199D01*
Y556792D01*
X1108509Y557936D01*
Y559356D01*
X1109353Y560200D01*
Y561900D01*
X1108509Y562744D01*
Y563956D01*
X1109453Y564900D01*
Y566100D01*
X1108854Y566699D01*
X1107874D01*
G01X1131299Y555957D02*
X1129594Y557662D01*
Y567849D01*
X1134645Y572900D01*
G01Y550914D02*
X1134557D01*
X1132871Y552600D01*
Y554292D01*
X1133046Y554467D01*
Y557100D01*
X1131934Y558212D01*
Y559288D01*
X1132946Y560300D01*
Y561500D01*
X1131934Y562512D01*
Y563588D01*
X1133071Y564725D01*
Y565999D01*
X1132371Y566699D01*
X1131299D01*
G01X1101181Y555957D02*
X1099476Y557662D01*
Y567635D01*
X1100098Y568257D01*
Y569445D01*
X1103153Y572500D01*
X1104141D01*
G01X1104227Y550914D02*
X1104139D01*
X1102453Y552600D01*
Y554800D01*
X1102953Y555300D01*
Y557199D01*
X1101816Y558336D01*
Y559664D01*
X1102753Y560601D01*
Y561999D01*
X1101816Y562936D01*
Y564164D01*
X1102853Y565201D01*
Y566099D01*
X1102253Y566699D01*
X1101181D01*
G01X1124606Y555957D02*
X1122901Y557662D01*
Y567849D01*
X1127952Y572900D01*
G01Y550914D02*
X1127864D01*
X1126178Y552600D01*
Y554292D01*
X1126353Y554467D01*
Y557100D01*
X1125241Y558212D01*
Y559288D01*
X1126253Y560300D01*
Y561500D01*
X1125241Y562512D01*
Y563588D01*
X1126378Y564725D01*
Y565999D01*
X1125678Y566699D01*
X1124606D01*
G01X1114366Y569550D02*
X1114367D01*
X1116072Y567845D01*
Y565939D01*
X1115333Y565200D01*
X1114053D01*
X1113413Y564560D01*
Y563140D01*
X1113963Y562590D01*
X1114543D01*
X1115175Y561958D01*
Y560612D01*
X1114543Y559980D01*
X1113933D01*
X1113413Y559460D01*
Y558090D01*
X1114003Y557500D01*
X1114953D01*
X1116053Y556400D01*
Y554812D01*
X1114341Y553100D01*
G01D02*
X1114340D01*
G01X1119440Y550714D02*
X1119153D01*
X1117735Y552132D01*
Y557101D01*
X1116906Y557930D01*
Y564470D01*
X1117735Y565299D01*
Y570244D01*
X1119440Y571949D01*
G01X1114340Y550500D02*
X1114053D01*
X1112353Y552200D01*
Y570212D01*
X1114340Y572199D01*
G01X1119440Y569340D02*
X1119441D01*
X1121253Y567528D01*
Y565800D01*
X1120253Y564800D01*
X1118737D01*
X1117966Y564029D01*
Y563138D01*
X1118506Y562598D01*
X1118743D01*
X1119453Y561888D01*
Y560800D01*
X1118753Y560100D01*
X1118418D01*
X1117966Y559648D01*
Y558371D01*
X1118637Y557700D01*
X1120153D01*
X1121153Y556700D01*
Y555026D01*
X1119441Y553314D01*
G01D02*
X1119440D01*
G01X1181496Y27899D02*
Y30021D01*
X1183375Y31900D01*
X1184775D01*
X1186231Y33356D01*
Y34700D01*
X1185615Y35316D01*
Y48441D01*
X1184142Y49914D01*
G01X1208267D02*
X1209656Y48525D01*
Y35512D01*
X1210268Y34900D01*
Y33500D01*
X1208468Y31700D01*
X1207468D01*
X1206168Y30400D01*
Y29146D01*
X1204921Y27899D01*
G01X1174803D02*
X1175800Y28896D01*
Y30450D01*
X1177050Y31700D01*
X1178274D01*
X1179850Y33276D01*
Y34900D01*
X1179075Y35675D01*
Y48688D01*
X1177849Y49914D01*
G01X1201574D02*
X1202963Y48525D01*
Y35512D01*
X1203575Y34900D01*
Y33500D01*
X1201775Y31700D01*
X1200775D01*
X1199475Y30400D01*
Y29146D01*
X1198228Y27899D01*
G01X1220953Y49914D02*
X1222426Y48441D01*
Y35316D01*
X1223042Y34700D01*
Y33356D01*
X1221586Y31900D01*
X1220186D01*
X1218307Y30021D01*
Y27899D01*
G01X1214660Y49914D02*
X1215886Y48688D01*
Y35675D01*
X1216661Y34900D01*
Y33276D01*
X1215085Y31700D01*
X1213861D01*
X1211614Y29453D01*
Y27899D01*
G01X1187963Y52100D02*
X1191069Y48994D01*
Y32851D01*
X1189738Y31520D01*
X1188759D01*
X1187989Y30750D01*
G01X1187963Y33399D02*
X1188782Y32580D01*
X1189298D01*
X1190009Y33291D01*
Y36580D01*
X1188089Y38500D01*
Y39500D01*
X1188689Y40100D01*
X1189189D01*
X1190009Y40920D01*
Y41880D01*
X1189289Y42600D01*
X1188577D01*
X1188075Y43102D01*
Y44434D01*
X1188691Y45050D01*
X1189039D01*
X1190009Y46020D01*
Y48553D01*
X1189062Y49500D01*
X1187963D01*
G01X1193063Y30540D02*
X1196255Y33732D01*
Y49122D01*
X1193063Y52314D01*
G01X1181496Y112357D02*
Y106733D01*
X1183305Y104924D01*
Y92104D01*
X1182300Y91099D01*
Y86479D01*
X1183474Y85305D01*
Y73374D01*
X1182174Y72074D01*
Y67433D01*
X1183405Y66202D01*
Y63266D01*
X1181496Y61357D01*
Y54957D01*
G01D02*
X1180375Y53836D01*
Y50900D01*
X1183275Y48000D01*
Y46032D01*
X1181742Y44499D01*
Y43300D01*
X1182992Y42050D01*
Y41150D01*
X1181642Y39800D01*
Y38501D01*
X1183275Y36868D01*
Y34567D01*
X1184142Y33700D01*
G01Y49914D02*
X1182400Y51656D01*
Y53400D01*
X1183924Y54924D01*
Y61135D01*
X1186055Y63266D01*
Y105051D01*
X1184142Y106964D01*
G01X1208267Y34100D02*
X1206700Y35667D01*
Y36868D01*
X1205342Y38226D01*
Y39599D01*
X1206542Y40799D01*
Y41925D01*
X1205342Y43125D01*
Y44700D01*
X1207142Y46500D01*
Y47558D01*
X1203800Y50900D01*
Y53836D01*
X1204921Y54957D01*
G01D02*
Y63152D01*
X1206721Y64952D01*
Y66511D01*
X1206205Y67027D01*
Y72405D01*
X1207005Y73205D01*
Y85774D01*
X1206274Y86505D01*
Y91275D01*
X1206905Y91906D01*
Y104954D01*
X1206274Y105585D01*
Y109374D01*
X1204921Y110727D01*
Y112357D01*
G01X1208267Y107314D02*
X1209505Y106076D01*
Y92042D01*
X1210205Y91342D01*
Y86494D01*
X1209505Y85794D01*
Y73095D01*
X1210205Y72395D01*
Y66979D01*
X1209814Y66588D01*
Y63715D01*
X1207914Y61815D01*
Y54985D01*
X1206121Y53192D01*
Y52060D01*
X1208267Y49914D01*
G01X1174742Y112357D02*
X1174803D01*
X1175874Y111286D01*
Y105905D01*
X1176705Y105074D01*
Y92006D01*
X1175855Y91156D01*
Y86424D01*
X1175990Y86290D01*
X1176705Y85574D01*
Y72959D01*
X1175855Y72109D01*
Y67145D01*
X1176705Y66295D01*
Y58805D01*
X1174803Y56903D01*
Y54957D01*
G01D02*
X1175900Y53860D01*
Y48876D01*
X1176675Y48101D01*
Y45876D01*
X1175292Y44493D01*
Y43008D01*
X1175629Y42671D01*
X1176329D01*
X1176742Y42258D01*
Y40542D01*
X1176179Y39979D01*
X1175579D01*
X1175242Y39642D01*
Y38557D01*
X1176675Y37124D01*
Y34788D01*
X1177763Y33700D01*
G01X1177849Y49914D02*
Y56249D01*
X1178900Y57300D01*
Y66100D01*
X1179705Y66905D01*
Y72659D01*
X1179405Y72959D01*
Y86074D01*
X1179805Y86474D01*
Y91174D01*
X1179505Y91474D01*
Y105658D01*
X1177849Y107314D01*
G01X1201574Y34100D02*
X1200100Y35574D01*
Y36668D01*
X1198667Y38101D01*
Y39324D01*
X1200167Y40824D01*
Y42176D01*
X1198667Y43676D01*
Y44799D01*
X1200342Y46474D01*
Y47859D01*
X1197300Y50901D01*
Y54029D01*
X1198228Y54957D01*
G01D02*
X1200205Y56934D01*
Y66339D01*
X1199405Y67139D01*
Y72505D01*
X1200174Y73274D01*
Y86005D01*
X1199405Y86774D01*
Y91074D01*
X1200505Y92174D01*
Y104775D01*
X1199285Y105995D01*
Y109064D01*
X1199024Y109324D01*
X1198228Y110121D01*
Y112357D01*
G01X1201574Y107314D02*
X1203005Y105883D01*
Y91712D01*
X1203705Y91012D01*
Y86674D01*
X1202874Y85843D01*
Y73126D01*
X1203605Y72395D01*
Y66991D01*
X1202405Y65791D01*
Y56176D01*
X1199774Y53545D01*
Y51714D01*
X1201574Y49914D01*
G01X1218307Y54957D02*
X1217186Y53836D01*
Y50900D01*
X1220086Y48000D01*
Y46032D01*
X1218553Y44499D01*
Y43300D01*
X1219803Y42050D01*
Y41150D01*
X1218453Y39800D01*
Y38501D01*
X1220086Y36868D01*
Y34567D01*
X1220953Y33700D01*
G01X1211614Y54957D02*
X1210686Y54029D01*
Y50901D01*
X1213486Y48101D01*
Y46232D01*
X1212103Y44849D01*
Y43450D01*
X1213553Y42000D01*
Y40800D01*
X1212053Y39300D01*
Y38101D01*
X1213486Y36668D01*
Y34788D01*
X1214574Y33700D01*
G01X1187963Y110514D02*
X1190980Y107497D01*
Y61747D01*
X1188980Y59747D01*
Y56781D01*
X1189689Y56072D01*
Y53826D01*
X1187963Y52100D01*
G01X1193063Y33149D02*
X1194172D01*
X1195195Y34172D01*
Y36793D01*
X1194488Y37500D01*
X1193690D01*
X1193089Y38101D01*
Y39299D01*
X1193690Y39900D01*
X1194388D01*
X1195195Y40707D01*
Y42080D01*
X1194475Y42800D01*
X1193975D01*
X1193275Y43500D01*
Y44500D01*
X1193975Y45200D01*
X1194489D01*
X1195195Y45906D01*
Y48681D01*
X1194161Y49715D01*
X1193063D01*
Y49714D01*
G01D02*
X1191339Y51438D01*
Y55739D01*
X1193120Y57520D01*
Y58192D01*
X1195020Y60092D01*
Y105698D01*
X1193063Y107655D01*
G01X1187963Y49500D02*
X1185989Y51474D01*
Y55389D01*
X1187920Y57320D01*
Y60190D01*
X1189920Y62190D01*
Y105934D01*
X1187989Y107865D01*
G01X1193063Y52314D02*
X1194889Y54140D01*
Y55911D01*
X1194180Y56620D01*
Y57749D01*
X1196080Y59649D01*
Y107247D01*
X1193089Y110238D01*
Y110264D01*
G01X1180400Y498387D02*
X1181496Y499483D01*
Y506610D01*
X1183563Y508677D01*
Y510707D01*
X1182213Y512057D01*
Y516307D01*
X1183363Y517457D01*
Y519600D01*
X1183200Y519763D01*
Y527600D01*
X1183363Y527763D01*
Y529467D01*
X1182263Y530567D01*
Y535263D01*
X1183413Y536413D01*
Y537900D01*
X1183200Y538113D01*
Y547100D01*
X1183413Y547313D01*
Y548657D01*
X1180063Y552007D01*
Y554524D01*
X1181496Y555957D01*
G01X1184142Y493394D02*
X1183374Y494162D01*
Y504952D01*
X1186063Y507641D01*
Y518964D01*
X1186500Y519401D01*
Y528100D01*
X1186063Y528537D01*
Y537700D01*
X1186500Y538137D01*
Y546400D01*
X1186063Y546837D01*
Y548643D01*
X1184142Y550564D01*
Y550914D01*
G01X1204921Y555957D02*
X1203563Y554599D01*
Y552107D01*
X1206963Y548707D01*
Y546663D01*
X1206600Y546300D01*
Y537999D01*
X1206963Y537636D01*
Y536242D01*
X1206063Y535342D01*
Y530597D01*
X1207163Y529497D01*
Y528263D01*
X1206597Y527697D01*
Y520066D01*
X1207163Y519500D01*
Y517857D01*
X1206363Y517057D01*
Y511657D01*
X1206863Y511157D01*
Y500829D01*
X1204521Y498487D01*
X1204400D01*
G01X1208267Y496144D02*
X1209663Y497540D01*
Y511657D01*
X1210263Y512257D01*
Y516807D01*
X1209713Y517357D01*
Y519800D01*
X1210000Y520087D01*
Y527600D01*
X1209713Y527887D01*
Y529847D01*
X1210563Y530697D01*
Y535338D01*
X1209563Y536338D01*
Y537600D01*
X1209900Y537937D01*
Y545900D01*
X1209563Y546237D01*
Y549670D01*
X1208267Y550966D01*
Y550914D01*
G01X1176713Y548657D02*
Y547413D01*
X1176500Y547200D01*
Y538013D01*
X1176713Y537800D01*
Y536142D01*
X1175715Y535144D01*
Y530485D01*
X1176763Y529437D01*
Y528063D01*
X1176500Y527800D01*
Y519763D01*
X1176763Y519500D01*
Y517407D01*
X1175863Y516507D01*
Y511757D01*
X1176863Y510757D01*
Y508241D01*
X1174600Y505978D01*
Y498784D01*
X1174203Y498387D01*
G01X1177799Y493544D02*
Y504476D01*
X1179363Y506040D01*
Y511441D01*
X1179713Y511791D01*
Y517207D01*
X1179463Y517457D01*
Y519200D01*
X1179800Y519537D01*
Y527600D01*
X1179463Y527937D01*
Y530197D01*
X1179963Y530697D01*
Y534856D01*
X1179363Y535456D01*
Y537500D01*
X1179800Y537937D01*
Y546400D01*
X1179363Y546837D01*
Y549400D01*
X1177849Y550914D01*
G01X1198228Y555957D02*
X1197563Y555292D01*
Y551457D01*
X1200463Y548557D01*
Y547163D01*
X1199900Y546600D01*
Y538263D01*
X1200200Y537963D01*
Y536179D01*
X1199190Y535169D01*
Y530670D01*
X1200263Y529597D01*
Y528063D01*
X1199900Y527700D01*
Y519863D01*
X1200263Y519500D01*
Y517557D01*
X1199663Y516957D01*
Y512057D01*
X1200463Y511257D01*
Y504841D01*
X1198228Y502606D01*
Y498528D01*
X1198100Y498400D01*
G01X1200974Y493344D02*
Y499652D01*
X1202963Y501641D01*
Y511257D01*
X1203863Y512157D01*
Y516557D01*
X1203063Y517357D01*
Y519400D01*
X1203200Y519537D01*
Y527900D01*
X1203063Y528037D01*
Y529797D01*
X1203629Y530363D01*
Y535571D01*
X1202963Y536237D01*
Y537800D01*
X1203300Y538137D01*
Y546500D01*
X1202963Y546837D01*
Y549568D01*
X1202920D01*
X1201574Y550914D01*
G01X1187963Y553100D02*
X1188107D01*
X1189963Y551244D01*
Y550612D01*
X1191043Y549532D01*
Y506089D01*
X1188800Y503846D01*
Y500600D01*
X1189700Y499700D01*
Y497631D01*
X1187978Y495909D01*
G01X1193063Y550714D02*
X1195083Y548694D01*
Y545407D01*
X1193516Y543840D01*
Y540357D01*
X1195083Y538790D01*
Y526425D01*
X1193719Y525061D01*
Y520849D01*
X1195083Y519485D01*
Y503383D01*
X1191300Y499600D01*
Y495272D01*
X1193063Y493509D01*
G01X1187963Y550500D02*
X1188157D01*
X1189983Y548674D01*
Y506529D01*
X1187740Y504286D01*
Y501040D01*
X1186098Y499398D01*
Y495089D01*
X1187978Y493209D01*
G01X1193063Y553314D02*
X1196143Y550234D01*
Y544967D01*
X1194576Y543400D01*
Y540797D01*
X1196143Y539230D01*
Y525985D01*
X1194779Y524621D01*
Y521289D01*
X1196143Y519925D01*
Y502943D01*
X1194800Y501600D01*
Y497946D01*
X1193063Y496209D01*
G01X1218307Y555957D02*
X1216602Y557662D01*
Y569315D01*
X1219787Y572500D01*
X1220953D01*
G01Y550914D02*
X1220865D01*
X1219179Y552600D01*
Y554292D01*
X1220086Y555199D01*
Y556792D01*
X1218942Y557936D01*
Y559356D01*
X1219786Y560200D01*
Y561900D01*
X1218942Y562744D01*
Y563956D01*
X1219886Y564900D01*
Y566100D01*
X1219287Y566699D01*
X1218307D01*
G01X1211614Y555957D02*
X1209909Y557662D01*
Y567635D01*
X1210531Y568257D01*
Y569445D01*
X1213586Y572500D01*
X1214574D01*
G01X1214874Y550574D02*
Y550612D01*
X1212886Y552600D01*
Y554800D01*
X1213386Y555300D01*
Y557199D01*
X1212249Y558336D01*
Y559664D01*
X1213186Y560601D01*
Y561999D01*
X1212249Y562936D01*
Y564164D01*
X1213286Y565201D01*
Y566099D01*
X1212686Y566699D01*
X1211614D01*
G01X1245078Y49914D02*
X1246467Y48525D01*
Y35512D01*
X1247079Y34900D01*
Y33500D01*
X1245279Y31700D01*
X1244279D01*
X1242979Y30400D01*
Y29146D01*
X1241732Y27899D01*
G01X1238385Y49914D02*
X1239774Y48525D01*
Y35512D01*
X1240386Y34900D01*
Y33500D01*
X1238586Y31700D01*
X1237586D01*
X1236286Y30400D01*
Y29146D01*
X1235039Y27899D01*
G01X1224774Y52100D02*
X1227880Y48994D01*
Y32848D01*
X1226552Y31520D01*
X1225570D01*
X1224800Y30750D01*
G01X1229874Y52314D02*
X1233066Y49122D01*
Y33732D01*
X1229874Y30540D01*
G01X1224774Y49500D02*
X1225873D01*
X1226820Y48553D01*
Y46020D01*
X1225850Y45050D01*
X1225502D01*
X1224886Y44434D01*
Y43102D01*
X1225388Y42600D01*
X1226100D01*
X1226820Y41880D01*
Y40920D01*
X1226000Y40100D01*
X1225500D01*
X1224900Y39500D01*
Y38500D01*
X1226820Y36580D01*
Y33291D01*
X1226109Y32580D01*
X1225593D01*
X1224774Y33399D01*
G01X1245078Y34100D02*
X1243511Y35667D01*
Y36868D01*
X1242153Y38226D01*
Y39599D01*
X1243353Y40799D01*
Y41925D01*
X1242153Y43125D01*
Y44700D01*
X1243953Y46500D01*
Y47558D01*
X1240611Y50900D01*
Y53836D01*
X1241732Y54957D01*
G01X1235039D02*
X1234111Y54029D01*
Y50901D01*
X1237153Y47859D01*
Y46474D01*
X1235478Y44799D01*
Y43676D01*
X1236978Y42176D01*
Y40824D01*
X1235478Y39324D01*
Y38101D01*
X1236911Y36668D01*
Y35574D01*
X1238385Y34100D01*
G01X1229874Y49714D02*
Y49715D01*
X1230972D01*
X1232006Y48681D01*
Y45906D01*
X1231300Y45200D01*
X1230786D01*
X1230086Y44500D01*
Y43500D01*
X1230786Y42800D01*
X1231286D01*
X1232006Y42080D01*
Y40707D01*
X1231199Y39900D01*
X1230501D01*
X1229900Y39299D01*
Y38101D01*
X1230501Y37500D01*
X1231299D01*
X1232006Y36793D01*
Y34172D01*
X1230983Y33149D01*
X1229874D01*
G01X1241732Y555957D02*
X1240027Y557662D01*
Y567849D01*
X1245078Y572900D01*
G01X1241732Y566699D02*
X1242804D01*
X1243504Y565999D01*
Y564725D01*
X1242367Y563588D01*
Y562512D01*
X1243379Y561500D01*
Y560300D01*
X1242367Y559288D01*
Y558212D01*
X1243479Y557100D01*
Y554467D01*
X1243304Y554292D01*
Y552688D01*
X1245078Y550914D01*
G01X1235039Y555957D02*
X1233334Y557662D01*
Y567849D01*
X1238385Y572900D01*
G01Y550914D02*
X1238297D01*
X1236611Y552600D01*
Y554292D01*
X1236786Y554467D01*
Y557100D01*
X1235674Y558212D01*
Y559288D01*
X1236686Y560300D01*
Y561500D01*
X1235674Y562512D01*
Y563588D01*
X1236811Y564725D01*
Y565999D01*
X1236111Y566699D01*
X1235039D01*
G01X1224774Y553100D02*
X1226486Y554812D01*
Y556400D01*
X1225386Y557500D01*
X1224436D01*
X1223846Y558090D01*
Y559460D01*
X1224366Y559980D01*
X1224976D01*
X1225586Y560590D01*
Y561980D01*
X1224976Y562590D01*
X1224396D01*
X1223846Y563140D01*
Y564560D01*
X1224486Y565200D01*
X1225766D01*
X1226505Y565939D01*
Y567845D01*
X1224800Y569550D01*
G01X1229874Y550714D02*
X1229586D01*
X1228168Y552132D01*
Y557101D01*
X1227339Y557930D01*
Y564470D01*
X1228168Y565299D01*
Y570243D01*
X1229874Y571949D01*
G01X1224774Y550500D02*
X1224486D01*
X1222786Y552200D01*
Y570211D01*
X1224774Y572199D01*
G01X1229874Y553314D02*
X1231586Y555026D01*
Y556700D01*
X1230586Y557700D01*
X1229070D01*
X1228399Y558371D01*
Y559648D01*
X1228851Y560100D01*
X1229186D01*
X1229886Y560800D01*
Y561888D01*
X1229176Y562598D01*
X1228939D01*
X1228399Y563138D01*
Y564029D01*
X1229170Y564800D01*
X1230686D01*
X1231686Y565800D01*
Y567528D01*
X1229874Y569340D01*
M02*
